G04 ================== begin FILE IDENTIFICATION RECORD ==================*
G04 Layout Name:  15669-1.brd*
G04 Film Name:    15669-1_X_Y*
G04 File Format:  Gerber RS274X*
G04 File Origin:  Cadence Allegro 16.5-S056*
G04 Origin Date:  Wed Nov 16 10:04:02 2016*
G04 *
G04 Layer:  BOARD GEOMETRY/PANEL_DRAWING*
G04 *
G04 Offset:    (0.00 0.00)*
G04 Mirror:    No*
G04 Mode:      Positive*
G04 Rotation:  0*
G04 FullContactRelief:  No*
G04 UndefLineWidth:     6.00*
G04 ================== end FILE IDENTIFICATION RECORD ====================*
%FSLAX25Y25*MOIN*%
%IR0*IPPOS*OFA0.00000B0.00000*MIA0B0*SFA1.00000B1.00000*%
%ADD10C,.006*%
G75*
%LPD*%
G75*
G36*
G01X1478494Y2224797D02*
X1468693Y2228346D01*
X1468076Y2224458D01*
X1478494Y2224797D01*
G37*
G36*
G01X1494474Y1309012D02*
X1501677Y1316546D01*
X1498369Y1318680D01*
X1494474Y1309012D01*
G37*
G36*
G01X1498077Y1317045D02*
X1504620Y1325159D01*
X1501144Y1327007D01*
X1498077Y1317045D01*
G37*
G36*
G01X2510771Y24124D02*
X2508803Y13888D01*
X2512740D01*
X2510771Y24124D01*
G37*
G36*
G01Y41447D02*
X2512740Y51683D01*
X2508803D01*
X2510771Y41447D01*
G37*
G36*
G01X2471943Y319735D02*
X2481827Y323047D01*
X2479894Y326476D01*
X2471943Y319735D01*
G37*
G36*
G01X2486340Y1972108D02*
X2495777Y1976535D01*
X2493462Y1979719D01*
X2486340Y1972108D01*
G37*
G36*
G01X2461984Y2167460D02*
X2471757Y2171086D01*
X2469715Y2174452D01*
X2461984Y2167460D01*
G37*
G36*
G01X2471377Y2226390D02*
X2481109Y2230122D01*
X2479031Y2233465D01*
X2471377Y2226390D01*
G37*
G36*
G01X2537167Y20187D02*
X2535198Y9951D01*
X2539135D01*
X2537167Y20187D01*
G37*
G36*
G01Y24124D02*
X2539135Y34360D01*
X2535198D01*
X2537167Y24124D01*
G37*
G36*
G01X2565571Y34481D02*
X2566748Y24124D01*
X2569496Y34179D01*
X2565571Y34481D01*
G37*
G36*
G01X2595313Y-28147D02*
X2586259Y-22981D01*
X2592751Y-31137D01*
X2595313Y-28147D01*
G37*
G36*
G01X2664073Y99195D02*
X2653837Y101164D01*
Y97227D01*
X2664073Y99195D01*
G37*
G36*
G01X2629428D02*
X2639664Y97227D01*
Y101164D01*
X2629428Y99195D01*
G37*
G36*
G01X2728058Y1899242D02*
X2726090Y1889005D01*
X2730027D01*
X2728058Y1899242D01*
G37*
G36*
G01Y1907903D02*
X2730027Y1918139D01*
X2726090D01*
X2728058Y1907903D01*
G37*
G36*
G01X2772374Y1931215D02*
X2782610Y1929246D01*
Y1933183D01*
X2772374Y1931215D01*
G37*
G36*
G01X2750720D02*
X2740484Y1933183D01*
Y1929246D01*
X2750720Y1931215D01*
G37*
G36*
G01X3653554Y250267D02*
X3644420Y255290D01*
X3651040Y247238D01*
X3653554Y250267D01*
G37*
G36*
G01X3649198Y2247079D02*
X3644420Y2237814D01*
X3652294Y2244646D01*
X3649198Y2247079D01*
G37*
G36*
G01X3746985Y251124D02*
X3736940Y253909D01*
X3745235Y247597D01*
X3746985Y251124D01*
G37*
G36*
G01X3733003Y2085073D02*
X3743240Y2083104D01*
Y2087041D01*
X3733003Y2085073D01*
G37*
G36*
G01X3689055Y2138437D02*
X3687087Y2128200D01*
X3691024D01*
X3689055Y2138437D01*
G37*
G36*
G01Y2152216D02*
X3691024Y2162452D01*
X3687087D01*
X3689055Y2152216D01*
G37*
G36*
G01X3739084Y2241979D02*
X3736940Y2231778D01*
X3742715Y2240456D01*
X3739084Y2241979D01*
G37*
G36*
G01X3764500Y2085073D02*
X3754263Y2087041D01*
Y2083104D01*
X3764500Y2085073D01*
G37*
G36*
G01X3754527Y2153446D02*
X3764949Y2153653D01*
X3764129Y2157504D01*
X3754527Y2153446D01*
G37*
G54D10*
G01X-280964Y-61874D02*
Y-69859D01*
X-276971D01*
G01X-281163Y146022D02*
Y154007D01*
G01X-277371D02*
X-281163Y149083D01*
G01X-276772Y146022D02*
X-279467Y151345D01*
G01X-280964Y363502D02*
X-280465Y362703D01*
X-279866Y362171D01*
X-279167Y361905D01*
X-278369Y362171D01*
X-277770Y362703D01*
X-277171Y363502D01*
X-276971Y364567D01*
Y369890D01*
G01X-280165Y585772D02*
X-277770D01*
G01X-278968D02*
Y577787D01*
G01X-280165D02*
X-277770D01*
G01X-281064Y793478D02*
Y801463D01*
G01X-276871D02*
Y793478D01*
G01Y797470D02*
X-281064D01*
G01X-278369Y1013353D02*
X-276372D01*
Y1010958D01*
X-276971Y1010159D01*
X-277670Y1009627D01*
X-278668Y1009361D01*
X-279666Y1009627D01*
X-280365Y1010159D01*
X-280964Y1010958D01*
X-281363Y1011890D01*
X-281563Y1012954D01*
Y1013886D01*
X-281363Y1014684D01*
X-280964Y1015616D01*
X-280365Y1016414D01*
X-279766Y1016947D01*
X-278968Y1017346D01*
X-278269D01*
X-277470Y1017080D01*
X-276871Y1016547D01*
G01X-281242Y1225433D02*
Y1233418D01*
X-277449D01*
G01X-278846Y1229559D02*
X-281242D01*
G01X-276971Y1441504D02*
X-280964D01*
Y1449489D01*
X-276971D01*
G01X-278568Y1445630D02*
X-280964D01*
G01X-281163Y1657196D02*
Y1665181D01*
X-279167D01*
X-278369Y1664782D01*
X-277770Y1664249D01*
X-277271Y1663451D01*
X-276871Y1662519D01*
X-276772Y1661188D01*
X-276871Y1659858D01*
X-277271Y1658926D01*
X-277770Y1658127D01*
X-278369Y1657595D01*
X-279167Y1657196D01*
X-281163D01*
G01X-276772Y1880587D02*
X-277371Y1880987D01*
X-278069Y1881253D01*
X-278868D01*
X-279766Y1880854D01*
X-280465Y1880188D01*
X-280964Y1879390D01*
X-281363Y1878059D01*
X-281463Y1876861D01*
X-281263Y1875663D01*
X-280964Y1874865D01*
X-280365Y1874066D01*
X-279666Y1873534D01*
X-278968Y1873268D01*
X-278269D01*
X-277570Y1873534D01*
X-276971Y1873933D01*
X-276472Y1874465D01*
G01X-278169Y2093218D02*
X-277770Y2093617D01*
X-277470Y2094282D01*
X-277271Y2095214D01*
X-277470Y2096012D01*
X-277869Y2096545D01*
X-278568Y2096944D01*
X-281263D01*
Y2088959D01*
X-277969D01*
X-277271Y2089491D01*
X-276871Y2090290D01*
X-276672Y2091221D01*
X-276871Y2092153D01*
X-277470Y2092951D01*
X-278169Y2093218D01*
X-281263D01*
G01X-281463Y2304841D02*
X-278968Y2312826D01*
X-276472Y2304841D01*
G01X-277371Y2307636D02*
X-280565D01*
G01X-152090Y-187269D02*
Y-179284D01*
X-153287Y-180881D01*
G01Y-187269D02*
X-150892D01*
G01X-146574Y4048D02*
X-147372Y3782D01*
X-147971Y3116D01*
X-148370Y2318D01*
X-148670Y1253D01*
X-148769Y55D01*
X-148670Y-1142D01*
X-148370Y-2207D01*
X-147971Y-3006D01*
X-147372Y-3671D01*
X-146574Y-3937D01*
X-145775Y-3671D01*
X-145176Y-3006D01*
X-144777Y-2207D01*
X-144477Y-1142D01*
X-144378Y55D01*
X-144477Y1253D01*
X-144777Y2318D01*
X-145176Y3116D01*
X-145775Y3782D01*
X-146574Y4048D01*
G01X-138589Y-4203D02*
X-138788Y-4070D01*
Y-3804D01*
X-138589Y-3671D01*
X-138389Y-3804D01*
Y-4070D01*
X-138589Y-4203D01*
G01X-130604Y4048D02*
X-131402Y3782D01*
X-132001Y3116D01*
X-132400Y2318D01*
X-132700Y1253D01*
X-132799Y55D01*
X-132700Y-1142D01*
X-132400Y-2207D01*
X-132001Y-3006D01*
X-131402Y-3671D01*
X-130604Y-3937D01*
X-129805Y-3671D01*
X-129206Y-3006D01*
X-128807Y-2207D01*
X-128507Y-1142D01*
X-128408Y55D01*
X-128507Y1253D01*
X-128807Y2318D01*
X-129206Y3116D01*
X-129805Y3782D01*
X-130604Y4048D01*
G01X-122619D02*
X-123417Y3782D01*
X-124016Y3116D01*
X-124415Y2318D01*
X-124715Y1253D01*
X-124814Y55D01*
X-124715Y-1142D01*
X-124415Y-2207D01*
X-124016Y-3006D01*
X-123417Y-3671D01*
X-122619Y-3937D01*
X-121820Y-3671D01*
X-121221Y-3006D01*
X-120822Y-2207D01*
X-120522Y-1142D01*
X-120423Y55D01*
X-120522Y1253D01*
X-120822Y2318D01*
X-121221Y3116D01*
X-121820Y3782D01*
X-122619Y4048D01*
G01X-174594Y1989657D02*
X-173996Y1988992D01*
X-173297Y1988593D01*
X-172399Y1988460D01*
X-171500Y1988726D01*
X-170802Y1989258D01*
X-170302Y1990190D01*
X-170203Y1991255D01*
X-170402Y1992319D01*
X-170901Y1992985D01*
X-171600Y1993517D01*
X-172299Y1993650D01*
X-172997Y1993517D01*
X-173896Y1992985D01*
X-173596Y1996445D01*
X-170901D01*
G01X-164414D02*
X-165212Y1996179D01*
X-165811Y1995513D01*
X-166210Y1994715D01*
X-166510Y1993650D01*
X-166609Y1992452D01*
X-166510Y1991255D01*
X-166210Y1990190D01*
X-165811Y1989391D01*
X-165212Y1988726D01*
X-164414Y1988460D01*
X-163615Y1988726D01*
X-163016Y1989391D01*
X-162617Y1990190D01*
X-162317Y1991255D01*
X-162218Y1992452D01*
X-162317Y1993650D01*
X-162617Y1994715D01*
X-163016Y1995513D01*
X-163615Y1996179D01*
X-164414Y1996445D01*
G01X-158325Y1991787D02*
X-157626Y1992719D01*
X-157027Y1993251D01*
X-156229Y1993517D01*
X-155530Y1993251D01*
X-155031Y1992719D01*
X-154632Y1991920D01*
X-154532Y1990989D01*
X-154632Y1990190D01*
X-155031Y1989391D01*
X-155630Y1988726D01*
X-156329Y1988460D01*
X-157127Y1988726D01*
X-157826Y1989524D01*
X-158225Y1990722D01*
X-158325Y1992053D01*
X-158125Y1993783D01*
X-157826Y1994715D01*
X-157327Y1995646D01*
X-156628Y1996312D01*
X-155929Y1996445D01*
X-155231Y1996179D01*
X-154732Y1995513D01*
G01X-148444Y1988194D02*
X-148643Y1988327D01*
Y1988593D01*
X-148444Y1988726D01*
X-148244Y1988593D01*
Y1988327D01*
X-148444Y1988194D01*
G01X-140459Y1996445D02*
X-141257Y1996179D01*
X-141856Y1995513D01*
X-142255Y1994715D01*
X-142555Y1993650D01*
X-142654Y1992452D01*
X-142555Y1991255D01*
X-142255Y1990190D01*
X-141856Y1989391D01*
X-141257Y1988726D01*
X-140459Y1988460D01*
X-139660Y1988726D01*
X-139061Y1989391D01*
X-138662Y1990190D01*
X-138362Y1991255D01*
X-138263Y1992452D01*
X-138362Y1993650D01*
X-138662Y1994715D01*
X-139061Y1995513D01*
X-139660Y1996179D01*
X-140459Y1996445D01*
G01X-132474D02*
X-133272Y1996179D01*
X-133871Y1995513D01*
X-134270Y1994715D01*
X-134570Y1993650D01*
X-134669Y1992452D01*
X-134570Y1991255D01*
X-134270Y1990190D01*
X-133871Y1989391D01*
X-133272Y1988726D01*
X-132474Y1988460D01*
X-131675Y1988726D01*
X-131076Y1989391D01*
X-130677Y1990190D01*
X-130377Y1991255D01*
X-130278Y1992452D01*
X-130377Y1993650D01*
X-130677Y1994715D01*
X-131076Y1995513D01*
X-131675Y1996179D01*
X-132474Y1996445D01*
G01X-152090Y2422250D02*
Y2430235D01*
X-153287Y2428638D01*
G01Y2422250D02*
X-150892D01*
G01X-95084Y2046477D02*
X-94818Y2045679D01*
X-94152Y2045080D01*
X-93354Y2044681D01*
X-92289Y2044381D01*
X-91091Y2044282D01*
X-89894Y2044381D01*
X-88829Y2044681D01*
X-88030Y2045080D01*
X-87365Y2045679D01*
X-87099Y2046477D01*
X-87365Y2047276D01*
X-88030Y2047875D01*
X-88829Y2048274D01*
X-89894Y2048574D01*
X-91091Y2048673D01*
X-92289Y2048574D01*
X-93354Y2048274D01*
X-94152Y2047875D01*
X-94818Y2047276D01*
X-95084Y2046477D01*
G01X-86833Y2054462D02*
X-86966Y2054263D01*
X-87232D01*
X-87365Y2054462D01*
X-87232Y2054662D01*
X-86966D01*
X-86833Y2054462D01*
G01X-95084Y2062447D02*
X-94818Y2061649D01*
X-94152Y2061050D01*
X-93354Y2060651D01*
X-92289Y2060351D01*
X-91091Y2060252D01*
X-89894Y2060351D01*
X-88829Y2060651D01*
X-88030Y2061050D01*
X-87365Y2061649D01*
X-87099Y2062447D01*
X-87365Y2063246D01*
X-88030Y2063845D01*
X-88829Y2064244D01*
X-89894Y2064544D01*
X-91091Y2064643D01*
X-92289Y2064544D01*
X-93354Y2064244D01*
X-94152Y2063845D01*
X-94818Y2063246D01*
X-95084Y2062447D01*
G01Y2070432D02*
X-94818Y2069634D01*
X-94152Y2069035D01*
X-93354Y2068636D01*
X-92289Y2068336D01*
X-91091Y2068237D01*
X-89894Y2068336D01*
X-88829Y2068636D01*
X-88030Y2069035D01*
X-87365Y2069634D01*
X-87099Y2070432D01*
X-87365Y2071231D01*
X-88030Y2071830D01*
X-88829Y2072229D01*
X-89894Y2072529D01*
X-91091Y2072628D01*
X-92289Y2072529D01*
X-93354Y2072229D01*
X-94152Y2071830D01*
X-94818Y2071231D01*
X-95084Y2070432D01*
G01X-3201Y2043700D02*
X-4000Y2044299D01*
X-4399Y2044998D01*
X-4532Y2045796D01*
X-4266Y2046794D01*
X-3600Y2047493D01*
X-2802Y2047693D01*
X-2003Y2047593D01*
X-1338Y2047193D01*
X-7Y2045197D01*
X924Y2044299D01*
X2256Y2043700D01*
X3453Y2043500D01*
Y2047693D01*
G01X1856Y2051386D02*
X2788Y2051984D01*
X3320Y2052783D01*
X3453Y2053681D01*
X3320Y2054480D01*
X2655Y2055278D01*
X1856Y2055777D01*
X1058Y2055877D01*
X126Y2055678D01*
X-539Y2054979D01*
X-806Y2054280D01*
Y2053382D01*
G01Y2054280D02*
X-1205Y2054879D01*
X-1870Y2055378D01*
X-2669Y2055578D01*
X-3467Y2055378D01*
X-4133Y2054879D01*
X-4532Y2053981D01*
X-4399Y2053082D01*
X-3866Y2052184D01*
G01X3719Y2061566D02*
X3586Y2061367D01*
X3320D01*
X3187Y2061566D01*
X3320Y2061766D01*
X3586D01*
X3719Y2061566D01*
G01X-4532Y2069551D02*
X-4266Y2068753D01*
X-3600Y2068154D01*
X-2802Y2067755D01*
X-1737Y2067455D01*
X-539Y2067356D01*
X658Y2067455D01*
X1723Y2067755D01*
X2522Y2068154D01*
X3187Y2068753D01*
X3453Y2069551D01*
X3187Y2070350D01*
X2522Y2070949D01*
X1723Y2071348D01*
X658Y2071648D01*
X-539Y2071747D01*
X-1737Y2071648D01*
X-2802Y2071348D01*
X-3600Y2070949D01*
X-4266Y2070350D01*
X-4532Y2069551D01*
G01Y2077536D02*
X-4266Y2076738D01*
X-3600Y2076139D01*
X-2802Y2075740D01*
X-1737Y2075440D01*
X-539Y2075341D01*
X658Y2075440D01*
X1723Y2075740D01*
X2522Y2076139D01*
X3187Y2076738D01*
X3453Y2077536D01*
X3187Y2078335D01*
X2522Y2078934D01*
X1723Y2079333D01*
X658Y2079633D01*
X-539Y2079732D01*
X-1737Y2079633D01*
X-2802Y2079333D01*
X-3600Y2078934D01*
X-4266Y2078335D01*
X-4532Y2077536D01*
G01X63790Y-180615D02*
X64389Y-179816D01*
X65088Y-179417D01*
X65886Y-179284D01*
X66884Y-179550D01*
X67583Y-180216D01*
X67783Y-181014D01*
X67683Y-181813D01*
X67283Y-182478D01*
X65287Y-183809D01*
X64389Y-184740D01*
X63790Y-186072D01*
X63590Y-187269D01*
X67783D01*
G01X63790Y2428904D02*
X64389Y2429703D01*
X65088Y2430102D01*
X65886Y2430235D01*
X66884Y2429969D01*
X67583Y2429303D01*
X67783Y2428505D01*
X67683Y2427706D01*
X67283Y2427041D01*
X65287Y2425710D01*
X64389Y2424779D01*
X63790Y2423447D01*
X63590Y2422250D01*
X67783D01*
G01X283160Y-185672D02*
X283758Y-186604D01*
X284557Y-187136D01*
X285455Y-187269D01*
X286254Y-187136D01*
X287052Y-186471D01*
X287551Y-185672D01*
X287651Y-184874D01*
X287452Y-183942D01*
X286753Y-183277D01*
X286054Y-183010D01*
X285156D01*
G01X286054D02*
X286653Y-182611D01*
X287152Y-181946D01*
X287352Y-181147D01*
X287152Y-180349D01*
X286653Y-179683D01*
X285755Y-179284D01*
X284856Y-179417D01*
X283958Y-179950D01*
G01X283160Y2423847D02*
X283758Y2422915D01*
X284557Y2422383D01*
X285455Y2422250D01*
X286254Y2422383D01*
X287052Y2423048D01*
X287551Y2423847D01*
X287651Y2424645D01*
X287452Y2425577D01*
X286753Y2426242D01*
X286054Y2426509D01*
X285156D01*
G01X286054D02*
X286653Y2426908D01*
X287152Y2427573D01*
X287352Y2428372D01*
X287152Y2429170D01*
X286653Y2429836D01*
X285755Y2430235D01*
X284856Y2430102D01*
X283958Y2429569D01*
G01X506222Y-187269D02*
Y-179284D01*
X502529Y-185007D01*
X507520D01*
G01X506222Y2422250D02*
Y2430235D01*
X502529Y2424512D01*
X507520D01*
G01X722499Y-186072D02*
X723097Y-186737D01*
X723796Y-187136D01*
X724694Y-187269D01*
X725593Y-187003D01*
X726291Y-186471D01*
X726791Y-185539D01*
X726890Y-184474D01*
X726691Y-183410D01*
X726192Y-182744D01*
X725493Y-182212D01*
X724794Y-182079D01*
X724096Y-182212D01*
X723197Y-182744D01*
X723497Y-179284D01*
X726192D01*
G01X722499Y2423447D02*
X723097Y2422782D01*
X723796Y2422383D01*
X724694Y2422250D01*
X725593Y2422516D01*
X726291Y2423048D01*
X726791Y2423980D01*
X726890Y2425045D01*
X726691Y2426109D01*
X726192Y2426775D01*
X725493Y2427307D01*
X724794Y2427440D01*
X724096Y2427307D01*
X723197Y2426775D01*
X723497Y2430235D01*
X726192D01*
G01X942467Y-183942D02*
X943166Y-183010D01*
X943765Y-182478D01*
X944563Y-182212D01*
X945262Y-182478D01*
X945761Y-183010D01*
X946160Y-183809D01*
X946260Y-184740D01*
X946160Y-185539D01*
X945761Y-186338D01*
X945162Y-187003D01*
X944463Y-187269D01*
X943665Y-187003D01*
X942966Y-186205D01*
X942567Y-185007D01*
X942467Y-183676D01*
X942667Y-181946D01*
X942966Y-181014D01*
X943465Y-180083D01*
X944164Y-179417D01*
X944863Y-179284D01*
X945561Y-179550D01*
X946060Y-180216D01*
G01X942467Y2425577D02*
X943166Y2426509D01*
X943765Y2427041D01*
X944563Y2427307D01*
X945262Y2427041D01*
X945761Y2426509D01*
X946160Y2425710D01*
X946260Y2424779D01*
X946160Y2423980D01*
X945761Y2423181D01*
X945162Y2422516D01*
X944463Y2422250D01*
X943665Y2422516D01*
X942966Y2423314D01*
X942567Y2424512D01*
X942467Y2425843D01*
X942667Y2427573D01*
X942966Y2428505D01*
X943465Y2429436D01*
X944164Y2430102D01*
X944863Y2430235D01*
X945561Y2429969D01*
X946060Y2429303D01*
G01X1034202Y2046417D02*
X1033403Y2047016D01*
X1033004Y2047715D01*
X1032871Y2048513D01*
X1033137Y2049511D01*
X1033803Y2050210D01*
X1034601Y2050410D01*
X1035400Y2050310D01*
X1036065Y2049910D01*
X1037396Y2047914D01*
X1038327Y2047016D01*
X1039659Y2046417D01*
X1040856Y2046217D01*
Y2050410D01*
G01Y2056298D02*
X1040723Y2056997D01*
X1040324Y2057796D01*
X1039659Y2058295D01*
X1038727Y2058494D01*
X1037795Y2058295D01*
X1036997Y2057696D01*
X1036597Y2056798D01*
Y2055799D01*
X1036331Y2055200D01*
X1035666Y2054701D01*
X1034734Y2054502D01*
X1033803Y2054801D01*
X1033137Y2055500D01*
X1032871Y2056298D01*
X1033137Y2057097D01*
X1033803Y2057796D01*
X1034734Y2058095D01*
X1035666Y2057895D01*
X1036331Y2057397D01*
X1036597Y2056798D01*
Y2055799D01*
X1036997Y2054901D01*
X1037795Y2054302D01*
X1038727Y2054103D01*
X1039659Y2054302D01*
X1040324Y2054801D01*
X1040723Y2055600D01*
X1040856Y2056298D01*
G01X1037529Y2062387D02*
X1036597Y2063086D01*
X1036065Y2063685D01*
X1035799Y2064483D01*
X1036065Y2065182D01*
X1036597Y2065681D01*
X1037396Y2066080D01*
X1038327Y2066180D01*
X1039126Y2066080D01*
X1039925Y2065681D01*
X1040590Y2065082D01*
X1040856Y2064383D01*
X1040590Y2063585D01*
X1039792Y2062886D01*
X1038594Y2062487D01*
X1037263Y2062387D01*
X1035533Y2062587D01*
X1034601Y2062886D01*
X1033670Y2063385D01*
X1033004Y2064084D01*
X1032871Y2064783D01*
X1033137Y2065481D01*
X1033803Y2065980D01*
G01X1041122Y2072268D02*
X1040989Y2072069D01*
X1040723D01*
X1040590Y2072268D01*
X1040723Y2072468D01*
X1040989D01*
X1041122Y2072268D01*
G01X1039659Y2078058D02*
X1040324Y2078656D01*
X1040723Y2079355D01*
X1040856Y2080253D01*
X1040590Y2081152D01*
X1040058Y2081850D01*
X1039126Y2082350D01*
X1038061Y2082449D01*
X1036997Y2082250D01*
X1036331Y2081751D01*
X1035799Y2081052D01*
X1035666Y2080353D01*
X1035799Y2079655D01*
X1036331Y2078756D01*
X1032871Y2079056D01*
Y2081751D01*
G01Y2088238D02*
X1033137Y2087440D01*
X1033803Y2086841D01*
X1034601Y2086442D01*
X1035666Y2086142D01*
X1036864Y2086043D01*
X1038061Y2086142D01*
X1039126Y2086442D01*
X1039925Y2086841D01*
X1040590Y2087440D01*
X1040856Y2088238D01*
X1040590Y2089037D01*
X1039925Y2089636D01*
X1039126Y2090035D01*
X1038061Y2090335D01*
X1036864Y2090434D01*
X1035666Y2090335D01*
X1034601Y2090035D01*
X1033803Y2089636D01*
X1033137Y2089037D01*
X1032871Y2088238D01*
G01X1129810Y2041144D02*
X1130742Y2041742D01*
X1131274Y2042541D01*
X1131407Y2043439D01*
X1131274Y2044238D01*
X1130609Y2045036D01*
X1129810Y2045535D01*
X1129012Y2045635D01*
X1128080Y2045436D01*
X1127415Y2044737D01*
X1127148Y2044038D01*
Y2043140D01*
G01Y2044038D02*
X1126749Y2044637D01*
X1126084Y2045136D01*
X1125285Y2045336D01*
X1124487Y2045136D01*
X1123821Y2044637D01*
X1123422Y2043739D01*
X1123555Y2042840D01*
X1124088Y2041942D01*
G01X1123422Y2051324D02*
X1123688Y2050526D01*
X1124354Y2049927D01*
X1125152Y2049528D01*
X1126217Y2049228D01*
X1127415Y2049129D01*
X1128612Y2049228D01*
X1129677Y2049528D01*
X1130476Y2049927D01*
X1131141Y2050526D01*
X1131407Y2051324D01*
X1131141Y2052123D01*
X1130476Y2052722D01*
X1129677Y2053121D01*
X1128612Y2053421D01*
X1127415Y2053520D01*
X1126217Y2053421D01*
X1125152Y2053121D01*
X1124354Y2052722D01*
X1123688Y2052123D01*
X1123422Y2051324D01*
G01X1130476Y2057613D02*
X1131141Y2058311D01*
X1131407Y2059110D01*
X1131141Y2059908D01*
X1130343Y2060607D01*
X1129145Y2061106D01*
X1127947Y2061306D01*
X1126483D01*
X1125285Y2061106D01*
X1124221Y2060607D01*
X1123688Y2060008D01*
X1123422Y2059309D01*
X1123688Y2058511D01*
X1124221Y2057912D01*
X1125019Y2057513D01*
X1126084Y2057313D01*
X1127015Y2057513D01*
X1127947Y2058012D01*
X1128479Y2058611D01*
X1128612Y2059309D01*
X1128346Y2060108D01*
X1127681Y2060707D01*
X1126483Y2061306D01*
G01X1131673Y2067294D02*
X1131540Y2067095D01*
X1131274D01*
X1131141Y2067294D01*
X1131274Y2067494D01*
X1131540D01*
X1131673Y2067294D01*
G01X1130210Y2073084D02*
X1130875Y2073682D01*
X1131274Y2074381D01*
X1131407Y2075279D01*
X1131141Y2076178D01*
X1130609Y2076876D01*
X1129677Y2077376D01*
X1128612Y2077475D01*
X1127548Y2077276D01*
X1126882Y2076777D01*
X1126350Y2076078D01*
X1126217Y2075379D01*
X1126350Y2074681D01*
X1126882Y2073782D01*
X1123422Y2074082D01*
Y2076777D01*
G01Y2083264D02*
X1123688Y2082466D01*
X1124354Y2081867D01*
X1125152Y2081468D01*
X1126217Y2081168D01*
X1127415Y2081069D01*
X1128612Y2081168D01*
X1129677Y2081468D01*
X1130476Y2081867D01*
X1131141Y2082466D01*
X1131407Y2083264D01*
X1131141Y2084063D01*
X1130476Y2084662D01*
X1129677Y2085061D01*
X1128612Y2085361D01*
X1127415Y2085460D01*
X1126217Y2085361D01*
X1125152Y2085061D01*
X1124354Y2084662D01*
X1123688Y2084063D01*
X1123422Y2083264D01*
G01X1163833Y-187269D02*
X1164032Y-185539D01*
X1164332Y-184075D01*
X1164731Y-182744D01*
X1165230Y-181280D01*
X1166029Y-179284D01*
X1162036D01*
G01X1163833Y2422250D02*
X1164032Y2423980D01*
X1164332Y2425444D01*
X1164731Y2426775D01*
X1165230Y2428239D01*
X1166029Y2430235D01*
X1162036D01*
G01X1383702Y-187269D02*
X1384401Y-187136D01*
X1385200Y-186737D01*
X1385699Y-186072D01*
X1385898Y-185140D01*
X1385699Y-184208D01*
X1385100Y-183410D01*
X1384202Y-183010D01*
X1383203D01*
X1382604Y-182744D01*
X1382105Y-182079D01*
X1381906Y-181147D01*
X1382205Y-180216D01*
X1382904Y-179550D01*
X1383702Y-179284D01*
X1384501Y-179550D01*
X1385200Y-180216D01*
X1385499Y-181147D01*
X1385299Y-182079D01*
X1384801Y-182744D01*
X1384202Y-183010D01*
X1383203D01*
X1382305Y-183410D01*
X1381706Y-184208D01*
X1381507Y-185140D01*
X1381706Y-186072D01*
X1382205Y-186737D01*
X1383004Y-187136D01*
X1383702Y-187269D01*
G01Y2422250D02*
X1384401Y2422383D01*
X1385200Y2422782D01*
X1385699Y2423447D01*
X1385898Y2424379D01*
X1385699Y2425311D01*
X1385100Y2426109D01*
X1384202Y2426509D01*
X1383203D01*
X1382604Y2426775D01*
X1382105Y2427440D01*
X1381906Y2428372D01*
X1382205Y2429303D01*
X1382904Y2429969D01*
X1383702Y2430235D01*
X1384501Y2429969D01*
X1385200Y2429303D01*
X1385499Y2428372D01*
X1385299Y2427440D01*
X1384801Y2426775D01*
X1384202Y2426509D01*
X1383203D01*
X1382305Y2426109D01*
X1381706Y2425311D01*
X1381507Y2424379D01*
X1381706Y2423447D01*
X1382205Y2422782D01*
X1383004Y2422383D01*
X1383702Y2422250D01*
G01X1601675Y-186338D02*
X1602373Y-187003D01*
X1603172Y-187269D01*
X1603970Y-187003D01*
X1604669Y-186205D01*
X1605168Y-185007D01*
X1605368Y-183809D01*
Y-182345D01*
X1605168Y-181147D01*
X1604669Y-180083D01*
X1604070Y-179550D01*
X1603371Y-179284D01*
X1602573Y-179550D01*
X1601974Y-180083D01*
X1601575Y-180881D01*
X1601375Y-181946D01*
X1601575Y-182877D01*
X1602074Y-183809D01*
X1602673Y-184341D01*
X1603371Y-184474D01*
X1604170Y-184208D01*
X1604769Y-183543D01*
X1605368Y-182345D01*
G01X1601675Y2423181D02*
X1602373Y2422516D01*
X1603172Y2422250D01*
X1603970Y2422516D01*
X1604669Y2423314D01*
X1605168Y2424512D01*
X1605368Y2425710D01*
Y2427174D01*
X1605168Y2428372D01*
X1604669Y2429436D01*
X1604070Y2429969D01*
X1603371Y2430235D01*
X1602573Y2429969D01*
X1601974Y2429436D01*
X1601575Y2428638D01*
X1601375Y2427573D01*
X1601575Y2426642D01*
X1602074Y2425710D01*
X1602673Y2425178D01*
X1603371Y2425045D01*
X1604170Y2425311D01*
X1604769Y2425976D01*
X1605368Y2427174D01*
G01X1820389Y-187269D02*
Y-179284D01*
X1819192Y-180881D01*
G01Y-187269D02*
X1821587D01*
G01X1828374Y-179284D02*
X1827576Y-179550D01*
X1826977Y-180216D01*
X1826578Y-181014D01*
X1826278Y-182079D01*
X1826179Y-183277D01*
X1826278Y-184474D01*
X1826578Y-185539D01*
X1826977Y-186338D01*
X1827576Y-187003D01*
X1828374Y-187269D01*
X1829173Y-187003D01*
X1829772Y-186338D01*
X1830171Y-185539D01*
X1830471Y-184474D01*
X1830570Y-183277D01*
X1830471Y-182079D01*
X1830171Y-181014D01*
X1829772Y-180216D01*
X1829173Y-179550D01*
X1828374Y-179284D01*
G01X1820389Y2422250D02*
Y2430235D01*
X1819192Y2428638D01*
G01Y2422250D02*
X1821587D01*
G01X1828374Y2430235D02*
X1827576Y2429969D01*
X1826977Y2429303D01*
X1826578Y2428505D01*
X1826278Y2427440D01*
X1826179Y2426242D01*
X1826278Y2425045D01*
X1826578Y2423980D01*
X1826977Y2423181D01*
X1827576Y2422516D01*
X1828374Y2422250D01*
X1829173Y2422516D01*
X1829772Y2423181D01*
X1830171Y2423980D01*
X1830471Y2425045D01*
X1830570Y2426242D01*
X1830471Y2427440D01*
X1830171Y2428505D01*
X1829772Y2429303D01*
X1829173Y2429969D01*
X1828374Y2430235D01*
G01X2040816Y-187269D02*
Y-179284D01*
X2039619Y-180881D01*
G01Y-187269D02*
X2042014D01*
G01X2048801D02*
Y-179284D01*
X2047604Y-180881D01*
G01Y-187269D02*
X2049999D01*
G01X2040816Y2422250D02*
Y2430235D01*
X2039619Y2428638D01*
G01Y2422250D02*
X2042014D01*
G01X2048801D02*
Y2430235D01*
X2047604Y2428638D01*
G01Y2422250D02*
X2049999D01*
G01X2258591Y-187269D02*
Y-179284D01*
X2257394Y-180881D01*
G01Y-187269D02*
X2259789D01*
G01X2264680Y-180615D02*
X2265279Y-179816D01*
X2265978Y-179417D01*
X2266776Y-179284D01*
X2267774Y-179550D01*
X2268473Y-180216D01*
X2268673Y-181014D01*
X2268573Y-181813D01*
X2268173Y-182478D01*
X2266177Y-183809D01*
X2265279Y-184740D01*
X2264680Y-186072D01*
X2264480Y-187269D01*
X2268673D01*
G01X2258591Y2422250D02*
Y2430235D01*
X2257394Y2428638D01*
G01Y2422250D02*
X2259789D01*
G01X2264680Y2428904D02*
X2265279Y2429703D01*
X2265978Y2430102D01*
X2266776Y2430235D01*
X2267774Y2429969D01*
X2268473Y2429303D01*
X2268673Y2428505D01*
X2268573Y2427706D01*
X2268173Y2427041D01*
X2266177Y2425710D01*
X2265279Y2424779D01*
X2264680Y2423447D01*
X2264480Y2422250D01*
X2268673D01*
G01X2478261Y-187269D02*
Y-179284D01*
X2477064Y-180881D01*
G01Y-187269D02*
X2479459D01*
G01X2484051Y-185672D02*
X2484649Y-186604D01*
X2485448Y-187136D01*
X2486346Y-187269D01*
X2487145Y-187136D01*
X2487943Y-186471D01*
X2488442Y-185672D01*
X2488542Y-184874D01*
X2488343Y-183942D01*
X2487644Y-183277D01*
X2486945Y-183010D01*
X2486047D01*
G01X2486945D02*
X2487544Y-182611D01*
X2488043Y-181946D01*
X2488243Y-181147D01*
X2488043Y-180349D01*
X2487544Y-179683D01*
X2486646Y-179284D01*
X2485747Y-179417D01*
X2484849Y-179950D01*
G01X2478261Y2422250D02*
Y2430235D01*
X2477064Y2428638D01*
G01Y2422250D02*
X2479459D01*
G01X2484051Y2423847D02*
X2484649Y2422915D01*
X2485448Y2422383D01*
X2486346Y2422250D01*
X2487145Y2422383D01*
X2487943Y2423048D01*
X2488442Y2423847D01*
X2488542Y2424645D01*
X2488343Y2425577D01*
X2487644Y2426242D01*
X2486945Y2426509D01*
X2486047D01*
G01X2486945D02*
X2487544Y2426908D01*
X2488043Y2427573D01*
X2488243Y2428372D01*
X2488043Y2429170D01*
X2487544Y2429836D01*
X2486646Y2430235D01*
X2485747Y2430102D01*
X2484849Y2429569D01*
G01X2697930Y-187269D02*
Y-179284D01*
X2696733Y-180881D01*
G01Y-187269D02*
X2699128D01*
G01X2707113D02*
Y-179284D01*
X2703420Y-185007D01*
X2708411D01*
G01X2697930Y2422250D02*
Y2430235D01*
X2696733Y2428638D01*
G01Y2422250D02*
X2699128D01*
G01X2707113D02*
Y2430235D01*
X2703420Y2424512D01*
X2708411D01*
G01X2917599Y-187269D02*
Y-179284D01*
X2916402Y-180881D01*
G01Y-187269D02*
X2918797D01*
G01X2923389Y-186072D02*
X2923987Y-186737D01*
X2924686Y-187136D01*
X2925584Y-187269D01*
X2926483Y-187003D01*
X2927181Y-186471D01*
X2927681Y-185539D01*
X2927780Y-184474D01*
X2927581Y-183410D01*
X2927082Y-182744D01*
X2926383Y-182212D01*
X2925684Y-182079D01*
X2924986Y-182212D01*
X2924087Y-182744D01*
X2924387Y-179284D01*
X2927082D01*
G01X2917599Y2422250D02*
Y2430235D01*
X2916402Y2428638D01*
G01Y2422250D02*
X2918797D01*
G01X2923389Y2423447D02*
X2923987Y2422782D01*
X2924686Y2422383D01*
X2925584Y2422250D01*
X2926483Y2422516D01*
X2927181Y2423048D01*
X2927681Y2423980D01*
X2927780Y2425045D01*
X2927581Y2426109D01*
X2927082Y2426775D01*
X2926383Y2427307D01*
X2925684Y2427440D01*
X2924986Y2427307D01*
X2924087Y2426775D01*
X2924387Y2430235D01*
X2927082D01*
G01X3137268Y-187269D02*
Y-179284D01*
X3136071Y-180881D01*
G01Y-187269D02*
X3138466D01*
G01X3143357Y-183942D02*
X3144056Y-183010D01*
X3144655Y-182478D01*
X3145453Y-182212D01*
X3146152Y-182478D01*
X3146651Y-183010D01*
X3147050Y-183809D01*
X3147150Y-184740D01*
X3147050Y-185539D01*
X3146651Y-186338D01*
X3146052Y-187003D01*
X3145353Y-187269D01*
X3144555Y-187003D01*
X3143856Y-186205D01*
X3143457Y-185007D01*
X3143357Y-183676D01*
X3143557Y-181946D01*
X3143856Y-181014D01*
X3144355Y-180083D01*
X3145054Y-179417D01*
X3145753Y-179284D01*
X3146451Y-179550D01*
X3146950Y-180216D01*
G01X3137268Y2422250D02*
Y2430235D01*
X3136071Y2428638D01*
G01Y2422250D02*
X3138466D01*
G01X3143357Y2425577D02*
X3144056Y2426509D01*
X3144655Y2427041D01*
X3145453Y2427307D01*
X3146152Y2427041D01*
X3146651Y2426509D01*
X3147050Y2425710D01*
X3147150Y2424779D01*
X3147050Y2423980D01*
X3146651Y2423181D01*
X3146052Y2422516D01*
X3145353Y2422250D01*
X3144555Y2422516D01*
X3143856Y2423314D01*
X3143457Y2424512D01*
X3143357Y2425843D01*
X3143557Y2427573D01*
X3143856Y2428505D01*
X3144355Y2429436D01*
X3145054Y2430102D01*
X3145753Y2430235D01*
X3146451Y2429969D01*
X3146950Y2429303D01*
G01X3187174Y-21269D02*
X3193424Y-41269D01*
X3199674Y-21269D01*
G01X3209674Y-32269D02*
X3217674D01*
X3216924Y-29936D01*
X3215674Y-28603D01*
X3213924Y-27936D01*
X3212174Y-28269D01*
X3210674Y-29269D01*
X3209674Y-31603D01*
X3209174Y-33603D01*
Y-35602D01*
X3209674Y-37603D01*
X3210924Y-39603D01*
X3212424Y-40936D01*
X3214174Y-41269D01*
X3215924Y-40602D01*
X3217674Y-38603D01*
G01X3229924Y-41269D02*
Y-27936D01*
G01Y-30602D02*
X3231174Y-29269D01*
X3232424Y-28269D01*
X3234174Y-27936D01*
X3235424Y-28269D01*
X3236924Y-29269D01*
G01X3249674Y-38936D02*
X3250924Y-40269D01*
X3252674Y-41269D01*
X3254174D01*
X3255674Y-40602D01*
X3256674Y-39603D01*
X3257174Y-38270D01*
X3256924Y-36269D01*
X3255924Y-35269D01*
X3251424Y-33269D01*
X3250424Y-30935D01*
X3250924Y-29269D01*
X3251924Y-28269D01*
X3253424Y-27936D01*
X3254924Y-28269D01*
X3256424Y-29269D01*
G01X3273424Y-27936D02*
Y-41269D01*
G01Y-22603D02*
X3272924Y-22269D01*
Y-21602D01*
X3273424Y-21269D01*
X3273924Y-21602D01*
Y-22269D01*
X3273424Y-22603D01*
G01X3293424Y-41269D02*
X3291924Y-40936D01*
X3290424Y-39603D01*
X3289424Y-37269D01*
X3288924Y-34603D01*
X3289424Y-31936D01*
X3290424Y-29602D01*
X3291924Y-28269D01*
X3293424Y-27936D01*
X3294924Y-28269D01*
X3296424Y-29602D01*
X3297424Y-31936D01*
X3297674Y-34603D01*
X3297424Y-37269D01*
X3296424Y-39603D01*
X3294924Y-40936D01*
X3293424Y-41269D01*
G01X3309174D02*
Y-27936D01*
G01Y-31269D02*
X3310174Y-29602D01*
X3311674Y-28269D01*
X3313674Y-27936D01*
X3315424Y-28269D01*
X3316924Y-29602D01*
X3317674Y-31936D01*
Y-41269D01*
G01X3201626Y-71844D02*
X3200126Y-70844D01*
X3198376Y-70177D01*
X3196376D01*
X3194126Y-71177D01*
X3192376Y-72844D01*
X3191126Y-74844D01*
X3190126Y-78177D01*
X3189876Y-81177D01*
X3190376Y-84177D01*
X3191126Y-86177D01*
X3192626Y-88177D01*
X3194376Y-89510D01*
X3196126Y-90177D01*
X3197876D01*
X3199626Y-89510D01*
X3201126Y-88511D01*
X3202376Y-87178D01*
G01X3212626Y-90177D02*
Y-76844D01*
G01Y-79510D02*
X3213876Y-78177D01*
X3215126Y-77177D01*
X3216876Y-76844D01*
X3218126Y-77177D01*
X3219626Y-78177D01*
G01X3232376Y-81177D02*
X3240376D01*
X3239626Y-78844D01*
X3238376Y-77511D01*
X3236626Y-76844D01*
X3234876Y-77177D01*
X3233376Y-78177D01*
X3232376Y-80511D01*
X3231876Y-82511D01*
Y-84510D01*
X3232376Y-86511D01*
X3233626Y-88511D01*
X3235126Y-89844D01*
X3236876Y-90177D01*
X3238626Y-89510D01*
X3240376Y-87511D01*
G01X3260626Y-90177D02*
Y-76844D01*
G01Y-79177D02*
X3259626Y-77844D01*
X3258126Y-77177D01*
X3256376Y-76844D01*
X3254626Y-77511D01*
X3253126Y-78844D01*
X3252126Y-80844D01*
X3251626Y-83511D01*
X3252126Y-86177D01*
X3253126Y-88177D01*
X3254626Y-89510D01*
X3256376Y-90177D01*
X3258126Y-89844D01*
X3259626Y-88844D01*
X3260626Y-87511D01*
G01X3276126Y-70177D02*
Y-90177D01*
G01X3272626Y-76844D02*
X3279626D01*
G01X3292376Y-81177D02*
X3300376D01*
X3299626Y-78844D01*
X3298376Y-77511D01*
X3296626Y-76844D01*
X3294876Y-77177D01*
X3293376Y-78177D01*
X3292376Y-80511D01*
X3291876Y-82511D01*
Y-84510D01*
X3292376Y-86511D01*
X3293626Y-88511D01*
X3295126Y-89844D01*
X3296876Y-90177D01*
X3298626Y-89510D01*
X3300376Y-87511D01*
G01X3320626Y-70177D02*
Y-90177D01*
G01Y-87178D02*
X3319626Y-88844D01*
X3318126Y-89844D01*
X3316376Y-90177D01*
X3314376Y-89510D01*
X3312876Y-87844D01*
X3311876Y-85844D01*
X3311626Y-83511D01*
X3311876Y-81177D01*
X3312876Y-79177D01*
X3314376Y-77511D01*
X3316376Y-76844D01*
X3318126Y-77177D01*
X3319376Y-77844D01*
X3320626Y-79177D01*
G01X3199311Y46957D02*
Y66957D01*
X3205811Y50290D01*
X3212311Y66957D01*
Y46957D01*
G01X3225811D02*
X3224311Y47290D01*
X3222811Y48623D01*
X3221811Y50957D01*
X3221311Y53623D01*
X3221811Y56290D01*
X3222811Y58624D01*
X3224311Y59957D01*
X3225811Y60290D01*
X3227311Y59957D01*
X3228811Y58624D01*
X3229811Y56290D01*
X3230061Y53623D01*
X3229811Y50957D01*
X3228811Y48623D01*
X3227311Y47290D01*
X3225811Y46957D01*
G01X3250311Y66957D02*
Y46957D01*
G01Y49956D02*
X3249311Y48290D01*
X3247811Y47290D01*
X3246061Y46957D01*
X3244061Y47624D01*
X3242561Y49290D01*
X3241561Y51290D01*
X3241311Y53623D01*
X3241561Y55957D01*
X3242561Y57957D01*
X3244061Y59623D01*
X3246061Y60290D01*
X3247811Y59957D01*
X3249061Y59290D01*
X3250311Y57957D01*
G01X3262061Y55957D02*
X3270061D01*
X3269311Y58290D01*
X3268061Y59623D01*
X3266311Y60290D01*
X3264561Y59957D01*
X3263061Y58957D01*
X3262061Y56623D01*
X3261561Y54623D01*
Y52624D01*
X3262061Y50623D01*
X3263311Y48623D01*
X3264811Y47290D01*
X3266561Y46957D01*
X3268311Y47624D01*
X3270061Y49623D01*
G01X3285811Y46957D02*
Y66957D01*
G01X3191126Y2744D02*
Y22744D01*
X3197126D01*
X3199126Y21744D01*
X3200626Y19411D01*
X3201126Y16744D01*
X3200626Y14077D01*
X3199376Y12077D01*
X3197126Y11077D01*
X3191126D01*
G01X3221626Y21077D02*
X3220126Y22077D01*
X3218376Y22744D01*
X3216376D01*
X3214126Y21744D01*
X3212376Y20077D01*
X3211126Y18077D01*
X3210126Y14744D01*
X3209876Y11744D01*
X3210376Y8744D01*
X3211126Y6744D01*
X3212626Y4744D01*
X3214376Y3411D01*
X3216126Y2744D01*
X3217876D01*
X3219626Y3411D01*
X3221126Y4410D01*
X3222376Y5743D01*
G01X3238126Y13411D02*
X3239126Y14411D01*
X3239876Y16077D01*
X3240376Y18411D01*
X3239876Y20411D01*
X3238876Y21744D01*
X3237126Y22744D01*
X3230376D01*
Y2744D01*
X3238626D01*
X3240376Y4077D01*
X3241376Y6077D01*
X3241876Y8411D01*
X3241376Y10744D01*
X3239876Y12744D01*
X3238126Y13411D01*
X3230376D01*
G01X3270376Y2744D02*
Y22744D01*
X3281876Y2744D01*
Y22744D01*
G01X3296126Y2744D02*
X3294626Y3077D01*
X3293126Y4410D01*
X3292126Y6744D01*
X3291626Y9410D01*
X3292126Y12077D01*
X3293126Y14411D01*
X3294626Y15744D01*
X3296126Y16077D01*
X3297626Y15744D01*
X3299126Y14411D01*
X3300126Y12077D01*
X3300376Y9410D01*
X3300126Y6744D01*
X3299126Y4410D01*
X3297626Y3077D01*
X3296126Y2744D01*
G01X3316126Y2077D02*
X3315626Y2411D01*
Y3077D01*
X3316126Y3411D01*
X3316626Y3077D01*
Y2411D01*
X3316126Y2077D01*
G01X3356937Y-187269D02*
Y-179284D01*
X3355740Y-180881D01*
G01Y-187269D02*
X3358135D01*
G01X3364723D02*
X3364922Y-185539D01*
X3365222Y-184075D01*
X3365621Y-182744D01*
X3366120Y-181280D01*
X3366919Y-179284D01*
X3362926D01*
G01X3369305Y-126712D02*
X3372805Y-146712D01*
X3376805Y-126712D01*
X3380805Y-146712D01*
X3384305Y-126712D01*
G01X3396805Y-133379D02*
Y-146712D01*
G01Y-128046D02*
X3396305Y-127712D01*
Y-127045D01*
X3396805Y-126712D01*
X3397305Y-127045D01*
Y-127712D01*
X3396805Y-128046D01*
G01X3413055Y-144379D02*
X3414305Y-145712D01*
X3416055Y-146712D01*
X3417555D01*
X3419055Y-146045D01*
X3420055Y-145046D01*
X3420555Y-143713D01*
X3420305Y-141712D01*
X3419305Y-140712D01*
X3414805Y-138712D01*
X3413805Y-136378D01*
X3414305Y-134712D01*
X3415305Y-133712D01*
X3416805Y-133379D01*
X3418305Y-133712D01*
X3419805Y-134712D01*
G01X3436805Y-126712D02*
Y-146712D01*
G01X3433305Y-133379D02*
X3440305D01*
G01X3453305Y-146712D02*
Y-133379D01*
G01Y-136045D02*
X3454555Y-134712D01*
X3455805Y-133712D01*
X3457555Y-133379D01*
X3458805Y-133712D01*
X3460305Y-134712D01*
G01X3476805Y-146712D02*
X3475305Y-146379D01*
X3473805Y-145046D01*
X3472805Y-142712D01*
X3472305Y-140046D01*
X3472805Y-137379D01*
X3473805Y-135045D01*
X3475305Y-133712D01*
X3476805Y-133379D01*
X3478305Y-133712D01*
X3479805Y-135045D01*
X3480805Y-137379D01*
X3481055Y-140046D01*
X3480805Y-142712D01*
X3479805Y-145046D01*
X3478305Y-146379D01*
X3476805Y-146712D01*
G01X3492555D02*
Y-133379D01*
G01Y-136712D02*
X3493555Y-135045D01*
X3495055Y-133712D01*
X3497055Y-133379D01*
X3498805Y-133712D01*
X3500305Y-135045D01*
X3501055Y-137379D01*
Y-146712D01*
G01X3542305Y-128379D02*
X3540805Y-127379D01*
X3539055Y-126712D01*
X3537055D01*
X3534805Y-127712D01*
X3533055Y-129379D01*
X3531805Y-131379D01*
X3530805Y-134712D01*
X3530555Y-137712D01*
X3531055Y-140712D01*
X3531805Y-142712D01*
X3533305Y-144712D01*
X3535055Y-146045D01*
X3536805Y-146712D01*
X3538555D01*
X3540305Y-146045D01*
X3541805Y-145046D01*
X3543055Y-143713D01*
G01X3556805Y-146712D02*
X3555305Y-146379D01*
X3553805Y-145046D01*
X3552805Y-142712D01*
X3552305Y-140046D01*
X3552805Y-137379D01*
X3553805Y-135045D01*
X3555305Y-133712D01*
X3556805Y-133379D01*
X3558305Y-133712D01*
X3559805Y-135045D01*
X3560805Y-137379D01*
X3561055Y-140046D01*
X3560805Y-142712D01*
X3559805Y-145046D01*
X3558305Y-146379D01*
X3556805Y-146712D01*
G01X3573305D02*
Y-133379D01*
G01Y-136045D02*
X3574555Y-134712D01*
X3575805Y-133712D01*
X3577555Y-133379D01*
X3578805Y-133712D01*
X3580305Y-134712D01*
G01X3592305Y-153378D02*
Y-133379D01*
G01Y-136378D02*
X3593555Y-134712D01*
X3594805Y-133712D01*
X3596805Y-133379D01*
X3598555Y-133712D01*
X3600305Y-135379D01*
X3601055Y-137712D01*
X3601305Y-140046D01*
X3601055Y-142379D01*
X3600305Y-144712D01*
X3598805Y-146045D01*
X3596805Y-146712D01*
X3595055Y-146379D01*
X3593305Y-145379D01*
X3592305Y-144046D01*
G01X3616805Y-146712D02*
X3615305Y-146379D01*
X3613805Y-145046D01*
X3612805Y-142712D01*
X3612305Y-140046D01*
X3612805Y-137379D01*
X3613805Y-135045D01*
X3615305Y-133712D01*
X3616805Y-133379D01*
X3618305Y-133712D01*
X3619805Y-135045D01*
X3620805Y-137379D01*
X3621055Y-140046D01*
X3620805Y-142712D01*
X3619805Y-145046D01*
X3618305Y-146379D01*
X3616805Y-146712D01*
G01X3633305D02*
Y-133379D01*
G01Y-136045D02*
X3634555Y-134712D01*
X3635805Y-133712D01*
X3637555Y-133379D01*
X3638805Y-133712D01*
X3640305Y-134712D01*
G01X3661305Y-146712D02*
Y-133379D01*
G01Y-135712D02*
X3660305Y-134379D01*
X3658805Y-133712D01*
X3657055Y-133379D01*
X3655305Y-134046D01*
X3653805Y-135379D01*
X3652805Y-137379D01*
X3652305Y-140046D01*
X3652805Y-142712D01*
X3653805Y-144712D01*
X3655305Y-146045D01*
X3657055Y-146712D01*
X3658805Y-146379D01*
X3660305Y-145379D01*
X3661305Y-144046D01*
G01X3676805Y-126712D02*
Y-146712D01*
G01X3673305Y-133379D02*
X3680305D01*
G01X3696805D02*
Y-146712D01*
G01Y-128046D02*
X3696305Y-127712D01*
Y-127045D01*
X3696805Y-126712D01*
X3697305Y-127045D01*
Y-127712D01*
X3696805Y-128046D01*
G01X3716805Y-146712D02*
X3715305Y-146379D01*
X3713805Y-145046D01*
X3712805Y-142712D01*
X3712305Y-140046D01*
X3712805Y-137379D01*
X3713805Y-135045D01*
X3715305Y-133712D01*
X3716805Y-133379D01*
X3718305Y-133712D01*
X3719805Y-135045D01*
X3720805Y-137379D01*
X3721055Y-140046D01*
X3720805Y-142712D01*
X3719805Y-145046D01*
X3718305Y-146379D01*
X3716805Y-146712D01*
G01X3732555D02*
Y-133379D01*
G01Y-136712D02*
X3733555Y-135045D01*
X3735055Y-133712D01*
X3737055Y-133379D01*
X3738805Y-133712D01*
X3740305Y-135045D01*
X3741055Y-137379D01*
Y-146712D01*
G01X3387176Y70664D02*
Y50664D01*
X3397176D01*
G01X3412176Y63997D02*
Y50664D01*
G01Y69330D02*
X3411676Y69664D01*
Y70331D01*
X3412176Y70664D01*
X3412676Y70331D01*
Y69664D01*
X3412176Y69330D01*
G01X3428676Y45664D02*
X3430426Y44331D01*
X3432426Y43998D01*
X3434176Y44331D01*
X3435676Y45997D01*
X3436676Y48331D01*
Y63997D01*
G01Y61331D02*
X3435676Y62664D01*
X3434176Y63664D01*
X3432426Y63997D01*
X3430426Y63330D01*
X3429176Y61997D01*
X3428176Y59664D01*
X3427676Y57330D01*
X3427926Y55330D01*
X3428926Y52997D01*
X3430426Y51331D01*
X3432426Y50664D01*
X3433926Y50997D01*
X3435676Y52330D01*
X3436676Y53663D01*
G01X3447926Y50664D02*
Y70664D01*
G01Y60998D02*
X3449176Y62664D01*
X3450426Y63664D01*
X3452426Y63997D01*
X3453926Y63664D01*
X3455676Y62331D01*
X3456426Y60330D01*
Y50664D01*
G01X3472176Y70664D02*
Y50664D01*
G01X3468676Y63997D02*
X3475676D01*
G01X3487926Y50664D02*
Y63997D01*
G01Y60664D02*
X3488926Y62331D01*
X3490426Y63664D01*
X3492426Y63997D01*
X3494176Y63664D01*
X3495676Y62331D01*
X3496426Y59997D01*
Y50664D01*
G01X3512176Y63997D02*
Y50664D01*
G01Y69330D02*
X3511676Y69664D01*
Y70331D01*
X3512176Y70664D01*
X3512676Y70331D01*
Y69664D01*
X3512176Y69330D01*
G01X3527926Y50664D02*
Y63997D01*
G01Y60664D02*
X3528926Y62331D01*
X3530426Y63664D01*
X3532426Y63997D01*
X3534176Y63664D01*
X3535676Y62331D01*
X3536426Y59997D01*
Y50664D01*
G01X3548676Y45664D02*
X3550426Y44331D01*
X3552426Y43998D01*
X3554176Y44331D01*
X3555676Y45997D01*
X3556676Y48331D01*
Y63997D01*
G01Y61331D02*
X3555676Y62664D01*
X3554176Y63664D01*
X3552426Y63997D01*
X3550426Y63330D01*
X3549176Y61997D01*
X3548176Y59664D01*
X3547676Y57330D01*
X3547926Y55330D01*
X3548926Y52997D01*
X3550426Y51331D01*
X3552426Y50664D01*
X3553926Y50997D01*
X3555676Y52330D01*
X3556676Y53663D01*
G01X3587176Y50664D02*
Y70664D01*
X3593176D01*
X3595176Y69664D01*
X3596676Y67331D01*
X3597176Y64664D01*
X3596676Y61997D01*
X3595426Y59997D01*
X3593176Y58997D01*
X3587176D01*
G01X3606676Y50664D02*
Y70664D01*
X3611676D01*
X3613676Y69664D01*
X3615176Y68331D01*
X3616426Y66331D01*
X3617426Y63997D01*
X3617676Y60664D01*
X3617426Y57330D01*
X3616426Y54997D01*
X3615176Y52997D01*
X3613676Y51664D01*
X3611676Y50664D01*
X3606676D01*
G01X3627176D02*
Y70664D01*
X3633176D01*
X3635176Y69664D01*
X3636676Y67331D01*
X3637176Y64664D01*
X3636676Y61997D01*
X3635426Y59997D01*
X3633176Y58997D01*
X3627176D01*
G01X3654176Y61331D02*
X3655176Y62331D01*
X3655926Y63997D01*
X3656426Y66331D01*
X3655926Y68331D01*
X3654926Y69664D01*
X3653176Y70664D01*
X3646426D01*
Y50664D01*
X3654676D01*
X3656426Y51997D01*
X3657426Y53997D01*
X3657926Y56331D01*
X3657426Y58664D01*
X3655926Y60664D01*
X3654176Y61331D01*
X3646426D01*
G01X3686676Y50664D02*
Y70664D01*
X3691676D01*
X3693676Y69664D01*
X3695176Y68331D01*
X3696426Y66331D01*
X3697426Y63997D01*
X3697676Y60664D01*
X3697426Y57330D01*
X3696426Y54997D01*
X3695176Y52997D01*
X3693676Y51664D01*
X3691676Y50664D01*
X3686676D01*
G01X3705926Y70664D02*
X3712176Y50664D01*
X3718426Y70664D01*
G01X3732176D02*
Y50664D01*
G01X3726426Y70664D02*
X3737926D01*
G01X3356937Y2422250D02*
Y2430235D01*
X3355740Y2428638D01*
G01Y2422250D02*
X3358135D01*
G01X3364723D02*
X3364922Y2423980D01*
X3365222Y2425444D01*
X3365621Y2426775D01*
X3366120Y2428239D01*
X3366919Y2430235D01*
X3362926D01*
G01X3418357Y-46163D02*
Y-26163D01*
X3415357Y-30163D01*
G01Y-46163D02*
X3421357D01*
G01X3391080Y-68202D02*
X3394580Y-88202D01*
X3398580Y-68202D01*
X3402580Y-88202D01*
X3406080Y-68202D01*
G01X3413580Y-88202D02*
Y-68202D01*
X3419580D01*
X3421580Y-69202D01*
X3423080Y-71535D01*
X3423580Y-74202D01*
X3423080Y-76869D01*
X3421830Y-78869D01*
X3419580Y-79869D01*
X3413580D01*
G01X3433330Y-88202D02*
Y-68202D01*
G01X3443830D02*
Y-88202D01*
G01Y-78202D02*
X3433330D01*
G01X3455330Y-81536D02*
X3461830D01*
G01X3472330Y-88202D02*
X3478580Y-68202D01*
X3484830Y-88202D01*
G01X3482580Y-81202D02*
X3474580D01*
G01X3498580Y-88202D02*
Y-68202D01*
G01X3513330Y-94202D02*
X3514830Y-94868D01*
X3516830Y-94202D01*
X3518080Y-92869D01*
X3519080Y-91202D01*
X3520580Y-85869D01*
X3523830Y-74869D01*
G01X3515830D02*
X3520580Y-85869D01*
G01X3534330Y-88202D02*
Y-74869D01*
G01Y-78202D02*
X3535330Y-76535D01*
X3536830Y-75202D01*
X3538830Y-74869D01*
X3540580Y-75202D01*
X3542080Y-76535D01*
X3542830Y-78869D01*
Y-88202D01*
G01X3554830Y-79202D02*
X3562830D01*
X3562080Y-76869D01*
X3560830Y-75536D01*
X3559080Y-74869D01*
X3557330Y-75202D01*
X3555830Y-76202D01*
X3554830Y-78536D01*
X3554330Y-80536D01*
Y-82535D01*
X3554830Y-84536D01*
X3556080Y-86536D01*
X3557580Y-87869D01*
X3559330Y-88202D01*
X3561080Y-87535D01*
X3562830Y-85536D01*
G01X3404327Y4719D02*
Y24719D01*
X3401327Y20719D01*
G01Y4719D02*
X3407327D01*
G01X3418827Y7718D02*
X3420327Y6052D01*
X3422077Y5052D01*
X3424327Y4719D01*
X3426577Y5386D01*
X3428327Y6719D01*
X3429577Y9052D01*
X3429827Y11719D01*
X3429327Y14385D01*
X3428077Y16052D01*
X3426327Y17385D01*
X3424577Y17719D01*
X3422827Y17385D01*
X3420577Y16052D01*
X3421327Y24719D01*
X3428077D01*
G01X3439577Y13052D02*
X3441327Y15386D01*
X3442827Y16719D01*
X3444827Y17385D01*
X3446577Y16719D01*
X3447827Y15386D01*
X3448827Y13386D01*
X3449077Y11052D01*
X3448827Y9052D01*
X3447827Y7052D01*
X3446327Y5386D01*
X3444577Y4719D01*
X3442577Y5386D01*
X3440827Y7385D01*
X3439827Y10386D01*
X3439577Y13719D01*
X3440077Y18052D01*
X3440827Y20386D01*
X3442077Y22719D01*
X3443827Y24386D01*
X3445577Y24719D01*
X3447327Y24052D01*
X3448577Y22386D01*
G01X3459577Y13052D02*
X3461327Y15386D01*
X3462827Y16719D01*
X3464827Y17385D01*
X3466577Y16719D01*
X3467827Y15386D01*
X3468827Y13386D01*
X3469077Y11052D01*
X3468827Y9052D01*
X3467827Y7052D01*
X3466327Y5386D01*
X3464577Y4719D01*
X3462577Y5386D01*
X3460827Y7385D01*
X3459827Y10386D01*
X3459577Y13719D01*
X3460077Y18052D01*
X3460827Y20386D01*
X3462077Y22719D01*
X3463827Y24386D01*
X3465577Y24719D01*
X3467327Y24052D01*
X3468577Y22386D01*
G01X3480077Y7052D02*
X3481827Y5386D01*
X3483827Y4719D01*
X3485827Y5386D01*
X3487577Y7385D01*
X3488827Y10386D01*
X3489327Y13386D01*
Y17052D01*
X3488827Y20052D01*
X3487577Y22719D01*
X3486077Y24052D01*
X3484327Y24719D01*
X3482327Y24052D01*
X3480827Y22719D01*
X3479827Y20719D01*
X3479327Y18052D01*
X3479827Y15719D01*
X3481077Y13386D01*
X3482577Y12052D01*
X3484327Y11719D01*
X3486327Y12385D01*
X3487827Y14052D01*
X3489327Y17052D01*
G01X3576606Y-187269D02*
Y-179284D01*
X3575409Y-180881D01*
G01Y-187269D02*
X3577804D01*
G01X3584591D02*
X3585290Y-187136D01*
X3586089Y-186737D01*
X3586588Y-186072D01*
X3586787Y-185140D01*
X3586588Y-184208D01*
X3585989Y-183410D01*
X3585091Y-183010D01*
X3584092D01*
X3583493Y-182744D01*
X3582994Y-182079D01*
X3582795Y-181147D01*
X3583094Y-180216D01*
X3583793Y-179550D01*
X3584591Y-179284D01*
X3585390Y-179550D01*
X3586089Y-180216D01*
X3586388Y-181147D01*
X3586188Y-182079D01*
X3585690Y-182744D01*
X3585091Y-183010D01*
X3584092D01*
X3583194Y-183410D01*
X3582595Y-184208D01*
X3582396Y-185140D01*
X3582595Y-186072D01*
X3583094Y-186737D01*
X3583893Y-187136D01*
X3584591Y-187269D01*
G01X3576606Y2422250D02*
Y2430235D01*
X3575409Y2428638D01*
G01Y2422250D02*
X3577804D01*
G01X3584591D02*
X3585290Y2422383D01*
X3586089Y2422782D01*
X3586588Y2423447D01*
X3586787Y2424379D01*
X3586588Y2425311D01*
X3585989Y2426109D01*
X3585091Y2426509D01*
X3584092D01*
X3583493Y2426775D01*
X3582994Y2427440D01*
X3582795Y2428372D01*
X3583094Y2429303D01*
X3583793Y2429969D01*
X3584591Y2430235D01*
X3585390Y2429969D01*
X3586089Y2429303D01*
X3586388Y2428372D01*
X3586188Y2427440D01*
X3585690Y2426775D01*
X3585091Y2426509D01*
X3584092D01*
X3583194Y2426109D01*
X3582595Y2425311D01*
X3582396Y2424379D01*
X3582595Y2423447D01*
X3583094Y2422782D01*
X3583893Y2422383D01*
X3584591Y2422250D01*
G01X3716789Y-21469D02*
Y-41469D01*
G01X3711039Y-21469D02*
X3722539D01*
G01X3732539Y-41469D02*
Y-21469D01*
G01Y-31135D02*
X3733789Y-29469D01*
X3735039Y-28469D01*
X3737039Y-28136D01*
X3738539Y-28469D01*
X3740289Y-29802D01*
X3741039Y-31803D01*
Y-41469D01*
G01X3756789Y-28136D02*
Y-41469D01*
G01Y-22803D02*
X3756289Y-22469D01*
Y-21802D01*
X3756789Y-21469D01*
X3757289Y-21802D01*
Y-22469D01*
X3756789Y-22803D01*
G01X3780789Y-29802D02*
X3779039Y-28469D01*
X3777539Y-28136D01*
X3775539Y-28803D01*
X3774039Y-30136D01*
X3773039Y-32469D01*
X3772789Y-34803D01*
X3773039Y-37136D01*
X3774039Y-39136D01*
X3775539Y-40802D01*
X3777539Y-41469D01*
X3779289Y-40802D01*
X3780789Y-39469D01*
G01X3792539Y-41469D02*
Y-21469D01*
G01X3800539Y-28136D02*
X3792539Y-35802D01*
G01X3795789Y-32802D02*
X3801039Y-41469D01*
G01X3812539D02*
Y-28136D01*
G01Y-31469D02*
X3813539Y-29802D01*
X3815039Y-28469D01*
X3817039Y-28136D01*
X3818789Y-28469D01*
X3820289Y-29802D01*
X3821039Y-32136D01*
Y-41469D01*
G01X3833039Y-32469D02*
X3841039D01*
X3840289Y-30136D01*
X3839039Y-28803D01*
X3837289Y-28136D01*
X3835539Y-28469D01*
X3834039Y-29469D01*
X3833039Y-31803D01*
X3832539Y-33803D01*
Y-35802D01*
X3833039Y-37803D01*
X3834289Y-39803D01*
X3835789Y-41136D01*
X3837539Y-41469D01*
X3839289Y-40802D01*
X3841039Y-38803D01*
G01X3853039Y-39136D02*
X3854289Y-40469D01*
X3856039Y-41469D01*
X3857539D01*
X3859039Y-40802D01*
X3860039Y-39803D01*
X3860539Y-38470D01*
X3860289Y-36469D01*
X3859289Y-35469D01*
X3854789Y-33469D01*
X3853789Y-31135D01*
X3854289Y-29469D01*
X3855289Y-28469D01*
X3856789Y-28136D01*
X3858289Y-28469D01*
X3859789Y-29469D01*
G01X3873039Y-39136D02*
X3874289Y-40469D01*
X3876039Y-41469D01*
X3877539D01*
X3879039Y-40802D01*
X3880039Y-39803D01*
X3880539Y-38470D01*
X3880289Y-36469D01*
X3879289Y-35469D01*
X3874789Y-33469D01*
X3873789Y-31135D01*
X3874289Y-29469D01*
X3875289Y-28469D01*
X3876789Y-28136D01*
X3878289Y-28469D01*
X3879789Y-29469D01*
G01X3796275Y-187269D02*
Y-179284D01*
X3795078Y-180881D01*
G01Y-187269D02*
X3797473D01*
G01X3802564Y-186338D02*
X3803262Y-187003D01*
X3804061Y-187269D01*
X3804859Y-187003D01*
X3805558Y-186205D01*
X3806057Y-185007D01*
X3806257Y-183809D01*
Y-182345D01*
X3806057Y-181147D01*
X3805558Y-180083D01*
X3804959Y-179550D01*
X3804260Y-179284D01*
X3803462Y-179550D01*
X3802863Y-180083D01*
X3802464Y-180881D01*
X3802264Y-181946D01*
X3802464Y-182877D01*
X3802963Y-183809D01*
X3803562Y-184341D01*
X3804260Y-184474D01*
X3805059Y-184208D01*
X3805658Y-183543D01*
X3806257Y-182345D01*
G01X3753863Y-90177D02*
Y-70177D01*
X3758863D01*
X3760863Y-71177D01*
X3762363Y-72510D01*
X3763613Y-74510D01*
X3764613Y-76844D01*
X3764863Y-80177D01*
X3764613Y-83511D01*
X3763613Y-85844D01*
X3762363Y-87844D01*
X3760863Y-89177D01*
X3758863Y-90177D01*
X3753863D01*
G01X3783863D02*
Y-76844D01*
G01Y-79177D02*
X3782863Y-77844D01*
X3781363Y-77177D01*
X3779613Y-76844D01*
X3777863Y-77511D01*
X3776363Y-78844D01*
X3775363Y-80844D01*
X3774863Y-83511D01*
X3775363Y-86177D01*
X3776363Y-88177D01*
X3777863Y-89510D01*
X3779613Y-90177D01*
X3781363Y-89844D01*
X3782863Y-88844D01*
X3783863Y-87511D01*
G01X3799363Y-70177D02*
Y-90177D01*
G01X3795863Y-76844D02*
X3802863D01*
G01X3815613Y-81177D02*
X3823613D01*
X3822863Y-78844D01*
X3821613Y-77511D01*
X3819863Y-76844D01*
X3818113Y-77177D01*
X3816613Y-78177D01*
X3815613Y-80511D01*
X3815113Y-82511D01*
Y-84510D01*
X3815613Y-86511D01*
X3816863Y-88511D01*
X3818363Y-89844D01*
X3820113Y-90177D01*
X3821863Y-89510D01*
X3823613Y-87511D01*
G01X3796275Y2422250D02*
Y2430235D01*
X3795078Y2428638D01*
G01Y2422250D02*
X3797473D01*
G01X3802564Y2423181D02*
X3803262Y2422516D01*
X3804061Y2422250D01*
X3804859Y2422516D01*
X3805558Y2423314D01*
X3806057Y2424512D01*
X3806257Y2425710D01*
Y2427174D01*
X3806057Y2428372D01*
X3805558Y2429436D01*
X3804959Y2429969D01*
X3804260Y2430235D01*
X3803462Y2429969D01*
X3802863Y2429436D01*
X3802464Y2428638D01*
X3802264Y2427573D01*
X3802464Y2426642D01*
X3802963Y2425710D01*
X3803562Y2425178D01*
X3804260Y2425045D01*
X3805059Y2425311D01*
X3805658Y2425976D01*
X3806257Y2427174D01*
G01X3922032Y-71535D02*
X3923532Y-69536D01*
X3925282Y-68535D01*
X3927282Y-68202D01*
X3929782Y-68869D01*
X3931532Y-70535D01*
X3932032Y-72535D01*
X3931782Y-74536D01*
X3930782Y-76202D01*
X3925782Y-79535D01*
X3923532Y-81869D01*
X3922032Y-85203D01*
X3921532Y-88202D01*
X3932032D01*
G01X3946782Y-68202D02*
X3944782Y-68869D01*
X3943282Y-70535D01*
X3942282Y-72535D01*
X3941532Y-75202D01*
X3941282Y-78202D01*
X3941532Y-81202D01*
X3942282Y-83869D01*
X3943282Y-85869D01*
X3944782Y-87535D01*
X3946782Y-88202D01*
X3948782Y-87535D01*
X3950282Y-85869D01*
X3951282Y-83869D01*
X3952032Y-81202D01*
X3952282Y-78202D01*
X3952032Y-75202D01*
X3951282Y-72535D01*
X3950282Y-70535D01*
X3948782Y-68869D01*
X3946782Y-68202D01*
G01X3966782Y-88202D02*
Y-68202D01*
X3963782Y-72202D01*
G01Y-88202D02*
X3969782D01*
G01X3982032Y-79869D02*
X3983782Y-77535D01*
X3985282Y-76202D01*
X3987282Y-75536D01*
X3989032Y-76202D01*
X3990282Y-77535D01*
X3991282Y-79535D01*
X3991532Y-81869D01*
X3991282Y-83869D01*
X3990282Y-85869D01*
X3988782Y-87535D01*
X3987032Y-88202D01*
X3985032Y-87535D01*
X3983282Y-85536D01*
X3982282Y-82535D01*
X3982032Y-79202D01*
X3982532Y-74869D01*
X3983282Y-72535D01*
X3984532Y-70202D01*
X3986282Y-68535D01*
X3988032Y-68202D01*
X3989782Y-68869D01*
X3991032Y-70535D01*
G01X4003532Y-81536D02*
X4010032D01*
G01X4026782Y-68202D02*
X4024782Y-68869D01*
X4023282Y-70535D01*
X4022282Y-72535D01*
X4021532Y-75202D01*
X4021282Y-78202D01*
X4021532Y-81202D01*
X4022282Y-83869D01*
X4023282Y-85869D01*
X4024782Y-87535D01*
X4026782Y-88202D01*
X4028782Y-87535D01*
X4030282Y-85869D01*
X4031282Y-83869D01*
X4032032Y-81202D01*
X4032282Y-78202D01*
X4032032Y-75202D01*
X4031282Y-72535D01*
X4030282Y-70535D01*
X4028782Y-68869D01*
X4026782Y-68202D01*
G01X4041282Y-85203D02*
X4042782Y-86869D01*
X4044532Y-87869D01*
X4046782Y-88202D01*
X4049032Y-87535D01*
X4050782Y-86202D01*
X4052032Y-83869D01*
X4052282Y-81202D01*
X4051782Y-78536D01*
X4050532Y-76869D01*
X4048782Y-75536D01*
X4047032Y-75202D01*
X4045282Y-75536D01*
X4043032Y-76869D01*
X4043782Y-68202D01*
X4050532D01*
G01X4063532Y-81536D02*
X4070032D01*
G01X4082032Y-71535D02*
X4083532Y-69536D01*
X4085282Y-68535D01*
X4087282Y-68202D01*
X4089782Y-68869D01*
X4091532Y-70535D01*
X4092032Y-72535D01*
X4091782Y-74536D01*
X4090782Y-76202D01*
X4085782Y-79535D01*
X4083532Y-81869D01*
X4082032Y-85203D01*
X4081532Y-88202D01*
X4092032D01*
G01X4101282Y-85203D02*
X4102782Y-86869D01*
X4104532Y-87869D01*
X4106782Y-88202D01*
X4109032Y-87535D01*
X4110782Y-86202D01*
X4112032Y-83869D01*
X4112282Y-81202D01*
X4111782Y-78536D01*
X4110532Y-76869D01*
X4108782Y-75536D01*
X4107032Y-75202D01*
X4105282Y-75536D01*
X4103032Y-76869D01*
X4103782Y-68202D01*
X4110532D01*
G01X3929926Y-22827D02*
X3931426Y-20828D01*
X3933176Y-19827D01*
X3935176Y-19494D01*
X3937676Y-20161D01*
X3939426Y-21827D01*
X3939926Y-23827D01*
X3939676Y-25828D01*
X3938676Y-27494D01*
X3933676Y-30827D01*
X3931426Y-33161D01*
X3929926Y-36495D01*
X3929426Y-39494D01*
X3939926D01*
G01X3954676Y-40161D02*
X3954176Y-39827D01*
Y-39161D01*
X3954676Y-38827D01*
X3955176Y-39161D01*
Y-39827D01*
X3954676Y-40161D01*
G01X3974676Y-39494D02*
Y-19494D01*
X3971676Y-23494D01*
G01Y-39494D02*
X3977676D01*
G01X3989926Y-31161D02*
X3991676Y-28827D01*
X3993176Y-27494D01*
X3995176Y-26828D01*
X3996926Y-27494D01*
X3998176Y-28827D01*
X3999176Y-30827D01*
X3999426Y-33161D01*
X3999176Y-35161D01*
X3998176Y-37161D01*
X3996676Y-38827D01*
X3994926Y-39494D01*
X3992926Y-38827D01*
X3991176Y-36828D01*
X3990176Y-33827D01*
X3989926Y-30494D01*
X3990426Y-26161D01*
X3991176Y-23827D01*
X3992426Y-21494D01*
X3994176Y-19827D01*
X3995926Y-19494D01*
X3997676Y-20161D01*
X3998926Y-21827D01*
G01X4007176Y-39494D02*
Y-26161D01*
G01Y-29828D02*
X4007926Y-28161D01*
X4009176Y-26828D01*
X4010926Y-26161D01*
X4012676Y-26828D01*
X4013926Y-28161D01*
X4014676Y-29828D01*
Y-39494D01*
G01Y-29828D02*
X4015426Y-28161D01*
X4016676Y-26828D01*
X4018426Y-26161D01*
X4020176Y-26828D01*
X4021426Y-28161D01*
X4022176Y-30161D01*
Y-39494D01*
G01X4027176D02*
Y-26161D01*
G01Y-29828D02*
X4027926Y-28161D01*
X4029176Y-26828D01*
X4030926Y-26161D01*
X4032676Y-26828D01*
X4033926Y-28161D01*
X4034676Y-29828D01*
Y-39494D01*
G01Y-29828D02*
X4035426Y-28161D01*
X4036676Y-26828D01*
X4038426Y-26161D01*
X4040176Y-26828D01*
X4041426Y-28161D01*
X4042176Y-30161D01*
Y-39494D01*
G01X4014048Y-180615D02*
X4014647Y-179816D01*
X4015346Y-179417D01*
X4016144Y-179284D01*
X4017142Y-179550D01*
X4017841Y-180216D01*
X4018041Y-181014D01*
X4017941Y-181813D01*
X4017541Y-182478D01*
X4015545Y-183809D01*
X4014647Y-184740D01*
X4014048Y-186072D01*
X4013848Y-187269D01*
X4018041D01*
G01X4023929Y-179284D02*
X4023131Y-179550D01*
X4022532Y-180216D01*
X4022133Y-181014D01*
X4021833Y-182079D01*
X4021734Y-183277D01*
X4021833Y-184474D01*
X4022133Y-185539D01*
X4022532Y-186338D01*
X4023131Y-187003D01*
X4023929Y-187269D01*
X4024728Y-187003D01*
X4025327Y-186338D01*
X4025726Y-185539D01*
X4026026Y-184474D01*
X4026125Y-183277D01*
X4026026Y-182079D01*
X4025726Y-181014D01*
X4025327Y-180216D01*
X4024728Y-179550D01*
X4023929Y-179284D01*
G01X4014048Y2428904D02*
X4014647Y2429703D01*
X4015346Y2430102D01*
X4016144Y2430235D01*
X4017142Y2429969D01*
X4017841Y2429303D01*
X4018041Y2428505D01*
X4017941Y2427706D01*
X4017541Y2427041D01*
X4015545Y2425710D01*
X4014647Y2424779D01*
X4014048Y2423447D01*
X4013848Y2422250D01*
X4018041D01*
G01X4023929Y2430235D02*
X4023131Y2429969D01*
X4022532Y2429303D01*
X4022133Y2428505D01*
X4021833Y2427440D01*
X4021734Y2426242D01*
X4021833Y2425045D01*
X4022133Y2423980D01*
X4022532Y2423181D01*
X4023131Y2422516D01*
X4023929Y2422250D01*
X4024728Y2422516D01*
X4025327Y2423181D01*
X4025726Y2423980D01*
X4026026Y2425045D01*
X4026125Y2426242D01*
X4026026Y2427440D01*
X4025726Y2428505D01*
X4025327Y2429303D01*
X4024728Y2429969D01*
X4023929Y2430235D01*
G01X4137038Y-61874D02*
Y-69859D01*
X4141031D01*
G01X4136839Y146022D02*
Y154007D01*
G01X4140631D02*
X4136839Y149083D01*
G01X4141230Y146022D02*
X4138535Y151345D01*
G01X4136849Y363502D02*
X4137348Y362703D01*
X4137947Y362171D01*
X4138646Y361905D01*
X4139444Y362171D01*
X4140043Y362703D01*
X4140642Y363502D01*
X4140842Y364567D01*
Y369890D01*
G01X4137648Y585772D02*
X4140043D01*
G01X4138845D02*
Y577787D01*
G01X4137648D02*
X4140043D01*
G01X4136749Y793478D02*
Y801463D01*
G01X4140942D02*
Y793478D01*
G01Y797470D02*
X4136749D01*
G01X4139444Y1013353D02*
X4141441D01*
Y1010958D01*
X4140842Y1010159D01*
X4140143Y1009627D01*
X4139145Y1009361D01*
X4138147Y1009627D01*
X4137448Y1010159D01*
X4136849Y1010958D01*
X4136450Y1011890D01*
X4136250Y1012954D01*
Y1013886D01*
X4136450Y1014684D01*
X4136849Y1015616D01*
X4137448Y1016414D01*
X4138047Y1016947D01*
X4138845Y1017346D01*
X4139544D01*
X4140343Y1017080D01*
X4140942Y1016547D01*
G01X4136570Y1225433D02*
Y1233418D01*
X4140363D01*
G01X4138966Y1229559D02*
X4136570D01*
G01X4140842Y1441504D02*
X4136849D01*
Y1449489D01*
X4140842D01*
G01X4139245Y1445630D02*
X4136849D01*
G01X4136650Y1657196D02*
Y1665181D01*
X4138646D01*
X4139444Y1664782D01*
X4140043Y1664249D01*
X4140542Y1663451D01*
X4140942Y1662519D01*
X4141041Y1661188D01*
X4140942Y1659858D01*
X4140542Y1658926D01*
X4140043Y1658127D01*
X4139444Y1657595D01*
X4138646Y1657196D01*
X4136650D01*
G01X4141041Y1880587D02*
X4140442Y1880987D01*
X4139744Y1881253D01*
X4138945D01*
X4138047Y1880854D01*
X4137348Y1880188D01*
X4136849Y1879390D01*
X4136450Y1878059D01*
X4136350Y1876861D01*
X4136550Y1875663D01*
X4136849Y1874865D01*
X4137448Y1874066D01*
X4138147Y1873534D01*
X4138845Y1873268D01*
X4139544D01*
X4140243Y1873534D01*
X4140842Y1873933D01*
X4141341Y1874465D01*
G01X4139644Y2093218D02*
X4140043Y2093617D01*
X4140343Y2094282D01*
X4140542Y2095214D01*
X4140343Y2096012D01*
X4139944Y2096545D01*
X4139245Y2096944D01*
X4136550D01*
Y2088959D01*
X4139844D01*
X4140542Y2089491D01*
X4140942Y2090290D01*
X4141141Y2091221D01*
X4140942Y2092153D01*
X4140343Y2092951D01*
X4139644Y2093218D01*
X4136550D01*
G01X4136350Y2304841D02*
X4138845Y2312826D01*
X4141341Y2304841D01*
G01X4140442Y2307636D02*
X4137248D01*
G01X-287643Y-191056D02*
Y2437400D01*
G01X4149296Y-191056D02*
X-287643D01*
G01X-268706Y-172119D02*
Y2418463D01*
G01X4130359Y-172119D02*
X-268706D01*
G01X-287643Y43763D02*
X-268706D01*
G01X-287643Y259644D02*
X-268706D01*
G01X-287643Y475526D02*
X-268706D01*
G01X-287643Y691409D02*
X-268706D01*
G01X-287643D02*
X-268706D01*
G01X-287643Y907291D02*
X-268706D01*
G01X-287643D02*
X-268706D01*
G01X-287643Y1123172D02*
X-268706D01*
G01X-287643D02*
X-268706D01*
G01X-287643Y1339055D02*
X-268706D01*
G01X-287643D02*
X-268706D01*
G01X-287643D02*
X-268706D01*
G01X-287643Y1554935D02*
X-268706D01*
G01X-287643D02*
X-268706D01*
G01X-287643Y1770818D02*
X-268706D01*
G01X-287643D02*
X-268706D01*
G01X-287643Y1986700D02*
X-268706D01*
G01X-287643D02*
X-268706D01*
G01X-287643Y2202582D02*
X-268706D01*
G01Y2418463D02*
X4130359D01*
G01X-287643Y2437400D02*
X4149296D01*
G01X-171080Y27181D02*
Y32181D01*
X-168546D01*
G01X-169480Y29764D02*
X-171080D01*
G01X-165213Y30514D02*
Y27181D01*
G01Y31848D02*
X-165346Y31931D01*
Y32098D01*
X-165213Y32181D01*
X-165080Y32098D01*
Y31931D01*
X-165213Y31848D01*
G01X-159413Y32181D02*
Y27181D01*
G01Y27931D02*
X-159680Y27514D01*
X-160080Y27264D01*
X-160546Y27181D01*
X-161080Y27348D01*
X-161480Y27764D01*
X-161746Y28264D01*
X-161813Y28848D01*
X-161746Y29431D01*
X-161480Y29931D01*
X-161080Y30348D01*
X-160546Y30514D01*
X-160080Y30431D01*
X-159746Y30264D01*
X-159413Y29931D01*
G01X-157146Y30514D02*
Y28181D01*
X-156880Y27598D01*
X-156480Y27264D01*
X-156013Y27181D01*
X-155546Y27264D01*
X-155146Y27598D01*
X-154880Y28181D01*
G01Y27181D02*
Y30514D01*
G01X-150346Y30098D02*
X-150813Y30431D01*
X-151213Y30514D01*
X-151746Y30348D01*
X-152146Y30014D01*
X-152413Y29431D01*
X-152480Y28848D01*
X-152413Y28264D01*
X-152146Y27764D01*
X-151746Y27348D01*
X-151213Y27181D01*
X-150746Y27348D01*
X-150346Y27681D01*
G01X-146813Y30514D02*
Y27181D01*
G01Y31848D02*
X-146946Y31931D01*
Y32098D01*
X-146813Y32181D01*
X-146680Y32098D01*
Y31931D01*
X-146813Y31848D01*
G01X-141013Y27181D02*
Y30514D01*
G01Y29931D02*
X-141280Y30264D01*
X-141680Y30431D01*
X-142146Y30514D01*
X-142613Y30348D01*
X-143013Y30014D01*
X-143280Y29514D01*
X-143413Y28848D01*
X-143280Y28181D01*
X-143013Y27681D01*
X-142613Y27348D01*
X-142146Y27181D01*
X-141680Y27264D01*
X-141280Y27514D01*
X-141013Y27848D01*
G01X-137613Y27181D02*
Y32181D01*
G01X-130146Y27181D02*
Y32181D01*
X-128413Y28014D01*
X-126680Y32181D01*
Y27181D01*
G01X-122613D02*
Y30514D01*
G01Y29931D02*
X-122880Y30264D01*
X-123280Y30431D01*
X-123746Y30514D01*
X-124213Y30348D01*
X-124613Y30014D01*
X-124880Y29514D01*
X-125013Y28848D01*
X-124880Y28181D01*
X-124613Y27681D01*
X-124213Y27348D01*
X-123746Y27181D01*
X-123280Y27264D01*
X-122880Y27514D01*
X-122613Y27848D01*
G01X-120146Y27181D02*
Y30514D01*
G01Y29848D02*
X-119813Y30181D01*
X-119480Y30431D01*
X-119013Y30514D01*
X-118680Y30431D01*
X-118280Y30181D01*
G01X-115746Y27181D02*
Y32181D01*
G01X-113613Y30514D02*
X-115746Y28598D01*
G01X-114880Y29348D02*
X-113480Y27181D01*
G01X-106413Y30514D02*
X-104413Y27181D01*
G01Y30514D02*
X-106413Y27181D01*
G01X-97680Y28181D02*
X-97280Y27598D01*
X-96746Y27264D01*
X-96146Y27181D01*
X-95613Y27264D01*
X-95080Y27681D01*
X-94746Y28181D01*
X-94680Y28681D01*
X-94813Y29264D01*
X-95280Y29681D01*
X-95746Y29848D01*
X-96346D01*
G01X-95746D02*
X-95346Y30098D01*
X-95013Y30514D01*
X-94880Y31014D01*
X-95013Y31514D01*
X-95346Y31931D01*
X-95946Y32181D01*
X-96546Y32098D01*
X-97146Y31764D01*
G01X-67678Y0D02*
X-117853D01*
G01X-67678Y1992126D02*
X-126659D01*
G01X-43355Y-172119D02*
Y-191056D01*
G01X-7874Y534024D02*
X-75552D01*
G03X-90552Y519024I0J-15000D01*
G01Y15000D01*
G03X-75552Y0I15000J0D01*
G01X-7874D01*
G01X-59449Y15000D02*
G03I-4292J0D01*
G01X-68379Y36739D02*
X-104579D01*
G01X-53164Y51954D02*
X-68379Y36739D01*
G01X-53164Y51954D02*
X-56699Y44884D01*
G01D02*
X-60234Y48419D01*
G01X-45168Y52138D02*
G03I-4000J0D01*
G01X-47168D02*
G03I-2000J0D01*
G01X-60234Y48419D02*
X-53164Y51954D01*
G01X-56299Y596228D02*
Y587173D01*
G01X-30709D02*
X-56299D01*
G01X0Y596228D02*
X-62205D01*
G01Y580480D02*
X-60236Y578512D01*
G01X-62205Y596228D02*
Y576543D01*
G01X-60236Y578512D02*
Y576543D01*
G01X-9055D02*
X-62205D01*
G01X-9055Y578512D02*
X-60236D01*
G01X-9055Y581268D02*
X-62205D01*
G01X-56299Y587173D02*
X-62205Y583763D01*
G01Y944260D02*
Y924575D01*
G01X-60236Y944260D02*
Y942291D01*
G01X-56299Y933630D02*
Y924575D01*
G01X-60236Y942291D02*
X-62205Y940323D01*
G01Y937039D02*
X-56299Y933630D01*
G01X0Y924575D02*
X-62205D01*
G01X-30709Y933630D02*
X-56299D01*
G01X-9055Y942291D02*
X-60236D01*
G01X-9055Y944260D02*
X-62205D01*
G01X-7874Y1030087D02*
X-75552D01*
G03X-90552Y1015087I0J-15000D01*
G01Y1001780D01*
G03X-75552Y986780I15000J0D01*
G01X-7874D01*
G01X-38048Y1008909D02*
G03I-4291J0D01*
G01X-62205Y1092291D02*
Y1072606D01*
G01X-60236Y1074575D02*
Y1072606D01*
G01X-56299Y1092291D02*
Y1083236D01*
G01D02*
X-62205Y1079826D01*
G01Y1076543D02*
X-60236Y1074575D01*
G01X-9055Y1072606D02*
X-62205D01*
G01X-9055Y1074575D02*
X-60236D01*
G01X-9055Y1077331D02*
X-62205D01*
G01X-30709Y1083236D02*
X-56299D01*
G01X0Y1092291D02*
X-62205D01*
G01Y1433102D02*
X-56299Y1429693D01*
G01X-30709D02*
X-56299D01*
G01X-62205Y1440323D02*
Y1420638D01*
G01X-56299Y1429693D02*
Y1420638D01*
G01X0D02*
X-62205D01*
G01X-60236Y1438354D02*
X-62205Y1436386D01*
G01X-60236Y1440323D02*
Y1438354D01*
G01X-9055D02*
X-60236D01*
G01X-9055Y1440323D02*
X-62205D01*
G01X-56299Y1500559D02*
X-62205Y1497149D01*
G01Y1509614D02*
Y1489929D01*
G01X-60236Y1491898D02*
Y1489929D01*
G01X-56299Y1509614D02*
Y1500559D01*
G01X-62205Y1493866D02*
X-60236Y1491898D01*
G01X-9055Y1489929D02*
X-62205D01*
G01X-9055Y1491898D02*
X-60236D01*
G01X-9055Y1494654D02*
X-62205D01*
G01X-30709Y1500559D02*
X-56299D01*
G01X0Y1509614D02*
X-62205D01*
G01X-60236Y1855677D02*
X-62205Y1853709D01*
G01X-60236Y1857646D02*
Y1855677D01*
G01X-62205Y1850425D02*
X-56299Y1847016D01*
G01X-30709D02*
X-56299D01*
G01X-9055Y1855677D02*
X-60236D01*
G01X-9055Y1857646D02*
X-62205D01*
G01D02*
Y1837961D01*
G01X-56299Y1847016D02*
Y1837961D01*
G01X0D02*
X-62205D01*
G01X-7874Y1992126D02*
X-75552D01*
G03X-90552Y1977126I0J-15000D01*
G01Y1915165D01*
G03X-75552Y1900165I15000J0D01*
G01X-7874D01*
G01X-90552Y1977126D02*
Y2042196D01*
G01X-59449Y1977126D02*
G03I-4292J0D01*
G01X-43355Y2437400D02*
Y2418463D01*
G01X1023227Y1618051D02*
Y1675945D01*
G02X1028700Y1681417I5472J0D01*
G01X1033464D01*
X1037401Y1685354D01*
Y1988189D01*
G03X1033464Y1992126I-3937J0D01*
G01X3936D01*
G03X-1Y1988189I0J-3937D01*
G01Y1661189D01*
X1968Y1659220D01*
X17322D01*
G02Y1650559I0J-4331D01*
G01X1968D01*
X-1Y1648591D01*
Y1243866D01*
X1968Y1241898D01*
X17322D01*
G02Y1233236I0J-4331D01*
G01X1968D01*
X-1Y1231268D01*
Y747803D01*
X1968Y745835D01*
X17322D01*
G02Y737173I0J-4331D01*
G01X1968D01*
X-1Y735205D01*
Y3937D01*
G03X3936Y0I3937J0D01*
G01X121259D01*
X127309Y11888D01*
G03X127952Y14567I-5263J2680D01*
G01Y17717D01*
G02X139763I5906J0D01*
G01Y14567D01*
G03X140405Y11888I5906J-1D01*
G01X146456Y0D01*
X1033464D01*
G03X1037401Y3937I0J3937D01*
G01Y1424882D01*
X1033464Y1428819D01*
X1028700D01*
G02X1023227Y1434291I0J5473D01*
G01Y1609902D01*
X1021259Y1611870D01*
X993680D01*
G02Y1616083I0J2107D01*
G01X1021259D01*
X1023227Y1618051D01*
G01X35827Y28720D02*
X40551Y24075D01*
G01X35827Y29824D02*
X40547Y25182D01*
G01X35827Y28720D02*
Y30453D01*
G01X39236Y32421D02*
X35827Y30453D01*
G01X0Y0D02*
X1134D01*
G01X0D02*
Y1134D01*
G01X-7874Y8350D02*
Y0D01*
G01Y251657D02*
Y39059D01*
G01D02*
G03X0I3937J0D01*
G01Y8350D02*
G03X-7874I-3937J0D01*
G01X39236Y174902D02*
X35827Y176870D01*
G01D02*
Y178602D01*
G01D02*
X40551Y183248D01*
G01X40547Y182141D02*
X35827Y177499D01*
G01X26441Y274602D02*
G03X40499I7029J-6890D01*
G01X17722Y267712D02*
G03X49218I15748J0D01*
G01X17722D02*
G03X49218I15748J0D01*
G01X17722D02*
G03X49218I15748J0D01*
G01X0Y251657D02*
G03X-7874I-3937J0D01*
G01X39373Y281491D02*
G03X27567I-5903J0D01*
G01X39375D02*
G03X27564I-5905J0D01*
G01X41344D02*
G03X25596I-7874J0D01*
G01X47249D02*
G03X19690I-13780J0D01*
G01X49218D02*
G03X17722I-15748J0D01*
G01X49218D02*
G03X17722I-15748J0D01*
G01X49218D02*
G03X17722I-15748J0D01*
G01X24415D02*
G03I-984J0D01*
G01X26441Y274602D02*
G03X27567Y277358I-2811J2756D01*
G01Y281491D02*
Y277358D01*
G01X27564Y279129D02*
Y281491D01*
G01X25596D02*
Y279129D01*
G01X19690Y281491D02*
Y279129D01*
G01X17722Y267712D02*
Y281491D01*
G01Y267712D02*
Y281491D01*
G01Y267712D02*
Y281491D01*
G01X19690Y279129D02*
X27564D01*
G01X39474Y290186D02*
G03I-984J0D01*
G01X29434D02*
G03I-984J0D01*
G01X25760Y286511D02*
G03I-984J0D01*
G01X-7874Y494965D02*
Y282366D01*
G01D02*
G03X0I3937J0D01*
G01X35827Y434232D02*
X40551Y429587D01*
G01X35827Y435335D02*
X40547Y430694D01*
G01X35827Y434232D02*
Y435965D01*
G01X39236Y437933D02*
X35827Y435965D01*
G01X-7874Y525673D02*
G03X0I3937J0D01*
G01Y494965D02*
G03X-7874I-3937J0D01*
G01Y534024D02*
Y525673D01*
G01X17709Y597026D02*
X17392Y597291D01*
G01X17754D02*
X18071Y597026D01*
G01X12057Y598787D02*
X12287Y598531D01*
G01X12057Y601937D02*
X12287Y601681D01*
G01X12057Y605087D02*
X12287Y604831D01*
G01X12057Y608236D02*
X12287Y607980D01*
G01X12057Y611386D02*
X12287Y611130D01*
G01X12057Y614535D02*
X12287Y614280D01*
G01X12057Y617685D02*
X12287Y617429D01*
G01X12057Y620835D02*
X12287Y620579D01*
G01X12057Y623984D02*
X12287Y623728D01*
G01X12416Y598802D02*
X12634Y598531D01*
G01X12416Y601951D02*
X12634Y601681D01*
G01X12416Y605101D02*
X12634Y604831D01*
G01X12416Y608250D02*
X12634Y607980D01*
G01X12416Y611400D02*
X12634Y611130D01*
G01X12416Y614550D02*
X12634Y614280D01*
G01X12416Y617699D02*
X12634Y617429D01*
G01X12416Y620849D02*
X12634Y620579D01*
G01X12416Y623998D02*
X12634Y623728D01*
G01X16487Y598974D02*
X15945Y599152D01*
G01X16669Y598930D02*
X17890Y598531D01*
G01X15945Y599417D02*
X18071Y598709D01*
G01X12057Y623984D02*
Y622803D01*
G01Y620835D02*
Y619654D01*
G01Y614535D02*
Y613354D01*
G01Y617685D02*
Y616504D01*
G01Y611386D02*
Y610205D01*
G01Y605087D02*
Y603906D01*
G01Y608236D02*
Y607055D01*
G01Y601937D02*
Y600756D01*
G01Y598787D02*
Y597606D01*
G01X12410Y623984D02*
Y622803D01*
G01Y620835D02*
Y619654D01*
G01Y614535D02*
Y613354D01*
G01Y617685D02*
Y616504D01*
G01Y611386D02*
Y610205D01*
G01Y605087D02*
Y603906D01*
G01Y608236D02*
Y607055D01*
G01Y601937D02*
Y600756D01*
G01Y598787D02*
Y597606D01*
G01X13353Y623728D02*
Y623059D01*
G01Y620579D02*
Y619909D01*
G01Y614280D02*
Y613610D01*
G01Y617429D02*
Y616760D01*
G01Y611130D02*
Y610461D01*
G01Y607980D02*
Y607311D01*
G01Y601681D02*
Y601012D01*
G01Y604831D02*
Y604161D01*
G01Y598531D02*
Y597862D01*
G01X13701Y623728D02*
Y623059D01*
G01Y620579D02*
Y619909D01*
G01Y614280D02*
Y613610D01*
G01Y617429D02*
Y616760D01*
G01Y611130D02*
Y610461D01*
G01Y607980D02*
Y607311D01*
G01Y601681D02*
Y601012D01*
G01Y604831D02*
Y604161D01*
G01Y598531D02*
Y597862D01*
G01X13780Y599181D02*
Y597213D01*
G01X15945Y599152D02*
Y599417D01*
G01Y597646D02*
Y597911D01*
G01Y596760D02*
Y597026D01*
G01X16487Y598089D02*
Y598974D01*
G01X16669Y598133D02*
Y598930D01*
G01X18071Y598709D02*
Y598354D01*
G01Y597026D02*
Y596760D01*
G01D02*
X15945D01*
G01Y597026D02*
X17709D01*
G01X17392Y597291D02*
X17754D01*
G01X13701Y597862D02*
X12287D01*
G01X13701Y598531D02*
X12287D01*
G01X13701Y601012D02*
X12287D01*
G01X13701Y601681D02*
X12287D01*
G01X13701Y604161D02*
X12287D01*
G01X13701Y604831D02*
X12287D01*
G01X13701Y607311D02*
X12287D01*
G01X13701Y607980D02*
X12287D01*
G01X13701Y610461D02*
X12287D01*
G01X13701Y611130D02*
X12287D01*
G01X13701Y613610D02*
X12287D01*
G01X13701Y614280D02*
X12287D01*
G01X13701Y616760D02*
X12287D01*
G01X13701Y617429D02*
X12287D01*
G01X13701Y619909D02*
X12287D01*
G01X13701Y620579D02*
X12287D01*
G01X13701Y623059D02*
X12287D01*
G01X13701Y623728D02*
X12287D01*
G01X12634Y623059D02*
X12416Y622789D01*
G01X12634Y619909D02*
X12416Y619639D01*
G01X12634Y616760D02*
X12416Y616490D01*
G01X12634Y613610D02*
X12416Y613340D01*
G01X12634Y610461D02*
X12416Y610191D01*
G01X12634Y607311D02*
X12416Y607041D01*
G01X12634Y604161D02*
X12416Y603891D01*
G01X12634Y601012D02*
X12416Y600742D01*
G01X12634Y597862D02*
X12416Y597592D01*
G01X12287Y623059D02*
X12057Y622803D01*
G01X12287Y619909D02*
X12057Y619654D01*
G01X12287Y616760D02*
X12057Y616504D01*
G01X12287Y613610D02*
X12057Y613354D01*
G01X12287Y610461D02*
X12057Y610205D01*
G01X12287Y607311D02*
X12057Y607055D01*
G01X12287Y604161D02*
X12057Y603906D01*
G01X12287Y601012D02*
X12057Y600756D01*
G01X12287Y597862D02*
X12057Y597606D01*
G01X18071Y598354D02*
X15945Y597646D01*
G01Y597911D02*
X16487Y598089D01*
G01X17890Y598531D02*
X16669Y598133D01*
G01X12057Y627134D02*
X12287Y626878D01*
G01X12416Y627148D02*
X12634Y626878D01*
G01X12057Y630283D02*
Y629102D01*
G01Y627134D02*
Y625953D01*
G01X12410Y630283D02*
Y629102D01*
G01Y627134D02*
Y625953D01*
G01X13353Y630028D02*
Y629358D01*
G01Y626878D02*
Y626209D01*
G01X13701Y630028D02*
Y629358D01*
G01Y626878D02*
Y626209D01*
G01D02*
X12287D01*
G01X13701Y626878D02*
X12287D01*
G01X13701Y629358D02*
X12287D01*
G01X12634D02*
X12416Y629088D01*
G01X12634Y626209D02*
X12416Y625939D01*
G01X12287Y629358D02*
X12057Y629102D01*
G01X12287Y626209D02*
X12057Y625953D01*
G01X22441Y587173D02*
Y557646D01*
G01Y567094D02*
X11811D01*
G01X22441Y575756D02*
X11811D01*
G01X11861Y567094D02*
G03Y575756I-50J4331D01*
G01X39236Y580413D02*
X35827Y582382D01*
G01D02*
Y584114D01*
G01D02*
X40551Y588760D01*
G01X40547Y587652D02*
X35827Y583011D01*
G01X-30709Y599772D02*
X-27981Y598197D01*
G01X-14677Y597705D02*
X-14537Y597617D01*
G01X-14449Y597705D02*
X-13977Y597409D01*
G01X-14677Y600854D02*
X-14537Y600767D01*
G01X-14449Y600854D02*
X-13977Y600559D01*
G01X-14677Y604004D02*
X-14537Y603916D01*
G01X-14449Y604004D02*
X-13977Y603709D01*
G01X-14677Y607154D02*
X-14537Y607066D01*
G01X-14449Y607154D02*
X-13977Y606858D01*
G01X-14677Y610303D02*
X-14537Y610215D01*
G01X-14449Y610303D02*
X-13977Y610008D01*
G01X-14677Y613453D02*
X-14537Y613365D01*
G01X-14449Y613453D02*
X-13977Y613157D01*
G01X0Y591110D02*
X3937Y587173D01*
G01X-30709Y924575D02*
Y596228D01*
G01Y592291D02*
Y587173D01*
G01X-26772Y737567D02*
Y596228D01*
G01X-20801Y623822D02*
Y622966D01*
G01Y620672D02*
Y619816D01*
G01Y614373D02*
Y613517D01*
G01Y617522D02*
Y616667D01*
G01Y611223D02*
Y610367D01*
G01Y604924D02*
Y604068D01*
G01Y608074D02*
Y607218D01*
G01Y601774D02*
Y600919D01*
G01Y598625D02*
Y597769D01*
G01X-19469Y623828D02*
Y622960D01*
G01Y620678D02*
Y619810D01*
G01Y614379D02*
Y613511D01*
G01Y617528D02*
Y616661D01*
G01Y611229D02*
Y610361D01*
G01Y604930D02*
Y604062D01*
G01Y608080D02*
Y607212D01*
G01Y601780D02*
Y600913D01*
G01Y598631D02*
Y597763D01*
G01X-18435Y623848D02*
Y622939D01*
G01Y620698D02*
Y619790D01*
G01Y614399D02*
Y613491D01*
G01Y617548D02*
Y616640D01*
G01Y611249D02*
Y610341D01*
G01Y604950D02*
Y604042D01*
G01Y608100D02*
Y607191D01*
G01Y601800D02*
Y600892D01*
G01Y598651D02*
Y597743D01*
G01X-18174Y623848D02*
Y622939D01*
G01Y620698D02*
Y619790D01*
G01Y614399D02*
Y613491D01*
G01Y617548D02*
Y616640D01*
G01Y611249D02*
Y610341D01*
G01Y604950D02*
Y604042D01*
G01Y608100D02*
Y607191D01*
G01Y601800D02*
Y600892D01*
G01Y598651D02*
Y597743D01*
G01X-16213Y623869D02*
Y622918D01*
G01Y620720D02*
Y619768D01*
G01Y614420D02*
Y613469D01*
G01Y617570D02*
Y616619D01*
G01Y611271D02*
Y610319D01*
G01Y604972D02*
Y604020D01*
G01Y608121D02*
Y607170D01*
G01Y601822D02*
Y600870D01*
G01Y598672D02*
Y597721D01*
G01X-15985Y623869D02*
Y622918D01*
G01Y620720D02*
Y619768D01*
G01Y614420D02*
Y613469D01*
G01Y617570D02*
Y616619D01*
G01Y611271D02*
Y610319D01*
G01Y604972D02*
Y604020D01*
G01Y608121D02*
Y607170D01*
G01Y601822D02*
Y600870D01*
G01Y598672D02*
Y597721D01*
G01X-14537Y597617D02*
X-14147Y597409D01*
G01X-14537Y600767D02*
X-14147Y600559D01*
G01X-14537Y603916D02*
X-14147Y603709D01*
G01X-14537Y607066D02*
X-14147Y606858D01*
G01X-14537Y610215D02*
X-14147Y610008D01*
G01X-14537Y613365D02*
X-14147Y613157D01*
G01X-14537Y616515D02*
X-14147Y616307D01*
G01X-14537Y619664D02*
X-14147Y619457D01*
G01X-14537Y622814D02*
X-14147Y622606D01*
G01X-14677Y616602D02*
X-14537Y616515D01*
G01X-14449Y616602D02*
X-13977Y616307D01*
G01X-14677Y619752D02*
X-14537Y619664D01*
G01X-14449Y619752D02*
X-13977Y619457D01*
G01X-14677Y622902D02*
X-14537Y622814D01*
G01X-14449Y622902D02*
X-13977Y622606D01*
G01X-14537Y623974D02*
Y622814D01*
G01Y620824D02*
Y619664D01*
G01Y614525D02*
Y613365D01*
G01Y617674D02*
Y616515D01*
G01Y611375D02*
Y610215D01*
G01Y605076D02*
Y603916D01*
G01Y608226D02*
Y607066D01*
G01Y601926D02*
Y600767D01*
G01Y598777D02*
Y597617D01*
G01X-13009Y624181D02*
Y622606D01*
G01Y621031D02*
Y619457D01*
G01Y614732D02*
Y613157D01*
G01Y617882D02*
Y616307D01*
G01Y611583D02*
Y610008D01*
G01Y605283D02*
Y603709D01*
G01Y608433D02*
Y606858D01*
G01Y602134D02*
Y600559D01*
G01Y598984D02*
Y597409D01*
G01X-7283Y737567D02*
Y594260D01*
G01X315Y624575D02*
Y623984D01*
G01Y621425D02*
Y620835D01*
G01Y619654D02*
Y619063D01*
G01Y622803D02*
Y622213D01*
G01Y615126D02*
Y614535D01*
G01Y618276D02*
Y617685D01*
G01Y616504D02*
Y615913D01*
G01Y611976D02*
Y611386D01*
G01Y610205D02*
Y609614D01*
G01Y613354D02*
Y612764D01*
G01Y605677D02*
Y605087D01*
G01Y608827D02*
Y608236D01*
G01Y607055D02*
Y606465D01*
G01Y602528D02*
Y601937D01*
G01Y600756D02*
Y600165D01*
G01Y603906D02*
Y603315D01*
G01Y599378D02*
Y598787D01*
G01Y597606D02*
Y597016D01*
G01X512Y624575D02*
Y623984D01*
G01Y621425D02*
Y620835D01*
G01Y619654D02*
Y619063D01*
G01Y622803D02*
Y622213D01*
G01Y615126D02*
Y614535D01*
G01Y618276D02*
Y617685D01*
G01Y616504D02*
Y615913D01*
G01Y611976D02*
Y611386D01*
G01Y610205D02*
Y609614D01*
G01Y613354D02*
Y612764D01*
G01Y605677D02*
Y605087D01*
G01Y608827D02*
Y608236D01*
G01Y607055D02*
Y606465D01*
G01Y602528D02*
Y601937D01*
G01Y600756D02*
Y600165D01*
G01Y603906D02*
Y603315D01*
G01Y599378D02*
Y598787D01*
G01Y597606D02*
Y597016D01*
G01X709Y623984D02*
Y622803D01*
G01Y620835D02*
Y619654D01*
G01Y614535D02*
Y613354D01*
G01Y617685D02*
Y616504D01*
G01Y611386D02*
Y610205D01*
G01Y605087D02*
Y603906D01*
G01Y608236D02*
Y607055D01*
G01Y601937D02*
Y600756D01*
G01Y598787D02*
Y597606D01*
G01X1074Y623984D02*
Y622803D01*
G01Y620835D02*
Y619654D01*
G01Y614535D02*
Y613354D01*
G01Y617685D02*
Y616504D01*
G01Y611386D02*
Y610205D01*
G01Y605087D02*
Y603906D01*
G01Y608236D02*
Y607055D01*
G01Y601937D02*
Y600756D01*
G01Y598787D02*
Y597606D01*
G01X1184Y623984D02*
Y622803D01*
G01Y620835D02*
Y619654D01*
G01Y614535D02*
Y613354D01*
G01Y617685D02*
Y616504D01*
G01Y611386D02*
Y610205D01*
G01Y605087D02*
Y603906D01*
G01Y608236D02*
Y607055D01*
G01Y601937D02*
Y600756D01*
G01Y598787D02*
Y597606D01*
G01X3937Y597213D02*
Y599181D01*
G01X9965Y623984D02*
Y622803D01*
G01Y620835D02*
Y619654D01*
G01Y614535D02*
Y613354D01*
G01Y617685D02*
Y616504D01*
G01Y611386D02*
Y610205D01*
G01Y605087D02*
Y603906D01*
G01Y608236D02*
Y607055D01*
G01Y601937D02*
Y600756D01*
G01Y598787D02*
Y597606D01*
G01X10075Y623984D02*
Y622803D01*
G01Y620835D02*
Y619654D01*
G01Y614535D02*
Y613354D01*
G01Y617685D02*
Y616504D01*
G01Y611386D02*
Y610205D01*
G01Y605087D02*
Y603906D01*
G01Y608236D02*
Y607055D01*
G01Y601937D02*
Y600756D01*
G01Y598787D02*
Y597606D01*
G01X-19469Y598637D02*
X-18174Y598651D01*
G01X-18435D02*
X-20801Y598625D01*
G01X-18174Y598651D02*
X-17126Y598662D01*
G01X-19469Y601786D02*
X-18174Y601800D01*
G01X-18435D02*
X-20801Y601774D01*
G01X-18174Y601800D02*
X-17126Y601812D01*
G01X-19469Y604936D02*
X-18174Y604950D01*
G01X-18435D02*
X-20801Y604924D01*
G01X-18174Y604950D02*
X-17126Y604961D01*
G01X-19469Y608085D02*
X-18174Y608100D01*
G01X-18435D02*
X-20801Y608074D01*
G01X-18174Y608100D02*
X-17126Y608111D01*
G01X-19469Y611235D02*
X-18174Y611249D01*
G01X-18435D02*
X-20801Y611223D01*
G01X-18174Y611249D02*
X-17126Y611261D01*
G01X-19469Y614385D02*
X-18174Y614399D01*
G01X-18435D02*
X-20801Y614373D01*
G01X-18174Y614399D02*
X-17126Y614410D01*
G01X-15985Y598672D02*
X-14449Y598689D01*
G01X-14677D02*
X-18174Y598651D01*
G01X-14677Y598689D02*
X-16213Y598672D01*
G01X-15985Y601822D02*
X-14449Y601839D01*
G01X-14677D02*
X-18174Y601800D01*
G01X-14677Y601839D02*
X-16213Y601822D01*
G01X-15985Y604972D02*
X-14449Y604988D01*
G01X-14677D02*
X-18174Y604950D01*
G01X-14677Y604988D02*
X-16213Y604972D01*
G01X-15985Y608121D02*
X-14449Y608138D01*
G01X-14677D02*
X-18174Y608100D01*
G01X-14677Y608138D02*
X-16213Y608121D01*
G01X-15985Y611271D02*
X-14449Y611287D01*
G01X-14677D02*
X-18174Y611249D01*
G01X-14677Y611287D02*
X-16213Y611271D01*
G01X-15985Y614420D02*
X-14449Y614437D01*
G01X-14677D02*
X-18174Y614399D01*
G01X-14677Y614437D02*
X-16213Y614420D01*
G01X-15985Y617570D02*
X-14449Y617587D01*
G01X-14677D02*
X-17126Y617560D01*
G01X-19469Y598637D02*
X-20801Y598625D01*
G01X-19469Y601786D02*
X-20801Y601774D01*
G01X-19469Y604936D02*
X-20801Y604924D01*
G01X-19469Y608085D02*
X-20801Y608074D01*
G01X-19469Y611235D02*
X-20801Y611223D01*
G01X-19469Y614385D02*
X-20801Y614373D01*
G01X-19469Y617534D02*
X-20801Y617522D01*
G01X-15985Y598672D02*
X-17126Y598662D01*
G01D02*
X-18435Y598651D01*
G01X-15985Y601822D02*
X-17126Y601812D01*
G01D02*
X-18435Y601800D01*
G01X-15985Y604972D02*
X-17126Y604961D01*
G01D02*
X-18435Y604950D01*
G01X-15985Y608121D02*
X-17126Y608111D01*
G01D02*
X-18435Y608100D01*
G01X-15985Y611271D02*
X-17126Y611261D01*
G01D02*
X-18435Y611249D01*
G01X-15985Y614420D02*
X-17126Y614410D01*
G01D02*
X-18435Y614399D01*
G01X-15985Y617570D02*
X-17126Y617560D01*
G01D02*
X-18435Y617548D01*
G01X22441Y587173D02*
X3937D01*
G01X-7283Y594260D02*
X-26772D01*
G01X512Y597016D02*
X0D01*
G01X13780Y597213D02*
X3937D01*
G01X-13009Y597409D02*
X-14147D01*
G01X12410Y597606D02*
X315D01*
G01X-14449Y597705D02*
X-14677D01*
G01X-15985Y597721D02*
X-16213D01*
G01X-18174Y597743D02*
X-18435D01*
G01X-18174Y598651D02*
X-18435D01*
G01X-16213Y598672D02*
X-15985D01*
G01X-14449Y598689D02*
X-14677D01*
G01X12410Y598787D02*
X315D01*
G01X-13009Y598984D02*
X-14147D01*
G01X3937Y599181D02*
X13780D01*
G01X512Y599378D02*
X0D01*
G01X512Y600165D02*
X0D01*
G01X-13009Y600559D02*
X-14147D01*
G01X12410Y600756D02*
X315D01*
G01X-14449Y600854D02*
X-14677D01*
G01X-15985Y600870D02*
X-16213D01*
G01X-18174Y600892D02*
X-18435D01*
G01X-18174Y601800D02*
X-18435D01*
G01X-15985Y601822D02*
X-16213D01*
G01X-14449Y601839D02*
X-14677D01*
G01X12410Y601937D02*
X315D01*
G01X-13009Y602134D02*
X-14147D01*
G01X512Y602528D02*
X0D01*
G01X512Y603315D02*
X0D01*
G01X-13009Y603709D02*
X-14147D01*
G01X12410Y603906D02*
X315D01*
G01X-14449Y604004D02*
X-14677D01*
G01X-15985Y604020D02*
X-16213D01*
G01X-18174Y604042D02*
X-18435D01*
G01X-18174Y604950D02*
X-18435D01*
G01X-15985Y604972D02*
X-16213D01*
G01X-14449Y604988D02*
X-14677D01*
G01X12410Y605087D02*
X315D01*
G01X-13009Y605283D02*
X-14147D01*
G01X512Y605677D02*
X0D01*
G01X512Y606465D02*
X0D01*
G01X-13009Y606858D02*
X-14147D01*
G01X12410Y607055D02*
X315D01*
G01X-14449Y607154D02*
X-14677D01*
G01X-15985Y607170D02*
X-16213D01*
G01X-18174Y607191D02*
X-18435D01*
G01X-18174Y608100D02*
X-18435D01*
G01X-15985Y608121D02*
X-16213D01*
G01X-14449Y608138D02*
X-14677D01*
G01X12410Y608236D02*
X315D01*
G01X-13009Y608433D02*
X-14147D01*
G01X512Y608827D02*
X0D01*
G01X512Y609614D02*
X0D01*
G01X-13009Y610008D02*
X-14147D01*
G01X12410Y610205D02*
X315D01*
G01X-14449Y610303D02*
X-14677D01*
G01X-15985Y610319D02*
X-16213D01*
G01X-18174Y610341D02*
X-18435D01*
G01X-18174Y611249D02*
X-18435D01*
G01X-15985Y611271D02*
X-16213D01*
G01X-14449Y611287D02*
X-14677D01*
G01X12410Y611386D02*
X315D01*
G01X-13009Y611583D02*
X-14147D01*
G01X512Y611976D02*
X0D01*
G01X512Y612764D02*
X0D01*
G01X-13009Y613157D02*
X-14147D01*
G01X12410Y613354D02*
X315D01*
G01X-14449Y613453D02*
X-14677D01*
G01X-15985Y613469D02*
X-16213D01*
G01X-18174Y613491D02*
X-18435D01*
G01X-18174Y614399D02*
X-18435D01*
G01X-15985Y614420D02*
X-16213D01*
G01X-14449Y614437D02*
X-14677D01*
G01X12410Y614535D02*
X315D01*
G01X-13009Y614732D02*
X-14147D01*
G01X512Y615126D02*
X0D01*
G01X512Y615913D02*
X0D01*
G01X-13009Y616307D02*
X-14147D01*
G01X12410Y616504D02*
X315D01*
G01X-14449Y616602D02*
X-14677D01*
G01X-15985Y616619D02*
X-16213D01*
G01X-18174Y616640D02*
X-18435D01*
G01X-18174Y617548D02*
X-18435D01*
G01X-15985Y617570D02*
X-16213D01*
G01X-14449Y617587D02*
X-14677D01*
G01X12410Y617685D02*
X315D01*
G01X-13009Y617882D02*
X-14147D01*
G01X512Y618276D02*
X0D01*
G01X512Y619063D02*
X0D01*
G01X-13009Y619457D02*
X-14147D01*
G01X12410Y619654D02*
X315D01*
G01X-14449Y619752D02*
X-14677D01*
G01X-15985Y619768D02*
X-16213D01*
G01X-18174Y619790D02*
X-18435D01*
G01X-18174Y620698D02*
X-18435D01*
G01X-15985Y620720D02*
X-16213D01*
G01X-14449Y620736D02*
X-14677D01*
G01X12410Y620835D02*
X315D01*
G01X-13009Y621031D02*
X-14147D01*
G01X512Y621425D02*
X0D01*
G01X512Y622213D02*
X0D01*
G01X-13009Y622606D02*
X-14147D01*
G01X12410Y622803D02*
X315D01*
G01X-14449Y622902D02*
X-14677D01*
G01X-15985Y622918D02*
X-16213D01*
G01X-18174Y622939D02*
X-18435D01*
G01X-19469Y597757D02*
X-20801Y597769D01*
G01X-15985Y597721D02*
X-18435Y597743D01*
G01X-19469Y600907D02*
X-20801Y600919D01*
G01X-15985Y600870D02*
X-18435Y600892D01*
G01X-19469Y604056D02*
X-20801Y604068D01*
G01X-15985Y604020D02*
X-18435Y604042D01*
G01X-19469Y607206D02*
X-20801Y607218D01*
G01X-15985Y607170D02*
X-18435Y607191D01*
G01X-19469Y610356D02*
X-20801Y610367D01*
G01X-15985Y610319D02*
X-18435Y610341D01*
G01X-19469Y613505D02*
X-20801Y613517D01*
G01X-15985Y613469D02*
X-18435Y613491D01*
G01X-19469Y616655D02*
X-20801Y616667D01*
G01X-15985Y616619D02*
X-18435Y616640D01*
G01X-19469Y619804D02*
X-20801Y619816D01*
G01X-15985Y619768D02*
X-18435Y619790D01*
G01X-19469Y622954D02*
X-20801Y622966D01*
G01X-15985Y622918D02*
X-18435Y622939D01*
G01X-15985Y597721D02*
X-14449Y597705D01*
G01X-15985Y600870D02*
X-14449Y600854D01*
G01X-15985Y604020D02*
X-14449Y604004D01*
G01X-15985Y607170D02*
X-14449Y607154D01*
G01X-15985Y610319D02*
X-14449Y610303D01*
G01X-15985Y613469D02*
X-14449Y613453D01*
G01X-15985Y616619D02*
X-14449Y616602D01*
G01X-15985Y619768D02*
X-14449Y619752D01*
G01X-15985Y622918D02*
X-14449Y622902D01*
G01X-18435Y597743D02*
X-20801Y597769D01*
G01X-18435Y600892D02*
X-20801Y600919D01*
G01X-18435Y604042D02*
X-20801Y604068D01*
G01X-18435Y607191D02*
X-20801Y607218D01*
G01X-18435Y610341D02*
X-20801Y610367D01*
G01X-18435Y613491D02*
X-20801Y613517D01*
G01X-18435Y616640D02*
X-20801Y616667D01*
G01X-18435Y619790D02*
X-20801Y619816D01*
G01X-18435Y622939D02*
X-20801Y622966D01*
G01X-19469Y597757D02*
X-16213Y597721D01*
G01X-18174Y597743D02*
X-14677Y597705D01*
G01X-19469Y600907D02*
X-16213Y600870D01*
G01X-18174Y600892D02*
X-14677Y600854D01*
G01X-19469Y604056D02*
X-16213Y604020D01*
G01X-18174Y604042D02*
X-14677Y604004D01*
G01X-19469Y607206D02*
X-16213Y607170D01*
G01X-18174Y607191D02*
X-14677Y607154D01*
G01X-19469Y610356D02*
X-16213Y610319D01*
G01X-18174Y610341D02*
X-14677Y610303D01*
G01X-19469Y613505D02*
X-16213Y613469D01*
G01X-18174Y613491D02*
X-14677Y613453D01*
G01X-19469Y616655D02*
X-16213Y616619D01*
G01X-18174Y616640D02*
X-14677Y616602D01*
G01X-19469Y619804D02*
X-16213Y619768D01*
G01X-18174Y619790D02*
X-14677Y619752D01*
G01X-19469Y622954D02*
X-16213Y622918D01*
G01X-18174Y622939D02*
X-14677Y622902D01*
G01X-17126Y617560D02*
X-16213Y617570D01*
G01X-19469Y617534D02*
X-18174Y617548D01*
G01X-18435D02*
X-20801Y617522D01*
G01X-18174Y617548D02*
X-17126Y617560D01*
G01X-18174Y617548D02*
X-17126Y617560D01*
G01X-19469Y620684D02*
X-18174Y620698D01*
G01X-18435D02*
X-20801Y620672D01*
G01X-18174Y620698D02*
X-17126Y620709D01*
G01X-19469Y623833D02*
X-18174Y623848D01*
G01X-18435D02*
X-20801Y623822D01*
G01X-18174Y623848D02*
X-17126Y623859D01*
G01X-15985Y620720D02*
X-14449Y620736D01*
G01X-14677D02*
X-18174Y620698D01*
G01X-14677Y620736D02*
X-16213Y620720D01*
G01X-15985Y623869D02*
X-14449Y623886D01*
G01X-14677D02*
X-18174Y623848D01*
G01X-14677Y623886D02*
X-16213Y623869D01*
G01X-19469Y620684D02*
X-20801Y620672D01*
G01X-19469Y623833D02*
X-20801Y623822D01*
G01X-15985Y620720D02*
X-17126Y620709D01*
G01D02*
X-18435Y620698D01*
G01X-15985Y623869D02*
X-17126Y623859D01*
G01D02*
X-18435Y623848D01*
G01X-18174D02*
X-18435D01*
G01X-15985Y623869D02*
X-16213D01*
G01X-14449Y623886D02*
X-14677D01*
G01X12410Y623984D02*
X315D01*
G01X-13009Y624181D02*
X-14147D01*
G01X512Y624575D02*
X0D01*
G01X-14537Y623974D02*
X-14677Y623886D01*
G01X-13977Y624181D02*
X-14449Y623886D01*
G01X-14537Y620824D02*
X-14677Y620736D01*
G01X-13977Y621031D02*
X-14449Y620736D01*
G01X-14537Y617674D02*
X-14677Y617587D01*
G01X-13977Y617882D02*
X-14449Y617587D01*
G01X-14537Y614525D02*
X-14677Y614437D01*
G01X-13977Y614732D02*
X-14449Y614437D01*
G01X-14537Y611375D02*
X-14677Y611287D01*
G01X-13977Y611583D02*
X-14449Y611287D01*
G01X-14537Y608226D02*
X-14677Y608138D01*
G01X-13977Y608433D02*
X-14449Y608138D01*
G01X-14537Y605076D02*
X-14677Y604988D01*
G01X-13977Y605283D02*
X-14449Y604988D01*
G01X-14537Y601926D02*
X-14677Y601839D01*
G01X-13977Y602134D02*
X-14449Y601839D01*
G01X-14537Y598777D02*
X-14677Y598689D01*
G01X-13977Y598984D02*
X-14449Y598689D01*
G01X-27981Y598197D02*
X-30709Y596622D01*
G01X-14147Y624181D02*
X-14537Y623974D01*
G01X-14147Y621031D02*
X-14537Y620824D01*
G01X-14147Y617882D02*
X-14537Y617674D01*
G01X-14147Y614732D02*
X-14537Y614525D01*
G01X-14147Y611583D02*
X-14537Y611375D01*
G01X-14147Y608433D02*
X-14537Y608226D01*
G01X-14147Y605283D02*
X-14537Y605076D01*
G01X-14147Y602134D02*
X-14537Y601926D01*
G01X-14147Y598984D02*
X-14537Y598777D01*
G01X-26772Y594260D02*
X-30709Y592291D01*
G01X-20801Y630121D02*
Y629265D01*
G01Y626971D02*
Y626115D01*
G01X-19469Y630127D02*
Y629259D01*
G01Y626977D02*
Y626109D01*
G01X-18435Y630147D02*
Y629239D01*
G01Y626997D02*
Y626089D01*
G01X-18174Y630147D02*
Y629239D01*
G01Y626997D02*
Y626089D01*
G01X-16213Y630169D02*
Y629217D01*
G01Y627019D02*
Y626067D01*
G01X-15985Y630169D02*
Y629217D01*
G01Y627019D02*
Y626067D01*
G01X-14537Y625963D02*
X-14147Y625756D01*
G01X-14537Y629113D02*
X-14147Y628906D01*
G01X-14677Y626051D02*
X-14537Y625963D01*
G01X-14449Y626051D02*
X-13977Y625756D01*
G01X-14677Y629201D02*
X-14537Y629113D01*
G01X-14449Y629201D02*
X-13977Y628906D01*
G01X-14537Y630273D02*
Y629113D01*
G01Y627123D02*
Y625963D01*
G01X-13009Y630480D02*
Y628906D01*
G01Y627331D02*
Y625756D01*
G01X315Y629102D02*
Y628512D01*
G01Y627724D02*
Y627134D01*
G01Y625953D02*
Y625362D01*
G01X512Y629102D02*
Y628512D01*
G01Y627724D02*
Y627134D01*
G01Y625953D02*
Y625362D01*
G01X709Y630283D02*
Y629102D01*
G01Y627134D02*
Y625953D01*
G01X1074Y630283D02*
Y629102D01*
G01Y627134D02*
Y625953D01*
G01X1184Y630283D02*
Y629102D01*
G01Y627134D02*
Y625953D01*
G01X9965Y630283D02*
Y629102D01*
G01Y627134D02*
Y625953D01*
G01X10075Y630283D02*
Y629102D01*
G01Y627134D02*
Y625953D01*
G01X-19469Y626104D02*
X-20801Y626115D01*
G01X-15985Y626067D02*
X-18435Y626089D01*
G01X-15985Y626067D02*
X-14449Y626051D01*
G01X-18435Y626089D02*
X-20801Y626115D01*
G01X-19469Y626104D02*
X-16213Y626067D01*
G01X-18174Y626089D02*
X-14677Y626051D01*
G01X-19469Y626983D02*
X-18174Y626997D01*
G01X-18435D02*
X-20801Y626971D01*
G01X-18174Y626997D02*
X-17126Y627009D01*
G01X-15985Y627019D02*
X-14449Y627035D01*
G01X-14677D02*
X-18174Y626997D01*
G01X-14677Y627035D02*
X-16213Y627019D01*
G01X-19469Y626983D02*
X-20801Y626971D01*
G01X-15985Y627019D02*
X-17126Y627009D01*
G01D02*
X-18435Y626997D01*
G01X512Y625362D02*
X0D01*
G01X-13009Y625756D02*
X-14147D01*
G01X12410Y625953D02*
X315D01*
G01X-14449Y626051D02*
X-14677D01*
G01X-15985Y626067D02*
X-16213D01*
G01X-18174Y626089D02*
X-18435D01*
G01X-18174Y626997D02*
X-18435D01*
G01X-15985Y627019D02*
X-16213D01*
G01X-14449Y627035D02*
X-14677D01*
G01X12410Y627134D02*
X315D01*
G01X-13009Y627331D02*
X-14147D01*
G01X512Y627724D02*
X0D01*
G01X512Y628512D02*
X0D01*
G01X-13009Y628906D02*
X-14147D01*
G01X12410Y629102D02*
X315D01*
G01X-14449Y629201D02*
X-14677D01*
G01X-15985Y629217D02*
X-16213D01*
G01X-18174Y629239D02*
X-18435D01*
G01X-19469Y629253D02*
X-20801Y629265D01*
G01X-15985Y629217D02*
X-18435Y629239D01*
G01X-15985Y629217D02*
X-14449Y629201D01*
G01X-18435Y629239D02*
X-20801Y629265D01*
G01X-19469Y629253D02*
X-16213Y629217D01*
G01X-18174Y629239D02*
X-14677Y629201D01*
G01X-14537Y627123D02*
X-14677Y627035D01*
G01X-13977Y627331D02*
X-14449Y627035D01*
G01X-14147Y627331D02*
X-14537Y627123D01*
G01X-9055Y581268D02*
Y557646D01*
G01X11893Y567095D02*
X-9055Y566701D01*
G01D02*
X11813Y567094D01*
G01X22441Y557646D02*
X-9055D01*
G01X11817Y575756D02*
X-9055Y576150D01*
G01X11893Y575755D02*
X-9055Y576150D01*
G01X16142Y571425D02*
G03I-4331J0D01*
G01X11827Y575756D02*
G03Y567094I-16J-4331D01*
G01X12057Y646031D02*
X12287Y645776D01*
G01X12057Y649181D02*
X12287Y648925D01*
G01X12416Y646046D02*
X12634Y645776D01*
G01X12416Y649195D02*
X12634Y648925D01*
G01X12416Y652345D02*
X12634Y652075D01*
G01X12057Y652331D02*
X12287Y652075D01*
G01X12057Y655480D02*
X12287Y655224D01*
G01X12057Y658630D02*
X12287Y658374D01*
G01X12057Y661780D02*
X12287Y661524D01*
G01X12057Y664929D02*
X12287Y664673D01*
G01X12057Y668079D02*
X12287Y667823D01*
G01X12057Y671228D02*
X12287Y670972D01*
G01X12057Y674378D02*
X12287Y674122D01*
G01X12057Y677528D02*
X12287Y677272D01*
G01X12057Y680677D02*
X12287Y680421D01*
G01X12057Y683827D02*
X12287Y683571D01*
G01X12057Y686976D02*
X12287Y686720D01*
G01X12057Y690126D02*
X12287Y689870D01*
G01X12057Y693276D02*
X12287Y693020D01*
G01X12057Y696425D02*
X12287Y696169D01*
G01X12057Y699575D02*
X12287Y699319D01*
G01X12057Y702724D02*
X12287Y702469D01*
G01X12416Y655494D02*
X12634Y655224D01*
G01X12416Y658644D02*
X12634Y658374D01*
G01X12416Y661794D02*
X12634Y661524D01*
G01X12416Y664943D02*
X12634Y664673D01*
G01X12416Y668093D02*
X12634Y667823D01*
G01X12416Y671243D02*
X12634Y670972D01*
G01X12416Y674392D02*
X12634Y674122D01*
G01X12416Y677542D02*
X12634Y677272D01*
G01X12416Y680691D02*
X12634Y680421D01*
G01X12416Y683841D02*
X12634Y683571D01*
G01X12416Y686991D02*
X12634Y686720D01*
G01X12416Y690140D02*
X12634Y689870D01*
G01X12416Y693290D02*
X12634Y693020D01*
G01X12416Y696439D02*
X12634Y696169D01*
G01X12416Y699589D02*
X12634Y699319D01*
G01X12416Y702739D02*
X12634Y702469D01*
G01X12057Y699575D02*
Y698394D01*
G01Y702724D02*
Y701543D01*
G01Y696425D02*
Y695244D01*
G01Y690126D02*
Y688945D01*
G01Y693276D02*
Y692094D01*
G01Y686976D02*
Y685795D01*
G01Y680677D02*
Y679496D01*
G01Y683827D02*
Y682646D01*
G01Y677528D02*
Y676346D01*
G01Y671228D02*
Y670047D01*
G01Y674378D02*
Y673197D01*
G01Y668079D02*
Y666898D01*
G01Y661780D02*
Y660598D01*
G01Y664929D02*
Y663748D01*
G01Y658630D02*
Y657449D01*
G01Y652331D02*
Y651150D01*
G01Y655480D02*
Y654299D01*
G01Y649181D02*
Y648000D01*
G01X12410Y699575D02*
Y698394D01*
G01Y702724D02*
Y701543D01*
G01Y696425D02*
Y695244D01*
G01Y690126D02*
Y688945D01*
G01Y693276D02*
Y692094D01*
G01Y686976D02*
Y685795D01*
G01Y680677D02*
Y679496D01*
G01Y683827D02*
Y682646D01*
G01Y677528D02*
Y676346D01*
G01Y671228D02*
Y670047D01*
G01Y674378D02*
Y673197D01*
G01Y668079D02*
Y666898D01*
G01Y661780D02*
Y660598D01*
G01Y664929D02*
Y663748D01*
G01Y658630D02*
Y657449D01*
G01Y652331D02*
Y651150D01*
G01Y655480D02*
Y654299D01*
G01Y649181D02*
Y648000D01*
G01X13353Y699319D02*
Y698650D01*
G01Y702469D02*
Y701799D01*
G01Y696169D02*
Y695500D01*
G01Y689870D02*
Y689201D01*
G01Y693020D02*
Y692350D01*
G01Y686720D02*
Y686051D01*
G01Y680421D02*
Y679752D01*
G01Y683571D02*
Y682902D01*
G01Y677272D02*
Y676602D01*
G01Y670972D02*
Y670303D01*
G01Y674122D02*
Y673453D01*
G01Y667823D02*
Y667154D01*
G01Y661524D02*
Y660854D01*
G01Y664673D02*
Y664004D01*
G01Y658374D02*
Y657705D01*
G01Y652075D02*
Y651406D01*
G01Y655224D02*
Y654555D01*
G01Y648925D02*
Y648256D01*
G01X13701Y699319D02*
Y698650D01*
G01Y702469D02*
Y701799D01*
G01Y696169D02*
Y695500D01*
G01Y689870D02*
Y689201D01*
G01Y693020D02*
Y692350D01*
G01Y686720D02*
Y686051D01*
G01Y680421D02*
Y679752D01*
G01Y683571D02*
Y682902D01*
G01Y677272D02*
Y676602D01*
G01Y670972D02*
Y670303D01*
G01Y674122D02*
Y673453D01*
G01Y667823D02*
Y667154D01*
G01Y661524D02*
Y660854D01*
G01Y664673D02*
Y664004D01*
G01Y658374D02*
Y657705D01*
G01Y652075D02*
Y651406D01*
G01Y655224D02*
Y654555D01*
G01Y648925D02*
Y648256D01*
G01Y645776D02*
X12287D01*
G01X13701Y648256D02*
X12287D01*
G01X13701Y648925D02*
X12287D01*
G01X13701Y651406D02*
X12287D01*
G01X13701Y652075D02*
X12287D01*
G01X13701Y654555D02*
X12287D01*
G01X13701Y655224D02*
X12287D01*
G01X13701Y657705D02*
X12287D01*
G01X13701Y658374D02*
X12287D01*
G01X13701Y660854D02*
X12287D01*
G01X13701Y661524D02*
X12287D01*
G01X13701Y664004D02*
X12287D01*
G01X13701Y664673D02*
X12287D01*
G01X13701Y667154D02*
X12287D01*
G01X13701Y667823D02*
X12287D01*
G01X13701Y670303D02*
X12287D01*
G01X13701Y670972D02*
X12287D01*
G01X13701Y673453D02*
X12287D01*
G01X13701Y674122D02*
X12287D01*
G01X13701Y676602D02*
X12287D01*
G01X13701Y677272D02*
X12287D01*
G01X13701Y679752D02*
X12287D01*
G01X13701Y680421D02*
X12287D01*
G01X13701Y682902D02*
X12287D01*
G01X13701Y683571D02*
X12287D01*
G01X13701Y686051D02*
X12287D01*
G01X13701Y686720D02*
X12287D01*
G01X13701Y689201D02*
X12287D01*
G01X13701Y689870D02*
X12287D01*
G01X13701Y692350D02*
X12287D01*
G01X13701Y693020D02*
X12287D01*
G01X13701Y695500D02*
X12287D01*
G01X13701Y696169D02*
X12287D01*
G01X13701Y698650D02*
X12287D01*
G01X13701Y699319D02*
X12287D01*
G01X13701Y701799D02*
X12287D01*
G01X12634D02*
X12416Y701529D01*
G01X12634Y698650D02*
X12416Y698380D01*
G01X12634Y695500D02*
X12416Y695230D01*
G01X12634Y692350D02*
X12416Y692080D01*
G01X12634Y689201D02*
X12416Y688931D01*
G01X12634Y686051D02*
X12416Y685781D01*
G01X12634Y682902D02*
X12416Y682631D01*
G01X12634Y679752D02*
X12416Y679482D01*
G01X12634Y676602D02*
X12416Y676332D01*
G01X12634Y673453D02*
X12416Y673183D01*
G01X12634Y670303D02*
X12416Y670033D01*
G01X12634Y667154D02*
X12416Y666883D01*
G01X12634Y664004D02*
X12416Y663734D01*
G01X12634Y660854D02*
X12416Y660584D01*
G01X12634Y657705D02*
X12416Y657435D01*
G01X12634Y654555D02*
X12416Y654285D01*
G01X12634Y651406D02*
X12416Y651135D01*
G01X12634Y648256D02*
X12416Y647986D01*
G01X12287Y701799D02*
X12057Y701543D01*
G01X12287Y698650D02*
X12057Y698394D01*
G01X12287Y695500D02*
X12057Y695244D01*
G01X12287Y692350D02*
X12057Y692094D01*
G01X12287Y689201D02*
X12057Y688945D01*
G01X12287Y686051D02*
X12057Y685795D01*
G01X12287Y682902D02*
X12057Y682646D01*
G01X12287Y679752D02*
X12057Y679496D01*
G01X12287Y676602D02*
X12057Y676346D01*
G01X12287Y673453D02*
X12057Y673197D01*
G01X12287Y670303D02*
X12057Y670047D01*
G01X12287Y667154D02*
X12057Y666898D01*
G01X12287Y664004D02*
X12057Y663748D01*
G01X12287Y660854D02*
X12057Y660598D01*
G01X12287Y657705D02*
X12057Y657449D01*
G01X12287Y654555D02*
X12057Y654299D01*
G01X12287Y651406D02*
X12057Y651150D01*
G01X12287Y648256D02*
X12057Y648000D01*
G01Y630283D02*
X12287Y630028D01*
G01X12057Y633433D02*
X12287Y633177D01*
G01X12057Y636583D02*
X12287Y636327D01*
G01X12057Y639732D02*
X12287Y639476D01*
G01X12057Y642882D02*
X12287Y642626D01*
G01X12416Y630298D02*
X12634Y630028D01*
G01X12416Y633447D02*
X12634Y633177D01*
G01X12416Y636597D02*
X12634Y636327D01*
G01X12416Y639746D02*
X12634Y639476D01*
G01X12416Y642896D02*
X12634Y642626D01*
G01X12057Y642882D02*
Y641701D01*
G01Y646031D02*
Y644850D01*
G01Y639732D02*
Y638551D01*
G01Y633433D02*
Y632252D01*
G01Y636583D02*
Y635402D01*
G01X12410Y642882D02*
Y641701D01*
G01Y646031D02*
Y644850D01*
G01Y639732D02*
Y638551D01*
G01Y633433D02*
Y632252D01*
G01Y636583D02*
Y635402D01*
G01X13353Y642626D02*
Y641957D01*
G01Y645776D02*
Y645106D01*
G01Y639476D02*
Y638807D01*
G01Y633177D02*
Y632508D01*
G01Y636327D02*
Y635657D01*
G01X13701Y642626D02*
Y641957D01*
G01Y645776D02*
Y645106D01*
G01Y639476D02*
Y638807D01*
G01Y633177D02*
Y632508D01*
G01Y636327D02*
Y635657D01*
G01Y630028D02*
X12287D01*
G01X13701Y632508D02*
X12287D01*
G01X13701Y633177D02*
X12287D01*
G01X13701Y635657D02*
X12287D01*
G01X13701Y636327D02*
X12287D01*
G01X13701Y638807D02*
X12287D01*
G01X13701Y639476D02*
X12287D01*
G01X13701Y641957D02*
X12287D01*
G01X13701Y642626D02*
X12287D01*
G01X13701Y645106D02*
X12287D01*
G01X12634D02*
X12416Y644836D01*
G01X12634Y641957D02*
X12416Y641687D01*
G01X12634Y638807D02*
X12416Y638537D01*
G01X12634Y635657D02*
X12416Y635387D01*
G01X12634Y632508D02*
X12416Y632238D01*
G01X12287Y645106D02*
X12057Y644850D01*
G01X12287Y641957D02*
X12057Y641701D01*
G01X12287Y638807D02*
X12057Y638551D01*
G01X12287Y635657D02*
X12057Y635402D01*
G01X12287Y632508D02*
X12057Y632252D01*
G01X-20801Y699412D02*
Y698556D01*
G01Y702562D02*
Y701706D01*
G01Y696263D02*
Y695407D01*
G01Y689963D02*
Y689107D01*
G01Y693113D02*
Y692257D01*
G01Y686814D02*
Y685958D01*
G01Y680515D02*
Y679659D01*
G01Y683664D02*
Y682808D01*
G01Y677365D02*
Y676509D01*
G01Y671066D02*
Y670210D01*
G01Y674215D02*
Y673359D01*
G01Y667916D02*
Y667060D01*
G01Y661617D02*
Y660761D01*
G01Y664767D02*
Y663911D01*
G01Y658467D02*
Y657611D01*
G01Y652168D02*
Y651312D01*
G01Y655318D02*
Y654462D01*
G01Y649019D02*
Y648163D01*
G01X-19469Y699418D02*
Y698550D01*
G01Y702568D02*
Y701700D01*
G01Y696269D02*
Y695401D01*
G01Y689969D02*
Y689102D01*
G01Y693119D02*
Y692251D01*
G01Y686820D02*
Y685952D01*
G01Y680520D02*
Y679653D01*
G01Y683670D02*
Y682802D01*
G01Y677371D02*
Y676503D01*
G01Y671072D02*
Y670204D01*
G01Y674221D02*
Y673354D01*
G01Y667922D02*
Y667054D01*
G01Y661623D02*
Y660755D01*
G01Y664772D02*
Y663905D01*
G01Y658473D02*
Y657606D01*
G01Y652174D02*
Y651306D01*
G01Y655324D02*
Y654456D01*
G01Y649024D02*
Y648157D01*
G01X-18435Y699438D02*
Y698530D01*
G01Y702588D02*
Y701680D01*
G01Y696289D02*
Y695380D01*
G01Y689989D02*
Y689081D01*
G01Y693139D02*
Y692231D01*
G01Y686840D02*
Y685931D01*
G01Y680541D02*
Y679632D01*
G01Y683690D02*
Y682782D01*
G01Y677391D02*
Y676483D01*
G01Y671092D02*
Y670183D01*
G01Y674241D02*
Y673333D01*
G01Y667942D02*
Y667034D01*
G01Y661643D02*
Y660735D01*
G01Y664793D02*
Y663884D01*
G01Y658493D02*
Y657585D01*
G01Y652194D02*
Y651286D01*
G01Y655344D02*
Y654435D01*
G01Y649044D02*
Y648136D01*
G01X-18174Y699438D02*
Y698530D01*
G01Y702588D02*
Y701680D01*
G01Y696289D02*
Y695380D01*
G01Y689989D02*
Y689081D01*
G01Y693139D02*
Y692231D01*
G01Y686840D02*
Y685931D01*
G01Y680541D02*
Y679632D01*
G01Y683690D02*
Y682782D01*
G01Y677391D02*
Y676483D01*
G01Y671092D02*
Y670183D01*
G01Y674241D02*
Y673333D01*
G01Y667942D02*
Y667034D01*
G01Y661643D02*
Y660735D01*
G01Y664793D02*
Y663884D01*
G01Y658493D02*
Y657585D01*
G01Y652194D02*
Y651286D01*
G01Y655344D02*
Y654435D01*
G01Y649044D02*
Y648136D01*
G01X-16213Y699460D02*
Y698508D01*
G01Y702609D02*
Y701658D01*
G01Y696310D02*
Y695359D01*
G01Y690011D02*
Y689059D01*
G01Y693161D02*
Y692209D01*
G01Y686861D02*
Y685910D01*
G01Y680562D02*
Y679611D01*
G01Y683712D02*
Y682760D01*
G01Y677413D02*
Y676461D01*
G01Y671113D02*
Y670162D01*
G01Y674263D02*
Y673311D01*
G01Y667964D02*
Y667012D01*
G01Y661665D02*
Y660713D01*
G01Y664814D02*
Y663863D01*
G01Y658515D02*
Y657563D01*
G01Y652216D02*
Y651264D01*
G01Y655365D02*
Y654414D01*
G01Y649066D02*
Y648115D01*
G01X-15985Y699460D02*
Y698508D01*
G01Y702609D02*
Y701658D01*
G01Y696310D02*
Y695359D01*
G01Y690011D02*
Y689059D01*
G01Y693161D02*
Y692209D01*
G01Y686861D02*
Y685910D01*
G01Y680562D02*
Y679611D01*
G01Y683712D02*
Y682760D01*
G01Y677413D02*
Y676461D01*
G01Y671113D02*
Y670162D01*
G01Y674263D02*
Y673311D01*
G01Y667964D02*
Y667012D01*
G01Y661665D02*
Y660713D01*
G01Y664814D02*
Y663863D01*
G01Y658515D02*
Y657563D01*
G01Y652216D02*
Y651264D01*
G01Y655365D02*
Y654414D01*
G01Y649066D02*
Y648115D01*
G01X-14537Y648011D02*
X-14147Y647803D01*
G01X-14537Y651160D02*
X-14147Y650953D01*
G01X-14537Y654310D02*
X-14147Y654102D01*
G01X-14537Y657459D02*
X-14147Y657252D01*
G01X-14537Y660609D02*
X-14147Y660402D01*
G01X-14537Y663759D02*
X-14147Y663551D01*
G01X-14537Y666908D02*
X-14147Y666701D01*
G01X-14537Y670058D02*
X-14147Y669850D01*
G01X-14537Y673207D02*
X-14147Y673000D01*
G01X-14537Y676357D02*
X-14147Y676150D01*
G01X-14537Y679507D02*
X-14147Y679299D01*
G01X-14677Y648098D02*
X-14537Y648011D01*
G01X-14449Y648098D02*
X-13977Y647803D01*
G01X-14677Y651248D02*
X-14537Y651160D01*
G01X-14449Y651248D02*
X-13977Y650953D01*
G01X-14677Y654398D02*
X-14537Y654310D01*
G01X-14449Y654398D02*
X-13977Y654102D01*
G01X-14677Y657547D02*
X-14537Y657459D01*
G01X-14449Y657547D02*
X-13977Y657252D01*
G01X-14677Y660697D02*
X-14537Y660609D01*
G01X-14449Y660697D02*
X-13977Y660402D01*
G01X-14677Y663846D02*
X-14537Y663759D01*
G01X-14449Y663846D02*
X-13977Y663551D01*
G01X-14677Y666996D02*
X-14537Y666908D01*
G01X-14449Y666996D02*
X-13977Y666701D01*
G01X-14677Y670146D02*
X-14537Y670058D01*
G01X-14449Y670146D02*
X-13977Y669850D01*
G01X-14677Y673295D02*
X-14537Y673207D01*
G01X-14449Y673295D02*
X-13977Y673000D01*
G01X-14677Y676445D02*
X-14537Y676357D01*
G01X-14449Y676445D02*
X-13977Y676150D01*
G01X-14677Y679594D02*
X-14537Y679507D01*
G01X-14449Y679594D02*
X-13977Y679299D01*
G01X-14677Y682744D02*
X-14537Y682656D01*
G01X-14449Y682744D02*
X-13977Y682449D01*
G01X-14677Y685894D02*
X-14537Y685806D01*
G01X-14449Y685894D02*
X-13977Y685598D01*
G01X-14677Y689043D02*
X-14537Y688956D01*
G01X-14449Y689043D02*
X-13977Y688748D01*
G01X-14677Y692193D02*
X-14537Y692105D01*
G01X-14449Y692193D02*
X-13977Y691898D01*
G01X-14677Y695343D02*
X-14537Y695255D01*
G01X-14449Y695343D02*
X-13977Y695047D01*
G01X-14677Y698492D02*
X-14537Y698404D01*
G01X-14449Y698492D02*
X-13977Y698197D01*
G01X-14677Y701642D02*
X-14537Y701554D01*
G01X-14449Y701642D02*
X-13977Y701346D01*
G01X-14537Y699564D02*
Y698404D01*
G01Y702714D02*
Y701554D01*
G01Y696415D02*
Y695255D01*
G01Y690115D02*
Y688956D01*
G01Y693265D02*
Y692105D01*
G01Y686966D02*
Y685806D01*
G01Y680667D02*
Y679507D01*
G01Y683816D02*
Y682656D01*
G01Y677517D02*
Y676357D01*
G01Y671218D02*
Y670058D01*
G01Y674367D02*
Y673207D01*
G01Y668068D02*
Y666908D01*
G01Y661769D02*
Y660609D01*
G01Y664919D02*
Y663759D01*
G01Y658619D02*
Y657459D01*
G01Y652320D02*
Y651160D01*
G01Y655470D02*
Y654310D01*
G01Y649170D02*
Y648011D01*
G01X-13009Y699772D02*
Y698197D01*
G01Y702921D02*
Y701346D01*
G01Y696622D02*
Y695047D01*
G01Y690323D02*
Y688748D01*
G01Y693472D02*
Y691898D01*
G01Y687173D02*
Y685598D01*
G01Y680874D02*
Y679299D01*
G01Y684024D02*
Y682449D01*
G01Y677724D02*
Y676150D01*
G01Y671425D02*
Y669850D01*
G01Y674575D02*
Y673000D01*
G01Y668276D02*
Y666701D01*
G01Y661976D02*
Y660402D01*
G01Y665126D02*
Y663551D01*
G01Y658827D02*
Y657252D01*
G01Y652528D02*
Y650953D01*
G01Y655677D02*
Y654102D01*
G01Y649378D02*
Y647803D01*
G01X315Y700165D02*
Y699575D01*
G01Y701543D02*
Y700953D01*
G01Y693866D02*
Y693276D01*
G01Y697016D02*
Y696425D01*
G01Y695244D02*
Y694654D01*
G01Y698394D02*
Y697803D01*
G01Y690717D02*
Y690126D01*
G01Y692094D02*
Y691504D01*
G01Y687567D02*
Y686976D01*
G01Y685795D02*
Y685205D01*
G01Y688945D02*
Y688354D01*
G01Y681268D02*
Y680677D01*
G01Y684417D02*
Y683827D01*
G01Y682646D02*
Y682055D01*
G01Y678118D02*
Y677528D01*
G01Y676346D02*
Y675756D01*
G01Y679496D02*
Y678906D01*
G01Y671819D02*
Y671228D01*
G01Y674969D02*
Y674378D01*
G01Y673197D02*
Y672606D01*
G01Y668669D02*
Y668079D01*
G01Y666898D02*
Y666307D01*
G01Y670047D02*
Y669457D01*
G01Y662370D02*
Y661780D01*
G01Y665520D02*
Y664929D01*
G01Y663748D02*
Y663157D01*
G01Y659220D02*
Y658630D01*
G01Y657449D02*
Y656858D01*
G01Y660598D02*
Y660008D01*
G01Y652921D02*
Y652331D01*
G01Y656071D02*
Y655480D01*
G01Y654299D02*
Y653709D01*
G01Y649772D02*
Y649181D01*
G01Y648000D02*
Y647409D01*
G01Y651150D02*
Y650559D01*
G01Y646622D02*
Y646031D01*
G01X512Y700165D02*
Y699575D01*
G01Y701543D02*
Y700953D01*
G01Y693866D02*
Y693276D01*
G01Y697016D02*
Y696425D01*
G01Y695244D02*
Y694654D01*
G01Y698394D02*
Y697803D01*
G01Y690717D02*
Y690126D01*
G01Y692094D02*
Y691504D01*
G01Y687567D02*
Y686976D01*
G01Y685795D02*
Y685205D01*
G01Y688945D02*
Y688354D01*
G01Y681268D02*
Y680677D01*
G01Y684417D02*
Y683827D01*
G01Y682646D02*
Y682055D01*
G01Y678118D02*
Y677528D01*
G01Y676346D02*
Y675756D01*
G01Y679496D02*
Y678906D01*
G01Y671819D02*
Y671228D01*
G01Y674969D02*
Y674378D01*
G01Y673197D02*
Y672606D01*
G01Y668669D02*
Y668079D01*
G01Y666898D02*
Y666307D01*
G01Y670047D02*
Y669457D01*
G01Y662370D02*
Y661780D01*
G01Y665520D02*
Y664929D01*
G01Y663748D02*
Y663157D01*
G01Y659220D02*
Y658630D01*
G01Y657449D02*
Y656858D01*
G01Y660598D02*
Y660008D01*
G01Y652921D02*
Y652331D01*
G01Y656071D02*
Y655480D01*
G01Y654299D02*
Y653709D01*
G01Y649772D02*
Y649181D01*
G01Y648000D02*
Y647409D01*
G01Y651150D02*
Y650559D01*
G01Y646622D02*
Y646031D01*
G01X709Y699575D02*
Y698394D01*
G01Y702724D02*
Y701543D01*
G01Y696425D02*
Y695244D01*
G01Y690126D02*
Y688945D01*
G01Y693276D02*
Y692094D01*
G01Y686976D02*
Y685795D01*
G01Y680677D02*
Y679496D01*
G01Y683827D02*
Y682646D01*
G01Y677528D02*
Y676346D01*
G01Y671228D02*
Y670047D01*
G01Y674378D02*
Y673197D01*
G01Y668079D02*
Y666898D01*
G01Y661780D02*
Y660598D01*
G01Y664929D02*
Y663748D01*
G01Y658630D02*
Y657449D01*
G01Y652331D02*
Y651150D01*
G01Y655480D02*
Y654299D01*
G01Y649181D02*
Y648000D01*
G01X1074Y699575D02*
Y698394D01*
G01Y702724D02*
Y701543D01*
G01Y696425D02*
Y695244D01*
G01Y690126D02*
Y688945D01*
G01Y693276D02*
Y692094D01*
G01Y686976D02*
Y685795D01*
G01Y680677D02*
Y679496D01*
G01Y683827D02*
Y682646D01*
G01Y677528D02*
Y676346D01*
G01Y671228D02*
Y670047D01*
G01Y674378D02*
Y673197D01*
G01Y668079D02*
Y666898D01*
G01Y661780D02*
Y660598D01*
G01Y664929D02*
Y663748D01*
G01Y658630D02*
Y657449D01*
G01Y652331D02*
Y651150D01*
G01Y655480D02*
Y654299D01*
G01Y649181D02*
Y648000D01*
G01X1184Y699575D02*
Y698394D01*
G01Y702724D02*
Y701543D01*
G01Y696425D02*
Y695244D01*
G01Y690126D02*
Y688945D01*
G01Y693276D02*
Y692094D01*
G01Y686976D02*
Y685795D01*
G01Y680677D02*
Y679496D01*
G01Y683827D02*
Y682646D01*
G01Y677528D02*
Y676346D01*
G01Y671228D02*
Y670047D01*
G01Y674378D02*
Y673197D01*
G01Y668079D02*
Y666898D01*
G01Y661780D02*
Y660598D01*
G01Y664929D02*
Y663748D01*
G01Y658630D02*
Y657449D01*
G01Y652331D02*
Y651150D01*
G01Y655480D02*
Y654299D01*
G01Y649181D02*
Y648000D01*
G01X9965Y699575D02*
Y698394D01*
G01Y702724D02*
Y701543D01*
G01Y696425D02*
Y695244D01*
G01Y690126D02*
Y688945D01*
G01Y693276D02*
Y692094D01*
G01Y686976D02*
Y685795D01*
G01Y680677D02*
Y679496D01*
G01Y683827D02*
Y682646D01*
G01Y677528D02*
Y676346D01*
G01Y671228D02*
Y670047D01*
G01Y674378D02*
Y673197D01*
G01Y668079D02*
Y666898D01*
G01Y661780D02*
Y660598D01*
G01Y664929D02*
Y663748D01*
G01Y658630D02*
Y657449D01*
G01Y652331D02*
Y651150D01*
G01Y655480D02*
Y654299D01*
G01Y649181D02*
Y648000D01*
G01X10075Y699575D02*
Y698394D01*
G01Y702724D02*
Y701543D01*
G01Y696425D02*
Y695244D01*
G01Y690126D02*
Y688945D01*
G01Y693276D02*
Y692094D01*
G01Y686976D02*
Y685795D01*
G01Y680677D02*
Y679496D01*
G01Y683827D02*
Y682646D01*
G01Y677528D02*
Y676346D01*
G01Y671228D02*
Y670047D01*
G01Y674378D02*
Y673197D01*
G01Y668079D02*
Y666898D01*
G01Y661780D02*
Y660598D01*
G01Y664929D02*
Y663748D01*
G01Y658630D02*
Y657449D01*
G01Y652331D02*
Y651150D01*
G01Y655480D02*
Y654299D01*
G01Y649181D02*
Y648000D01*
G01X-14537Y682656D02*
X-14147Y682449D01*
G01X-14537Y685806D02*
X-14147Y685598D01*
G01X-14537Y688956D02*
X-14147Y688748D01*
G01X-14537Y692105D02*
X-14147Y691898D01*
G01X-14537Y695255D02*
X-14147Y695047D01*
G01X-14537Y698404D02*
X-14147Y698197D01*
G01X-14537Y701554D02*
X-14147Y701346D01*
G01X-19469Y645881D02*
X-18174Y645895D01*
G01X-18435D02*
X-20801Y645869D01*
G01X-18174Y645895D02*
X-17126Y645906D01*
G01X-19469Y649030D02*
X-18174Y649044D01*
G01X-18435D02*
X-20801Y649019D01*
G01X-18174Y649044D02*
X-17126Y649056D01*
G01X-19469Y652180D02*
X-18174Y652194D01*
G01X-18435D02*
X-20801Y652168D01*
G01X-18174Y652194D02*
X-17126Y652206D01*
G01X-19469Y655330D02*
X-18174Y655344D01*
G01X-18435D02*
X-20801Y655318D01*
G01X-18174Y655344D02*
X-17126Y655355D01*
G01X-19469Y658479D02*
X-18174Y658493D01*
G01X-18435D02*
X-20801Y658467D01*
G01X-18174Y658493D02*
X-17126Y658505D01*
G01X-19469Y661629D02*
X-18174Y661643D01*
G01X-18435D02*
X-20801Y661617D01*
G01X-18174Y661643D02*
X-17126Y661654D01*
G01X-19469Y664778D02*
X-18174Y664793D01*
G01X-18435D02*
X-20801Y664767D01*
G01X-18174Y664793D02*
X-17126Y664804D01*
G01X-19469Y667928D02*
X-18174Y667942D01*
G01X-18435D02*
X-20801Y667916D01*
G01X-18174Y667942D02*
X-17126Y667954D01*
G01X-19469Y671078D02*
X-18174Y671092D01*
G01X-18435D02*
X-20801Y671066D01*
G01X-18174Y671092D02*
X-17126Y671103D01*
G01X-19469Y674227D02*
X-18174Y674241D01*
G01X-18435D02*
X-20801Y674215D01*
G01X-18174Y674241D02*
X-17126Y674253D01*
G01X-19469Y677377D02*
X-18174Y677391D01*
G01X-18435D02*
X-20801Y677365D01*
G01X-18174Y677391D02*
X-17126Y677402D01*
G01X-19469Y680526D02*
X-18174Y680541D01*
G01X-18435D02*
X-20801Y680515D01*
G01X-18174Y680541D02*
X-17126Y680552D01*
G01X-19469Y683676D02*
X-18174Y683690D01*
G01X-18435D02*
X-20801Y683664D01*
G01X-18174Y683690D02*
X-17126Y683702D01*
G01X-19469Y686826D02*
X-18174Y686840D01*
G01X-18435D02*
X-20801Y686814D01*
G01X-18174Y686840D02*
X-17126Y686851D01*
G01X-19469Y689975D02*
X-18174Y689989D01*
G01X-18435D02*
X-20801Y689963D01*
G01X-18174Y689989D02*
X-17126Y690001D01*
G01X-19469Y693125D02*
X-18174Y693139D01*
G01X-18435D02*
X-20801Y693113D01*
G01X-18174Y693139D02*
X-17126Y693150D01*
G01X-15985Y645917D02*
X-14449Y645933D01*
G01X-14677D02*
X-18174Y645895D01*
G01X-14677Y645933D02*
X-16213Y645917D01*
G01X-15985Y649066D02*
X-14449Y649083D01*
G01X-14677D02*
X-18174Y649044D01*
G01X-14677Y649083D02*
X-16213Y649066D01*
G01X-15985Y652216D02*
X-14449Y652232D01*
G01X-14677D02*
X-18174Y652194D01*
G01X-14677Y652232D02*
X-16213Y652216D01*
G01X-15985Y655365D02*
X-14449Y655382D01*
G01X-14677D02*
X-18174Y655344D01*
G01X-14677Y655382D02*
X-16213Y655365D01*
G01X-15985Y658515D02*
X-14449Y658531D01*
G01X-14677D02*
X-18174Y658493D01*
G01X-14677Y658531D02*
X-16213Y658515D01*
G01X-15985Y661665D02*
X-14449Y661681D01*
G01X-14677D02*
X-18174Y661643D01*
G01X-14677Y661681D02*
X-16213Y661665D01*
G01X-15985Y664814D02*
X-14449Y664831D01*
G01X-14677D02*
X-18174Y664793D01*
G01X-14677Y664831D02*
X-16213Y664814D01*
G01X-15985Y667964D02*
X-14449Y667980D01*
G01X-14677D02*
X-18174Y667942D01*
G01X-14677Y667980D02*
X-16213Y667964D01*
G01X-15985Y671113D02*
X-14449Y671130D01*
G01X-14677D02*
X-18174Y671092D01*
G01X-14677Y671130D02*
X-16213Y671113D01*
G01X-15985Y674263D02*
X-14449Y674280D01*
G01X-14677D02*
X-18174Y674241D01*
G01X-14677Y674280D02*
X-16213Y674263D01*
G01X-15985Y677413D02*
X-14449Y677429D01*
G01X-14677D02*
X-18174Y677391D01*
G01X-14677Y677429D02*
X-16213Y677413D01*
G01X-15985Y680562D02*
X-14449Y680579D01*
G01X-14677D02*
X-18174Y680541D01*
G01X-14677Y680579D02*
X-16213Y680562D01*
G01X-15985Y683712D02*
X-14449Y683728D01*
G01X-14677D02*
X-18174Y683690D01*
G01X-14677Y683728D02*
X-16213Y683712D01*
G01X-15985Y686861D02*
X-14449Y686878D01*
G01X-14677D02*
X-18174Y686840D01*
G01X-14677Y686878D02*
X-16213Y686861D01*
G01X-15985Y690011D02*
X-14449Y690028D01*
G01X-14677D02*
X-18174Y689989D01*
G01X-14677Y690028D02*
X-16213Y690011D01*
G01X-15985Y693161D02*
X-14449Y693177D01*
G01X-14677D02*
X-18174Y693139D01*
G01X-14677Y693177D02*
X-16213Y693161D01*
G01X-19469Y645881D02*
X-20801Y645869D01*
G01X-19469Y649030D02*
X-20801Y649019D01*
G01X-19469Y652180D02*
X-20801Y652168D01*
G01X-19469Y655330D02*
X-20801Y655318D01*
G01X-19469Y658479D02*
X-20801Y658467D01*
G01X-19469Y661629D02*
X-20801Y661617D01*
G01X-19469Y664778D02*
X-20801Y664767D01*
G01X-19469Y667928D02*
X-20801Y667916D01*
G01X-19469Y671078D02*
X-20801Y671066D01*
G01X-19469Y674227D02*
X-20801Y674215D01*
G01X-19469Y677377D02*
X-20801Y677365D01*
G01X-19469Y680526D02*
X-20801Y680515D01*
G01X-19469Y683676D02*
X-20801Y683664D01*
G01X-19469Y686826D02*
X-20801Y686814D01*
G01X-19469Y689975D02*
X-20801Y689963D01*
G01X-19469Y693125D02*
X-20801Y693113D01*
G01X-15985Y645917D02*
X-17126Y645906D01*
G01D02*
X-18435Y645895D01*
G01X-15985Y649066D02*
X-17126Y649056D01*
G01D02*
X-18435Y649044D01*
G01X-15985Y652216D02*
X-17126Y652206D01*
G01D02*
X-18435Y652194D01*
G01X-15985Y655365D02*
X-17126Y655355D01*
G01D02*
X-18435Y655344D01*
G01X-15985Y658515D02*
X-17126Y658505D01*
G01D02*
X-18435Y658493D01*
G01X-15985Y661665D02*
X-17126Y661654D01*
G01D02*
X-18435Y661643D01*
G01X-15985Y664814D02*
X-17126Y664804D01*
G01D02*
X-18435Y664793D01*
G01X-15985Y667964D02*
X-17126Y667954D01*
G01D02*
X-18435Y667942D01*
G01X-15985Y671113D02*
X-17126Y671103D01*
G01D02*
X-18435Y671092D01*
G01X-15985Y674263D02*
X-17126Y674253D01*
G01D02*
X-18435Y674241D01*
G01X-15985Y677413D02*
X-17126Y677402D01*
G01D02*
X-18435Y677391D01*
G01X-15985Y680562D02*
X-17126Y680552D01*
G01D02*
X-18435Y680541D01*
G01X-15985Y683712D02*
X-17126Y683702D01*
G01D02*
X-18435Y683690D01*
G01X-15985Y686861D02*
X-17126Y686851D01*
G01D02*
X-18435Y686840D01*
G01X-15985Y690011D02*
X-17126Y690001D01*
G01D02*
X-18435Y689989D01*
G01X-15985Y693161D02*
X-17126Y693150D01*
G01X-18435Y693139D02*
X-17126Y693150D01*
G01X-18174Y645895D02*
X-18435D01*
G01X-15985Y645917D02*
X-16213D01*
G01X-14449Y645933D02*
X-14677D01*
G01X12410Y646031D02*
X315D01*
G01X-13009Y646228D02*
X-14147D01*
G01X512Y646622D02*
X0D01*
G01X512Y647409D02*
X0D01*
G01X-13009Y647803D02*
X-14147D01*
G01X12410Y648000D02*
X315D01*
G01X-14449Y648098D02*
X-14677D01*
G01X-15985Y648115D02*
X-16213D01*
G01X-18174Y648136D02*
X-18435D01*
G01X-18174Y649044D02*
X-18435D01*
G01X-15985Y649066D02*
X-16213D01*
G01X-14449Y649083D02*
X-14677D01*
G01X12410Y649181D02*
X315D01*
G01X-13009Y649378D02*
X-14147D01*
G01X512Y649772D02*
X0D01*
G01X512Y650559D02*
X0D01*
G01X-13009Y650953D02*
X-14147D01*
G01X12410Y651150D02*
X315D01*
G01X-14449Y651248D02*
X-14677D01*
G01X-15985Y651264D02*
X-16213D01*
G01X-18174Y651286D02*
X-18435D01*
G01X-18174Y652194D02*
X-18435D01*
G01X-15985Y652216D02*
X-16213D01*
G01X-14449Y652232D02*
X-14677D01*
G01X12410Y652331D02*
X315D01*
G01X-13009Y652528D02*
X-14147D01*
G01X512Y652921D02*
X0D01*
G01X512Y653709D02*
X0D01*
G01X-13009Y654102D02*
X-14147D01*
G01X12410Y654299D02*
X315D01*
G01X-14449Y654398D02*
X-14677D01*
G01X-15985Y654414D02*
X-16213D01*
G01X-18174Y654435D02*
X-18435D01*
G01X-18174Y655344D02*
X-18435D01*
G01X-15985Y655365D02*
X-16213D01*
G01X-14449Y655382D02*
X-14677D01*
G01X12410Y655480D02*
X315D01*
G01X-13009Y655677D02*
X-14147D01*
G01X512Y656071D02*
X0D01*
G01X512Y656858D02*
X0D01*
G01X-13009Y657252D02*
X-14147D01*
G01X12410Y657449D02*
X315D01*
G01X-14449Y657547D02*
X-14677D01*
G01X-15985Y657563D02*
X-16213D01*
G01X-18174Y657585D02*
X-18435D01*
G01X-18174Y658493D02*
X-18435D01*
G01X-15985Y658515D02*
X-16213D01*
G01X-14449Y658531D02*
X-14677D01*
G01X12410Y658630D02*
X315D01*
G01X-13009Y658827D02*
X-14147D01*
G01X512Y659220D02*
X0D01*
G01X512Y660008D02*
X0D01*
G01X-13009Y660402D02*
X-14147D01*
G01X12410Y660598D02*
X315D01*
G01X-14449Y660697D02*
X-14677D01*
G01X-15985Y660713D02*
X-16213D01*
G01X-18174Y660735D02*
X-18435D01*
G01X-18174Y661643D02*
X-18435D01*
G01X-15985Y661665D02*
X-16213D01*
G01X-14449Y661681D02*
X-14677D01*
G01X12410Y661780D02*
X315D01*
G01X-13009Y661976D02*
X-14147D01*
G01X512Y662370D02*
X0D01*
G01X512Y663157D02*
X0D01*
G01X-13009Y663551D02*
X-14147D01*
G01X12410Y663748D02*
X315D01*
G01X-14449Y663846D02*
X-14677D01*
G01X-15985Y663863D02*
X-16213D01*
G01X-18174Y663884D02*
X-18435D01*
G01X-18174Y664793D02*
X-18435D01*
G01X-15985Y664814D02*
X-16213D01*
G01X-14449Y664831D02*
X-14677D01*
G01X12410Y664929D02*
X315D01*
G01X-13009Y665126D02*
X-14147D01*
G01X512Y665520D02*
X0D01*
G01X512Y666307D02*
X0D01*
G01X-13009Y666701D02*
X-14147D01*
G01X12410Y666898D02*
X315D01*
G01X-14449Y666996D02*
X-14677D01*
G01X-15985Y667012D02*
X-16213D01*
G01X-18174Y667034D02*
X-18435D01*
G01X-18174Y667942D02*
X-18435D01*
G01X-15985Y667964D02*
X-16213D01*
G01X-14449Y667980D02*
X-14677D01*
G01X12410Y668079D02*
X315D01*
G01X-13009Y668276D02*
X-14147D01*
G01X512Y668669D02*
X0D01*
G01X512Y669457D02*
X0D01*
G01X-13009Y669850D02*
X-14147D01*
G01X12410Y670047D02*
X315D01*
G01X-14449Y670146D02*
X-14677D01*
G01X-15985Y670162D02*
X-16213D01*
G01X-18174Y670183D02*
X-18435D01*
G01X-18174Y671092D02*
X-18435D01*
G01X-16213Y671113D02*
X-15985D01*
G01X-14449Y671130D02*
X-14677D01*
G01X12410Y671228D02*
X315D01*
G01X-13009Y671425D02*
X-14147D01*
G01X512Y671819D02*
X0D01*
G01X512Y672606D02*
X0D01*
G01X-13009Y673000D02*
X-14147D01*
G01X12410Y673197D02*
X315D01*
G01X-14449Y673295D02*
X-14677D01*
G01X-15985Y673311D02*
X-16213D01*
G01X-18174Y673333D02*
X-18435D01*
G01X-18174Y674241D02*
X-18435D01*
G01X-15985Y674263D02*
X-16213D01*
G01X-14449Y674280D02*
X-14677D01*
G01X12410Y674378D02*
X315D01*
G01X-13009Y674575D02*
X-14147D01*
G01X512Y674969D02*
X0D01*
G01X512Y675756D02*
X0D01*
G01X-13009Y676150D02*
X-14147D01*
G01X12410Y676346D02*
X315D01*
G01X-14449Y676445D02*
X-14677D01*
G01X-15985Y676461D02*
X-16213D01*
G01X-18174Y676483D02*
X-18435D01*
G01X-18174Y677391D02*
X-18435D01*
G01X-15985Y677413D02*
X-16213D01*
G01X-14449Y677429D02*
X-14677D01*
G01X12410Y677528D02*
X315D01*
G01X-13009Y677724D02*
X-14147D01*
G01X512Y678118D02*
X0D01*
G01X512Y678906D02*
X0D01*
G01X-13009Y679299D02*
X-14147D01*
G01X12410Y679496D02*
X315D01*
G01X-14449Y679594D02*
X-14677D01*
G01X-15985Y679611D02*
X-16213D01*
G01X-18174Y679632D02*
X-18435D01*
G01X-18174Y680541D02*
X-18435D01*
G01X-15985Y680562D02*
X-16213D01*
G01X-14449Y680579D02*
X-14677D01*
G01X12410Y680677D02*
X315D01*
G01X-13009Y680874D02*
X-14147D01*
G01X512Y681268D02*
X0D01*
G01X512Y682055D02*
X0D01*
G01X-13009Y682449D02*
X-14147D01*
G01X12410Y682646D02*
X315D01*
G01X-14449Y682744D02*
X-14677D01*
G01X-15985Y682760D02*
X-16213D01*
G01X-18174Y682782D02*
X-18435D01*
G01X-18174Y683690D02*
X-18435D01*
G01X-15985Y683712D02*
X-16213D01*
G01X-14449Y683728D02*
X-14677D01*
G01X12410Y683827D02*
X315D01*
G01X-13009Y684024D02*
X-14147D01*
G01X512Y684417D02*
X0D01*
G01X512Y685205D02*
X0D01*
G01X-13009Y685598D02*
X-14147D01*
G01X12410Y685795D02*
X315D01*
G01X-14449Y685894D02*
X-14677D01*
G01X-15985Y685910D02*
X-16213D01*
G01X-18174Y685931D02*
X-18435D01*
G01X-18174Y686840D02*
X-18435D01*
G01X-15985Y686861D02*
X-16213D01*
G01X-14449Y686878D02*
X-14677D01*
G01X12410Y686976D02*
X315D01*
G01X-13009Y687173D02*
X-14147D01*
G01X512Y687567D02*
X0D01*
G01X512Y688354D02*
X0D01*
G01X-13009Y688748D02*
X-14147D01*
G01X12410Y688945D02*
X315D01*
G01X-14449Y689043D02*
X-14677D01*
G01X-15985Y689059D02*
X-16213D01*
G01X-18174Y689081D02*
X-18435D01*
G01X-18174Y689989D02*
X-18435D01*
G01X-15985Y690011D02*
X-16213D01*
G01X-14449Y690028D02*
X-14677D01*
G01X12410Y690126D02*
X315D01*
G01X-13009Y690323D02*
X-14147D01*
G01X512Y690717D02*
X0D01*
G01X512Y691504D02*
X0D01*
G01X-13009Y691898D02*
X-14147D01*
G01X12410Y692094D02*
X315D01*
G01X-14449Y692193D02*
X-14677D01*
G01X-15985Y692209D02*
X-16213D01*
G01X-18174Y692231D02*
X-18435D01*
G01X-18174Y693139D02*
X-18435D01*
G01X-15985Y693161D02*
X-16213D01*
G01X-14449Y693177D02*
X-14677D01*
G01X12410Y693276D02*
X315D01*
G01X-13009Y693472D02*
X-14147D01*
G01X512Y693866D02*
X0D01*
G01X512Y694654D02*
X0D01*
G01X-13009Y695047D02*
X-14147D01*
G01X12410Y695244D02*
X315D01*
G01X-14449Y695343D02*
X-14677D01*
G01X-15985Y695359D02*
X-16213D01*
G01X-18174Y695380D02*
X-18435D01*
G01X-18174Y696289D02*
X-18435D01*
G01X-15985Y696310D02*
X-16213D01*
G01X-14449Y696327D02*
X-14677D01*
G01X12410Y696425D02*
X315D01*
G01X-13009Y696622D02*
X-14147D01*
G01X512Y697016D02*
X0D01*
G01X512Y697803D02*
X0D01*
G01X-13009Y698197D02*
X-14147D01*
G01X12410Y698394D02*
X315D01*
G01X-14449Y698492D02*
X-14677D01*
G01X-15985Y698508D02*
X-16213D01*
G01X-18174Y698530D02*
X-18435D01*
G01X-18174Y699438D02*
X-18435D01*
G01X-15985Y699460D02*
X-16213D01*
G01X-14449Y699476D02*
X-14677D01*
G01X12410Y699575D02*
X315D01*
G01X-13009Y699772D02*
X-14147D01*
G01X-19469Y648151D02*
X-20801Y648163D01*
G01X-15985Y648115D02*
X-18435Y648136D01*
G01X-19469Y651300D02*
X-20801Y651312D01*
G01X-15985Y651264D02*
X-18435Y651286D01*
G01X-19469Y654450D02*
X-20801Y654462D01*
G01X-15985Y654414D02*
X-18435Y654435D01*
G01X-19469Y657600D02*
X-20801Y657611D01*
G01X-15985Y657563D02*
X-18435Y657585D01*
G01X-19469Y660749D02*
X-20801Y660761D01*
G01X-15985Y660713D02*
X-18435Y660735D01*
G01X-19469Y663899D02*
X-20801Y663911D01*
G01X-15985Y663863D02*
X-18435Y663884D01*
G01X-19469Y667048D02*
X-20801Y667060D01*
G01X-15985Y667012D02*
X-18435Y667034D01*
G01X-19469Y670198D02*
X-20801Y670210D01*
G01X-15985Y670162D02*
X-18435Y670183D01*
G01X-19469Y673348D02*
X-20801Y673359D01*
G01X-15985Y673311D02*
X-18435Y673333D01*
G01X-19469Y676497D02*
X-20801Y676509D01*
G01X-15985Y676461D02*
X-18435Y676483D01*
G01X-19469Y679647D02*
X-20801Y679659D01*
G01X-15985Y679611D02*
X-18435Y679632D01*
G01X-19469Y682796D02*
X-20801Y682808D01*
G01X-15985Y682760D02*
X-18435Y682782D01*
G01X-19469Y685946D02*
X-20801Y685958D01*
G01X-15985Y685910D02*
X-18435Y685931D01*
G01X-19469Y689096D02*
X-20801Y689107D01*
G01X-15985Y689059D02*
X-18435Y689081D01*
G01X-19469Y692245D02*
X-20801Y692257D01*
G01X-15985Y692209D02*
X-18435Y692231D01*
G01X-19469Y695395D02*
X-20801Y695407D01*
G01X-15985Y695359D02*
X-18435Y695380D01*
G01X-19469Y698544D02*
X-20801Y698556D01*
G01X-15985Y698508D02*
X-18435Y698530D01*
G01X-19469Y701694D02*
X-20801Y701706D01*
G01X-15985Y701658D02*
X-18435Y701680D01*
G01X-15985Y648115D02*
X-14449Y648098D01*
G01X-15985Y651264D02*
X-14449Y651248D01*
G01X-15985Y654414D02*
X-14449Y654398D01*
G01X-15985Y657563D02*
X-14449Y657547D01*
G01X-15985Y660713D02*
X-14449Y660697D01*
G01X-15985Y663863D02*
X-14449Y663846D01*
G01X-15985Y667012D02*
X-14449Y666996D01*
G01X-15985Y670162D02*
X-14449Y670146D01*
G01X-15985Y673311D02*
X-14449Y673295D01*
G01X-15985Y676461D02*
X-14449Y676445D01*
G01X-15985Y679611D02*
X-14449Y679594D01*
G01X-15985Y682760D02*
X-14449Y682744D01*
G01X-15985Y685910D02*
X-14449Y685894D01*
G01X-15985Y689059D02*
X-14449Y689043D01*
G01X-15985Y692209D02*
X-14449Y692193D01*
G01X-15985Y695359D02*
X-14449Y695343D01*
G01X-15985Y698508D02*
X-14449Y698492D01*
G01X-15985Y701658D02*
X-14449Y701642D01*
G01X-18435Y648136D02*
X-20801Y648163D01*
G01X-18435Y651286D02*
X-20801Y651312D01*
G01X-18435Y654435D02*
X-20801Y654462D01*
G01X-18435Y657585D02*
X-20801Y657611D01*
G01X-18435Y660735D02*
X-20801Y660761D01*
G01X-18435Y663884D02*
X-20801Y663911D01*
G01X-18435Y667034D02*
X-20801Y667060D01*
G01X-18435Y670183D02*
X-20801Y670210D01*
G01X-18435Y673333D02*
X-20801Y673359D01*
G01X-18435Y676483D02*
X-20801Y676509D01*
G01X-18435Y679632D02*
X-20801Y679659D01*
G01X-18435Y682782D02*
X-20801Y682808D01*
G01X-18435Y685931D02*
X-20801Y685958D01*
G01X-18435Y689081D02*
X-20801Y689107D01*
G01X-18435Y692231D02*
X-20801Y692257D01*
G01X-18435Y695380D02*
X-20801Y695407D01*
G01X-18435Y698530D02*
X-20801Y698556D01*
G01X-18435Y701680D02*
X-20801Y701706D01*
G01X-19469Y648151D02*
X-16213Y648115D01*
G01X-18174Y648136D02*
X-14677Y648098D01*
G01X-19469Y651300D02*
X-16213Y651264D01*
G01X-18174Y651286D02*
X-14677Y651248D01*
G01X-19469Y654450D02*
X-16213Y654414D01*
G01X-18174Y654435D02*
X-14677Y654398D01*
G01X-19469Y657600D02*
X-16213Y657563D01*
G01X-18174Y657585D02*
X-14677Y657547D01*
G01X-19469Y660749D02*
X-16213Y660713D01*
G01X-18174Y660735D02*
X-14677Y660697D01*
G01X-19469Y663899D02*
X-16213Y663863D01*
G01X-18174Y663884D02*
X-14677Y663846D01*
G01X-19469Y667048D02*
X-16213Y667012D01*
G01X-18174Y667034D02*
X-14677Y666996D01*
G01X-19469Y670198D02*
X-16213Y670162D01*
G01X-18174Y670183D02*
X-14677Y670146D01*
G01X-19469Y673348D02*
X-16213Y673311D01*
G01X-18174Y673333D02*
X-14677Y673295D01*
G01X-19469Y676497D02*
X-16213Y676461D01*
G01X-18174Y676483D02*
X-14677Y676445D01*
G01X-19469Y679647D02*
X-16213Y679611D01*
G01X-18174Y679632D02*
X-14677Y679594D01*
G01X-19469Y682796D02*
X-16213Y682760D01*
G01X-18174Y682782D02*
X-14677Y682744D01*
G01X-19469Y685946D02*
X-16213Y685910D01*
G01X-18174Y685931D02*
X-14677Y685894D01*
G01X-19469Y689096D02*
X-16213Y689059D01*
G01X-18174Y689081D02*
X-14677Y689043D01*
G01X-19469Y692245D02*
X-16213Y692209D01*
G01X-18174Y692231D02*
X-14677Y692193D01*
G01X-19469Y695395D02*
X-16213Y695359D01*
G01X-18174Y695380D02*
X-14677Y695343D01*
G01X-19469Y698544D02*
X-16213Y698508D01*
G01X-18174Y698530D02*
X-14677Y698492D01*
G01X-19469Y701694D02*
X-16213Y701658D01*
G01X-18174Y701680D02*
X-14677Y701642D01*
G01X-19469Y696274D02*
X-18174Y696289D01*
G01X-18435D02*
X-20801Y696263D01*
G01X-18174Y696289D02*
X-17126Y696300D01*
G01X-19469Y699424D02*
X-18174Y699438D01*
G01X-18435D02*
X-20801Y699412D01*
G01X-18174Y699438D02*
X-17126Y699450D01*
G01X-15985Y696310D02*
X-14449Y696327D01*
G01X-14677D02*
X-18174Y696289D01*
G01X-14677Y696327D02*
X-16213Y696310D01*
G01X-15985Y699460D02*
X-14449Y699476D01*
G01X-14677D02*
X-18174Y699438D01*
G01X-14677Y699476D02*
X-16213Y699460D01*
G01X-19469Y696274D02*
X-20801Y696263D01*
G01X-19469Y699424D02*
X-20801Y699412D01*
G01X-15985Y696310D02*
X-17126Y696300D01*
G01D02*
X-18435Y696289D01*
G01X-15985Y699460D02*
X-17126Y699450D01*
G01D02*
X-18435Y699438D01*
G01X512Y700165D02*
X0D01*
G01X512Y700953D02*
X0D01*
G01X-13009Y701346D02*
X-14147D01*
G01X12410Y701543D02*
X315D01*
G01X-14449Y701642D02*
X-14677D01*
G01X-15985Y701658D02*
X-16213D01*
G01X-18174Y701680D02*
X-18435D01*
G01X-14537Y699564D02*
X-14677Y699476D01*
G01X-13977Y699772D02*
X-14449Y699476D01*
G01X-14537Y696415D02*
X-14677Y696327D01*
G01X-13977Y696622D02*
X-14449Y696327D01*
G01X-14537Y693265D02*
X-14677Y693177D01*
G01X-13977Y693472D02*
X-14449Y693177D01*
G01X-14537Y690115D02*
X-14677Y690028D01*
G01X-13977Y690323D02*
X-14449Y690028D01*
G01X-14537Y686966D02*
X-14677Y686878D01*
G01X-13977Y687173D02*
X-14449Y686878D01*
G01X-14537Y683816D02*
X-14677Y683728D01*
G01X-13977Y684024D02*
X-14449Y683728D01*
G01X-14537Y680667D02*
X-14677Y680579D01*
G01X-13977Y680874D02*
X-14449Y680579D01*
G01X-14537Y677517D02*
X-14677Y677429D01*
G01X-13977Y677724D02*
X-14449Y677429D01*
G01X-14537Y674367D02*
X-14677Y674280D01*
G01X-13977Y674575D02*
X-14449Y674280D01*
G01X-14537Y671218D02*
X-14677Y671130D01*
G01X-13977Y671425D02*
X-14449Y671130D01*
G01X-14537Y668068D02*
X-14677Y667980D01*
G01X-13977Y668276D02*
X-14449Y667980D01*
G01X-14537Y664919D02*
X-14677Y664831D01*
G01X-13977Y665126D02*
X-14449Y664831D01*
G01X-14537Y661769D02*
X-14677Y661681D01*
G01X-13977Y661976D02*
X-14449Y661681D01*
G01X-14537Y658619D02*
X-14677Y658531D01*
G01X-13977Y658827D02*
X-14449Y658531D01*
G01X-14537Y655470D02*
X-14677Y655382D01*
G01X-13977Y655677D02*
X-14449Y655382D01*
G01X-14537Y652320D02*
X-14677Y652232D01*
G01X-13977Y652528D02*
X-14449Y652232D01*
G01X-14537Y649170D02*
X-14677Y649083D01*
G01X-13977Y649378D02*
X-14449Y649083D01*
G01X-14537Y646021D02*
X-14677Y645933D01*
G01X-13977Y646228D02*
X-14449Y645933D01*
G01X-14147Y699772D02*
X-14537Y699564D01*
G01X-14147Y696622D02*
X-14537Y696415D01*
G01X-14147Y693472D02*
X-14537Y693265D01*
G01X-14147Y690323D02*
X-14537Y690115D01*
G01X-14147Y687173D02*
X-14537Y686966D01*
G01X-14147Y684024D02*
X-14537Y683816D01*
G01X-14147Y680874D02*
X-14537Y680667D01*
G01X-14147Y677724D02*
X-14537Y677517D01*
G01X-14147Y674575D02*
X-14537Y674367D01*
G01X-14147Y671425D02*
X-14537Y671218D01*
G01X-14147Y668276D02*
X-14537Y668068D01*
G01X-14147Y665126D02*
X-14537Y664919D01*
G01X-14147Y661976D02*
X-14537Y661769D01*
G01X-14147Y658827D02*
X-14537Y658619D01*
G01X-14147Y655677D02*
X-14537Y655470D01*
G01X-14147Y652528D02*
X-14537Y652320D01*
G01X-14147Y649378D02*
X-14537Y649170D01*
G01X-14147Y646228D02*
X-14537Y646021D01*
G01X-20801Y642719D02*
Y641863D01*
G01Y645869D02*
Y645013D01*
G01Y639570D02*
Y638714D01*
G01Y633270D02*
Y632415D01*
G01Y636420D02*
Y635564D01*
G01X-19469Y642725D02*
Y641857D01*
G01Y645875D02*
Y645007D01*
G01Y639576D02*
Y638708D01*
G01Y633276D02*
Y632409D01*
G01Y636426D02*
Y635558D01*
G01X-18435Y642745D02*
Y641837D01*
G01Y645895D02*
Y644987D01*
G01Y639596D02*
Y638687D01*
G01Y633296D02*
Y632388D01*
G01Y636446D02*
Y635538D01*
G01X-18174Y642745D02*
Y641837D01*
G01Y645895D02*
Y644987D01*
G01Y639596D02*
Y638687D01*
G01Y633296D02*
Y632388D01*
G01Y636446D02*
Y635538D01*
G01X-16213Y642767D02*
Y641815D01*
G01Y645917D02*
Y644965D01*
G01Y639617D02*
Y638666D01*
G01Y633318D02*
Y632367D01*
G01Y636468D02*
Y635516D01*
G01X-15985Y642767D02*
Y641815D01*
G01Y645917D02*
Y644965D01*
G01Y639617D02*
Y638666D01*
G01Y633318D02*
Y632367D01*
G01Y636468D02*
Y635516D01*
G01X-14537Y632263D02*
X-14147Y632055D01*
G01X-14537Y635412D02*
X-14147Y635205D01*
G01X-14537Y638562D02*
X-14147Y638354D01*
G01X-14537Y641711D02*
X-14147Y641504D01*
G01X-14537Y644861D02*
X-14147Y644654D01*
G01X-14677Y632350D02*
X-14537Y632263D01*
G01X-14449Y632350D02*
X-13977Y632055D01*
G01X-14677Y635500D02*
X-14537Y635412D01*
G01X-14449Y635500D02*
X-13977Y635205D01*
G01X-14677Y638650D02*
X-14537Y638562D01*
G01X-14449Y638650D02*
X-13977Y638354D01*
G01X-14677Y641799D02*
X-14537Y641711D01*
G01X-14449Y641799D02*
X-13977Y641504D01*
G01X-14677Y644949D02*
X-14537Y644861D01*
G01X-14449Y644949D02*
X-13977Y644654D01*
G01X-14537Y642871D02*
Y641711D01*
G01Y646021D02*
Y644861D01*
G01Y639722D02*
Y638562D01*
G01Y633422D02*
Y632263D01*
G01Y636572D02*
Y635412D01*
G01X-13009Y643079D02*
Y641504D01*
G01Y646228D02*
Y644654D01*
G01Y639929D02*
Y638354D01*
G01Y633630D02*
Y632055D01*
G01Y636780D02*
Y635205D01*
G01X315Y643472D02*
Y642882D01*
G01Y644850D02*
Y644260D01*
G01Y640323D02*
Y639732D01*
G01Y638551D02*
Y637961D01*
G01Y641701D02*
Y641110D01*
G01Y634024D02*
Y633433D01*
G01Y637173D02*
Y636583D01*
G01Y635402D02*
Y634811D01*
G01Y630874D02*
Y630283D01*
G01Y632252D02*
Y631661D01*
G01X512Y643472D02*
Y642882D01*
G01Y644850D02*
Y644260D01*
G01Y640323D02*
Y639732D01*
G01Y638551D02*
Y637961D01*
G01Y641701D02*
Y641110D01*
G01Y634024D02*
Y633433D01*
G01Y637173D02*
Y636583D01*
G01Y635402D02*
Y634811D01*
G01Y630874D02*
Y630283D01*
G01Y632252D02*
Y631661D01*
G01X709Y642882D02*
Y641701D01*
G01Y646031D02*
Y644850D01*
G01Y639732D02*
Y638551D01*
G01Y633433D02*
Y632252D01*
G01Y636583D02*
Y635402D01*
G01X1074Y642882D02*
Y641701D01*
G01Y646031D02*
Y644850D01*
G01Y639732D02*
Y638551D01*
G01Y633433D02*
Y632252D01*
G01Y636583D02*
Y635402D01*
G01X1184Y642882D02*
Y641701D01*
G01Y646031D02*
Y644850D01*
G01Y639732D02*
Y638551D01*
G01Y633433D02*
Y632252D01*
G01Y636583D02*
Y635402D01*
G01X9965Y642882D02*
Y641701D01*
G01Y646031D02*
Y644850D01*
G01Y639732D02*
Y638551D01*
G01Y633433D02*
Y632252D01*
G01Y636583D02*
Y635402D01*
G01X10075Y642882D02*
Y641701D01*
G01Y646031D02*
Y644850D01*
G01Y639732D02*
Y638551D01*
G01Y633433D02*
Y632252D01*
G01Y636583D02*
Y635402D01*
G01X-19469Y630133D02*
X-18174Y630147D01*
G01X-18435D02*
X-20801Y630121D01*
G01X-18174Y630147D02*
X-17126Y630158D01*
G01X-19469Y633282D02*
X-18174Y633296D01*
G01X-18435D02*
X-20801Y633270D01*
G01X-18174Y633296D02*
X-17126Y633308D01*
G01X-19469Y636432D02*
X-18174Y636446D01*
G01X-18435D02*
X-20801Y636420D01*
G01X-18174Y636446D02*
X-17126Y636457D01*
G01X-19469Y639581D02*
X-18174Y639596D01*
G01X-18435D02*
X-20801Y639570D01*
G01X-18174Y639596D02*
X-17126Y639607D01*
G01X-19469Y642731D02*
X-18174Y642745D01*
G01X-18435D02*
X-20801Y642719D01*
G01X-18174Y642745D02*
X-17126Y642757D01*
G01X-15985Y630169D02*
X-14449Y630185D01*
G01X-14677D02*
X-18174Y630147D01*
G01X-14677Y630185D02*
X-16213Y630169D01*
G01X-15985Y633318D02*
X-14449Y633335D01*
G01X-14677D02*
X-18174Y633296D01*
G01X-14677Y633335D02*
X-16213Y633318D01*
G01X-15985Y636468D02*
X-14449Y636484D01*
G01X-14677D02*
X-18174Y636446D01*
G01X-14677Y636484D02*
X-16213Y636468D01*
G01X-15985Y639617D02*
X-14449Y639634D01*
G01X-14677D02*
X-18174Y639596D01*
G01X-14677Y639634D02*
X-16213Y639617D01*
G01X-15985Y642767D02*
X-14449Y642783D01*
G01X-14677D02*
X-18174Y642745D01*
G01X-14677Y642783D02*
X-16213Y642767D01*
G01X-19469Y630133D02*
X-20801Y630121D01*
G01X-19469Y633282D02*
X-20801Y633270D01*
G01X-19469Y636432D02*
X-20801Y636420D01*
G01X-19469Y639581D02*
X-20801Y639570D01*
G01X-19469Y642731D02*
X-20801Y642719D01*
G01X-15985Y630169D02*
X-17126Y630158D01*
G01D02*
X-18435Y630147D01*
G01X-15985Y633318D02*
X-17126Y633308D01*
G01D02*
X-18435Y633296D01*
G01X-15985Y636468D02*
X-17126Y636457D01*
G01D02*
X-18435Y636446D01*
G01X-15985Y639617D02*
X-17126Y639607D01*
G01D02*
X-18435Y639596D01*
G01X-15985Y642767D02*
X-17126Y642757D01*
G01D02*
X-18435Y642745D01*
G01X-18174Y630147D02*
X-18435D01*
G01X-15985Y630169D02*
X-16213D01*
G01X-14449Y630185D02*
X-14677D01*
G01X12410Y630283D02*
X315D01*
G01X-13009Y630480D02*
X-14147D01*
G01X512Y630874D02*
X0D01*
G01X512Y631661D02*
X0D01*
G01X-13009Y632055D02*
X-14147D01*
G01X12410Y632252D02*
X315D01*
G01X-14449Y632350D02*
X-14677D01*
G01X-15985Y632367D02*
X-16213D01*
G01X-18174Y632388D02*
X-18435D01*
G01X-18174Y633296D02*
X-18435D01*
G01X-15985Y633318D02*
X-16213D01*
G01X-14449Y633335D02*
X-14677D01*
G01X12410Y633433D02*
X315D01*
G01X-13009Y633630D02*
X-14147D01*
G01X512Y634024D02*
X0D01*
G01X512Y634811D02*
X0D01*
G01X-13009Y635205D02*
X-14147D01*
G01X12410Y635402D02*
X315D01*
G01X-14449Y635500D02*
X-14677D01*
G01X-15985Y635516D02*
X-16213D01*
G01X-18174Y635538D02*
X-18435D01*
G01X-18174Y636446D02*
X-18435D01*
G01X-15985Y636468D02*
X-16213D01*
G01X-14449Y636484D02*
X-14677D01*
G01X12410Y636583D02*
X315D01*
G01X-13009Y636780D02*
X-14147D01*
G01X512Y637173D02*
X0D01*
G01X512Y637961D02*
X0D01*
G01X-13009Y638354D02*
X-14147D01*
G01X12410Y638551D02*
X315D01*
G01X-14449Y638650D02*
X-14677D01*
G01X-15985Y638666D02*
X-16213D01*
G01X-18174Y638687D02*
X-18435D01*
G01X-18174Y639596D02*
X-18435D01*
G01X-15985Y639617D02*
X-16213D01*
G01X-14449Y639634D02*
X-14677D01*
G01X12410Y639732D02*
X315D01*
G01X-13009Y639929D02*
X-14147D01*
G01X512Y640323D02*
X0D01*
G01X512Y641110D02*
X0D01*
G01X-13009Y641504D02*
X-14147D01*
G01X12410Y641701D02*
X315D01*
G01X-14449Y641799D02*
X-14677D01*
G01X-15985Y641815D02*
X-16213D01*
G01X-18174Y641837D02*
X-18435D01*
G01X-18174Y642745D02*
X-18435D01*
G01X-15985Y642767D02*
X-16213D01*
G01X-14449Y642783D02*
X-14677D01*
G01X12410Y642882D02*
X315D01*
G01X-13009Y643079D02*
X-14147D01*
G01X512Y643472D02*
X0D01*
G01X512Y644260D02*
X0D01*
G01X-13009Y644654D02*
X-14147D01*
G01X12410Y644850D02*
X315D01*
G01X-14449Y644949D02*
X-14677D01*
G01X-15985Y644965D02*
X-16213D01*
G01X-18174Y644987D02*
X-18435D01*
G01X-19469Y632403D02*
X-20801Y632415D01*
G01X-15985Y632367D02*
X-18435Y632388D01*
G01X-19469Y635552D02*
X-20801Y635564D01*
G01X-15985Y635516D02*
X-18435Y635538D01*
G01X-19469Y638702D02*
X-20801Y638714D01*
G01X-15985Y638666D02*
X-18435Y638687D01*
G01X-19469Y641852D02*
X-20801Y641863D01*
G01X-15985Y641815D02*
X-18435Y641837D01*
G01X-19469Y645001D02*
X-20801Y645013D01*
G01X-15985Y644965D02*
X-18435Y644987D01*
G01X-15985Y632367D02*
X-14449Y632350D01*
G01X-15985Y635516D02*
X-14449Y635500D01*
G01X-15985Y638666D02*
X-14449Y638650D01*
G01X-15985Y641815D02*
X-14449Y641799D01*
G01X-15985Y644965D02*
X-14449Y644949D01*
G01X-18435Y632388D02*
X-20801Y632415D01*
G01X-18435Y635538D02*
X-20801Y635564D01*
G01X-18435Y638687D02*
X-20801Y638714D01*
G01X-18435Y641837D02*
X-20801Y641863D01*
G01X-18435Y644987D02*
X-20801Y645013D01*
G01X-19469Y632403D02*
X-16213Y632367D01*
G01X-18174Y632388D02*
X-14677Y632350D01*
G01X-19469Y635552D02*
X-16213Y635516D01*
G01X-18174Y635538D02*
X-14677Y635500D01*
G01X-19469Y638702D02*
X-16213Y638666D01*
G01X-18174Y638687D02*
X-14677Y638650D01*
G01X-19469Y641852D02*
X-16213Y641815D01*
G01X-18174Y641837D02*
X-14677Y641799D01*
G01X-19469Y645001D02*
X-16213Y644965D01*
G01X-18174Y644987D02*
X-14677Y644949D01*
G01X-14537Y642871D02*
X-14677Y642783D01*
G01X-13977Y643079D02*
X-14449Y642783D01*
G01X-14537Y639722D02*
X-14677Y639634D01*
G01X-13977Y639929D02*
X-14449Y639634D01*
G01X-14537Y636572D02*
X-14677Y636484D01*
G01X-13977Y636780D02*
X-14449Y636484D01*
G01X-14537Y633422D02*
X-14677Y633335D01*
G01X-13977Y633630D02*
X-14449Y633335D01*
G01X-14537Y630273D02*
X-14677Y630185D01*
G01X-13977Y630480D02*
X-14449Y630185D01*
G01X-14147Y643079D02*
X-14537Y642871D01*
G01X-14147Y639929D02*
X-14537Y639722D01*
G01X-14147Y636780D02*
X-14537Y636572D01*
G01X-14147Y633630D02*
X-14537Y633422D01*
G01X-14147Y630480D02*
X-14537Y630273D01*
G01X12057Y705874D02*
X12287Y705618D01*
G01X12057Y709024D02*
X12287Y708768D01*
G01X12057Y712173D02*
X12287Y711917D01*
G01X12057Y715323D02*
X12287Y715067D01*
G01X12057Y718472D02*
X12287Y718217D01*
G01X12057Y721622D02*
X12287Y721366D01*
G01X12057Y724772D02*
X12287Y724516D01*
G01X12057Y727921D02*
X12287Y727665D01*
G01X12057Y731071D02*
X12287Y730815D01*
G01X12057Y734220D02*
X12287Y733965D01*
G01X12416Y705888D02*
X12634Y705618D01*
G01X12416Y709038D02*
X12634Y708768D01*
G01X12416Y712187D02*
X12634Y711917D01*
G01X12416Y715337D02*
X12634Y715067D01*
G01X12416Y718487D02*
X12634Y718217D01*
G01X12416Y721636D02*
X12634Y721366D01*
G01X12416Y724786D02*
X12634Y724516D01*
G01X12416Y727935D02*
X12634Y727665D01*
G01X12416Y731085D02*
X12634Y730815D01*
G01X12416Y734235D02*
X12634Y733965D01*
G01X12057Y734220D02*
Y733039D01*
G01Y727921D02*
Y726740D01*
G01Y731071D02*
Y729890D01*
G01Y724772D02*
Y723591D01*
G01Y718472D02*
Y717291D01*
G01Y721622D02*
Y720441D01*
G01Y715323D02*
Y714142D01*
G01Y709024D02*
Y707843D01*
G01Y712173D02*
Y710992D01*
G01X12410Y734220D02*
Y733039D01*
G01Y727921D02*
Y726740D01*
G01Y731071D02*
Y729890D01*
G01Y724772D02*
Y723591D01*
G01Y718472D02*
Y717291D01*
G01Y721622D02*
Y720441D01*
G01Y715323D02*
Y714142D01*
G01Y709024D02*
Y707843D01*
G01Y712173D02*
Y710992D01*
G01X13353Y733965D02*
Y733295D01*
G01Y727665D02*
Y726996D01*
G01Y730815D02*
Y730146D01*
G01Y724516D02*
Y723846D01*
G01Y718217D02*
Y717547D01*
G01Y721366D02*
Y720697D01*
G01Y715067D02*
Y714398D01*
G01Y708768D02*
Y708098D01*
G01Y711917D02*
Y711248D01*
G01X13701Y733965D02*
Y733295D01*
G01Y727665D02*
Y726996D01*
G01Y730815D02*
Y730146D01*
G01Y724516D02*
Y723846D01*
G01Y718217D02*
Y717547D01*
G01Y721366D02*
Y720697D01*
G01Y715067D02*
Y714398D01*
G01Y708768D02*
Y708098D01*
G01Y711917D02*
Y711248D01*
G01X19685Y743472D02*
Y739535D01*
G01X17717Y745441D02*
X19685Y743472D01*
G01X12634Y733295D02*
X12416Y733025D01*
G01X12634Y730146D02*
X12416Y729876D01*
G01X13701Y705618D02*
X12287D01*
G01X13701Y708098D02*
X12287D01*
G01X13701Y708768D02*
X12287D01*
G01X13701Y711248D02*
X12287D01*
G01X13701Y711917D02*
X12287D01*
G01X13701Y714398D02*
X12287D01*
G01X13701Y715067D02*
X12287D01*
G01X13701Y717547D02*
X12287D01*
G01X13701Y718217D02*
X12287D01*
G01X13701Y720697D02*
X12287D01*
G01X13701Y721366D02*
X12287D01*
G01X13701Y723846D02*
X12287D01*
G01X13701Y724516D02*
X12287D01*
G01X13701Y726996D02*
X12287D01*
G01X13701Y727665D02*
X12287D01*
G01X13701Y730146D02*
X12287D01*
G01X13701Y730815D02*
X12287D01*
G01X13701Y733295D02*
X12287D01*
G01X13701Y733965D02*
X12287D01*
G01X12634Y726996D02*
X12416Y726726D01*
G01X12634Y723846D02*
X12416Y723576D01*
G01X12634Y720697D02*
X12416Y720427D01*
G01X12634Y717547D02*
X12416Y717277D01*
G01X12634Y714398D02*
X12416Y714128D01*
G01X12634Y711248D02*
X12416Y710978D01*
G01X12634Y708098D02*
X12416Y707828D01*
G01X12287Y733295D02*
X12057Y733039D01*
G01X12287Y730146D02*
X12057Y729890D01*
G01X12287Y726996D02*
X12057Y726740D01*
G01X12287Y723846D02*
X12057Y723591D01*
G01X12287Y720697D02*
X12057Y720441D01*
G01X12287Y717547D02*
X12057Y717291D01*
G01X12287Y714398D02*
X12057Y714142D01*
G01X12287Y711248D02*
X12057Y710992D01*
G01X12287Y708098D02*
X12057Y707843D01*
G01X19685Y739535D02*
X17717Y737567D01*
G01X17323Y737173D02*
G03Y745835I0J4331D01*
G01X12416Y765731D02*
X12634Y765461D01*
G01X12416Y768880D02*
X12634Y768610D01*
G01X12416Y772030D02*
X12634Y771760D01*
G01X12416Y775180D02*
X12634Y774909D01*
G01X12057Y775165D02*
Y773984D01*
G01Y768866D02*
Y767685D01*
G01Y772016D02*
Y770835D01*
G01X12410Y775165D02*
Y773984D01*
G01Y768866D02*
Y767685D01*
G01Y772016D02*
Y770835D01*
G01X13353Y774909D02*
Y774240D01*
G01Y771760D02*
Y771091D01*
G01Y768610D02*
Y767941D01*
G01X13701Y774909D02*
Y774240D01*
G01Y771760D02*
Y771091D01*
G01Y768610D02*
Y767941D01*
G01X12057Y765717D02*
X12287Y765461D01*
G01X12057Y768866D02*
X12287Y768610D01*
G01X12057Y772016D02*
X12287Y771760D01*
G01X12057Y775165D02*
X12287Y774909D01*
G01X12634Y774240D02*
X12416Y773970D01*
G01X12634Y771091D02*
X12416Y770820D01*
G01X12634Y767941D02*
X12416Y767671D01*
G01X12287Y774240D02*
X12057Y773984D01*
G01X12287Y771091D02*
X12057Y770835D01*
G01X13701Y765461D02*
X12287D01*
G01X13701Y767941D02*
X12287D01*
G01X13701Y768610D02*
X12287D01*
G01X13701Y771091D02*
X12287D01*
G01X13701Y771760D02*
X12287D01*
G01X13701Y774240D02*
X12287D01*
G01X13701Y774909D02*
X12287D01*
G01Y767941D02*
X12057Y767685D01*
G01Y749969D02*
X12287Y749713D01*
G01X12057Y753118D02*
X12287Y752862D01*
G01X12057Y756268D02*
X12287Y756012D01*
G01X12057Y759417D02*
X12287Y759161D01*
G01X12057Y762567D02*
X12287Y762311D01*
G01X12416Y749983D02*
X12634Y749713D01*
G01X12416Y753132D02*
X12634Y752862D01*
G01X12416Y756282D02*
X12634Y756012D01*
G01X12416Y759431D02*
X12634Y759161D01*
G01X12416Y762581D02*
X12634Y762311D01*
G01X12057Y765717D02*
Y764535D01*
G01Y759417D02*
Y758236D01*
G01Y762567D02*
Y761386D01*
G01Y756268D02*
Y755087D01*
G01Y753118D02*
Y751937D01*
G01Y749969D02*
Y748787D01*
G01X12410Y765717D02*
Y764535D01*
G01Y759417D02*
Y758236D01*
G01Y762567D02*
Y761386D01*
G01Y756268D02*
Y755087D01*
G01Y753118D02*
Y751937D01*
G01Y749969D02*
Y748787D01*
G01X13353Y765461D02*
Y764791D01*
G01Y762311D02*
Y761642D01*
G01Y756012D02*
Y755343D01*
G01Y759161D02*
Y758492D01*
G01Y752862D02*
Y752193D01*
G01Y749713D02*
Y749043D01*
G01X13701Y765461D02*
Y764791D01*
G01Y762311D02*
Y761642D01*
G01Y756012D02*
Y755343D01*
G01Y759161D02*
Y758492D01*
G01Y752862D02*
Y752193D01*
G01Y749713D02*
Y749043D01*
G01X12634Y764791D02*
X12416Y764521D01*
G01X12634Y761642D02*
X12416Y761372D01*
G01X12634Y758492D02*
X12416Y758222D01*
G01X12634Y755343D02*
X12416Y755072D01*
G01X12634Y752193D02*
X12416Y751923D01*
G01X12634Y749043D02*
X12416Y748773D01*
G01X13701Y749043D02*
X12287D01*
G01X13701Y749713D02*
X12287D01*
G01X13701Y752193D02*
X12287D01*
G01X13701Y752862D02*
X12287D01*
G01X13701Y755343D02*
X12287D01*
G01X13701Y756012D02*
X12287D01*
G01X13701Y758492D02*
X12287D01*
G01X13701Y759161D02*
X12287D01*
G01X13701Y761642D02*
X12287D01*
G01X13701Y762311D02*
X12287D01*
G01X13701Y764791D02*
X12287D01*
G01D02*
X12057Y764535D01*
G01X12287Y761642D02*
X12057Y761386D01*
G01X12287Y758492D02*
X12057Y758236D01*
G01X12287Y755343D02*
X12057Y755087D01*
G01X12287Y752193D02*
X12057Y751937D01*
G01X12287Y749043D02*
X12057Y748787D01*
G01Y705874D02*
Y704693D01*
G01X12410Y705874D02*
Y704693D01*
G01X13353Y705618D02*
Y704949D01*
G01X13701Y705618D02*
Y704949D01*
G01Y702469D02*
X12287D01*
G01X13701Y704949D02*
X12287D01*
G01X12634D02*
X12416Y704679D01*
G01X12287Y704949D02*
X12057Y704693D01*
G01X-20801Y734058D02*
Y733202D01*
G01Y727759D02*
Y726903D01*
G01Y730908D02*
Y730052D01*
G01Y724609D02*
Y723753D01*
G01Y718310D02*
Y717454D01*
G01Y721459D02*
Y720604D01*
G01Y715160D02*
Y714304D01*
G01Y708861D02*
Y708005D01*
G01Y712011D02*
Y711155D01*
G01X-19469Y734064D02*
Y733196D01*
G01Y727765D02*
Y726897D01*
G01Y730914D02*
Y730046D01*
G01Y724615D02*
Y723747D01*
G01Y718316D02*
Y717448D01*
G01Y721465D02*
Y720598D01*
G01Y715166D02*
Y714298D01*
G01Y708867D02*
Y707999D01*
G01Y712017D02*
Y711149D01*
G01X-18435Y734084D02*
Y733176D01*
G01Y727785D02*
Y726876D01*
G01Y730934D02*
Y730026D01*
G01Y724635D02*
Y723727D01*
G01Y718336D02*
Y717428D01*
G01Y721485D02*
Y720577D01*
G01Y715186D02*
Y714278D01*
G01Y708887D02*
Y707979D01*
G01Y712037D02*
Y711128D01*
G01X-18174Y734084D02*
Y733176D01*
G01Y727785D02*
Y726876D01*
G01Y730934D02*
Y730026D01*
G01Y724635D02*
Y723727D01*
G01Y718336D02*
Y717428D01*
G01Y721485D02*
Y720577D01*
G01Y715186D02*
Y714278D01*
G01Y708887D02*
Y707979D01*
G01Y712037D02*
Y711128D01*
G01X-16213Y734106D02*
Y733154D01*
G01Y727806D02*
Y726855D01*
G01Y730956D02*
Y730004D01*
G01Y724657D02*
Y723705D01*
G01Y718357D02*
Y717406D01*
G01Y721507D02*
Y720556D01*
G01Y715208D02*
Y714256D01*
G01Y708909D02*
Y707957D01*
G01Y712058D02*
Y711107D01*
G01X-15985Y734106D02*
Y733154D01*
G01Y727806D02*
Y726855D01*
G01Y730956D02*
Y730004D01*
G01Y724657D02*
Y723705D01*
G01Y718357D02*
Y717406D01*
G01Y721507D02*
Y720556D01*
G01Y715208D02*
Y714256D01*
G01Y708909D02*
Y707957D01*
G01Y712058D02*
Y711107D01*
G01X-14537Y734210D02*
Y733050D01*
G01Y727911D02*
Y726751D01*
G01Y731060D02*
Y729900D01*
G01Y724761D02*
Y723601D01*
G01Y718462D02*
Y717302D01*
G01Y721611D02*
Y720452D01*
G01Y715312D02*
Y714152D01*
G01Y709013D02*
Y707853D01*
G01Y712163D02*
Y711003D01*
G01X-13009Y734417D02*
Y732843D01*
G01Y728118D02*
Y726543D01*
G01Y731268D02*
Y729693D01*
G01Y724969D02*
Y723394D01*
G01Y718669D02*
Y717094D01*
G01Y721819D02*
Y720244D01*
G01Y715520D02*
Y713945D01*
G01Y709220D02*
Y707646D01*
G01Y712370D02*
Y710795D01*
G01X315Y731661D02*
Y731071D01*
G01Y734811D02*
Y734220D01*
G01Y733039D02*
Y732449D01*
G01Y728512D02*
Y727921D01*
G01Y726740D02*
Y726150D01*
G01Y729890D02*
Y729299D01*
G01Y722213D02*
Y721622D01*
G01Y725362D02*
Y724772D01*
G01Y723591D02*
Y723000D01*
G01Y719063D02*
Y718472D01*
G01Y717291D02*
Y716701D01*
G01Y720441D02*
Y719850D01*
G01Y712764D02*
Y712173D01*
G01Y715913D02*
Y715323D01*
G01Y714142D02*
Y713551D01*
G01Y709614D02*
Y709024D01*
G01Y710992D02*
Y710402D01*
G01Y706465D02*
Y705874D01*
G01Y707843D02*
Y707252D01*
G01X512Y731661D02*
Y731071D01*
G01Y734811D02*
Y734220D01*
G01Y733039D02*
Y732449D01*
G01Y728512D02*
Y727921D01*
G01Y726740D02*
Y726150D01*
G01Y729890D02*
Y729299D01*
G01Y722213D02*
Y721622D01*
G01Y725362D02*
Y724772D01*
G01Y723591D02*
Y723000D01*
G01Y719063D02*
Y718472D01*
G01Y717291D02*
Y716701D01*
G01Y720441D02*
Y719850D01*
G01Y712764D02*
Y712173D01*
G01Y715913D02*
Y715323D01*
G01Y714142D02*
Y713551D01*
G01Y709614D02*
Y709024D01*
G01Y710992D02*
Y710402D01*
G01Y706465D02*
Y705874D01*
G01Y707843D02*
Y707252D01*
G01X709Y734220D02*
Y733039D01*
G01Y727921D02*
Y726740D01*
G01Y731071D02*
Y729890D01*
G01Y724772D02*
Y723591D01*
G01Y718472D02*
Y717291D01*
G01Y721622D02*
Y720441D01*
G01Y715323D02*
Y714142D01*
G01Y709024D02*
Y707843D01*
G01Y712173D02*
Y710992D01*
G01X1074Y734220D02*
Y733039D01*
G01Y727921D02*
Y726740D01*
G01Y731071D02*
Y729890D01*
G01Y724772D02*
Y723591D01*
G01Y718472D02*
Y717291D01*
G01Y721622D02*
Y720441D01*
G01Y715323D02*
Y714142D01*
G01Y709024D02*
Y707843D01*
G01Y712173D02*
Y710992D01*
G01X1184Y734220D02*
Y733039D01*
G01Y727921D02*
Y726740D01*
G01Y731071D02*
Y729890D01*
G01Y724772D02*
Y723591D01*
G01Y718472D02*
Y717291D01*
G01Y721622D02*
Y720441D01*
G01Y715323D02*
Y714142D01*
G01Y709024D02*
Y707843D01*
G01Y712173D02*
Y710992D01*
G01X9965Y734220D02*
Y733039D01*
G01Y727921D02*
Y726740D01*
G01Y731071D02*
Y729890D01*
G01Y724772D02*
Y723591D01*
G01Y718472D02*
Y717291D01*
G01Y721622D02*
Y720441D01*
G01Y715323D02*
Y714142D01*
G01Y709024D02*
Y707843D01*
G01Y712173D02*
Y710992D01*
G01X10075Y734220D02*
Y733039D01*
G01Y727921D02*
Y726740D01*
G01Y731071D02*
Y729890D01*
G01Y724772D02*
Y723591D01*
G01Y718472D02*
Y717291D01*
G01Y721622D02*
Y720441D01*
G01Y715323D02*
Y714142D01*
G01Y709024D02*
Y707843D01*
G01Y712173D02*
Y710992D01*
G01X-30709Y739535D02*
X-26772Y737567D01*
G01X-14537Y707853D02*
X-14147Y707646D01*
G01X-14537Y711003D02*
X-14147Y710795D01*
G01X-14537Y714152D02*
X-14147Y713945D01*
G01X-14537Y717302D02*
X-14147Y717094D01*
G01X-14537Y720452D02*
X-14147Y720244D01*
G01X-14537Y723601D02*
X-14147Y723394D01*
G01X-14537Y726751D02*
X-14147Y726543D01*
G01X-14537Y729900D02*
X-14147Y729693D01*
G01X-14537Y733050D02*
X-14147Y732843D01*
G01X-14677Y707941D02*
X-14537Y707853D01*
G01X-14449Y707941D02*
X-13977Y707646D01*
G01X-14677Y711091D02*
X-14537Y711003D01*
G01X-14449Y711091D02*
X-13977Y710795D01*
G01X-14677Y714240D02*
X-14537Y714152D01*
G01X-14449Y714240D02*
X-13977Y713945D01*
G01X-14677Y717390D02*
X-14537Y717302D01*
G01X-14449Y717390D02*
X-13977Y717094D01*
G01X-14677Y720539D02*
X-14537Y720452D01*
G01X-14449Y720539D02*
X-13977Y720244D01*
G01X-14677Y723689D02*
X-14537Y723601D01*
G01X-14449Y723689D02*
X-13977Y723394D01*
G01X-14677Y726839D02*
X-14537Y726751D01*
G01X-14449Y726839D02*
X-13977Y726543D01*
G01X-14677Y729988D02*
X-14537Y729900D01*
G01X-14449Y729988D02*
X-13977Y729693D01*
G01X-14677Y733138D02*
X-14537Y733050D01*
G01X-14449Y733138D02*
X-13977Y732843D01*
G01X-19469Y705723D02*
X-18174Y705737D01*
G01X-18435D02*
X-20801Y705711D01*
G01X-18174Y705737D02*
X-17126Y705749D01*
G01X-19469Y708873D02*
X-18174Y708887D01*
G01X-18435D02*
X-20801Y708861D01*
G01X-18174Y708887D02*
X-17126Y708898D01*
G01X-19469Y712022D02*
X-18174Y712037D01*
G01X-18435D02*
X-20801Y712011D01*
G01X-18174Y712037D02*
X-17126Y712048D01*
G01X-19469Y715172D02*
X-18174Y715186D01*
G01X-18435D02*
X-20801Y715160D01*
G01X-18174Y715186D02*
X-17126Y715198D01*
G01X-19469Y718322D02*
X-18174Y718336D01*
G01X-18435D02*
X-20801Y718310D01*
G01X-18174Y718336D02*
X-17126Y718347D01*
G01X-19469Y721471D02*
X-18174Y721485D01*
G01X-18435D02*
X-20801Y721459D01*
G01X-18174Y721485D02*
X-17126Y721497D01*
G01X-19469Y724621D02*
X-18174Y724635D01*
G01X-18435D02*
X-20801Y724609D01*
G01X-18174Y724635D02*
X-17126Y724646D01*
G01X-19469Y727770D02*
X-18174Y727785D01*
G01X-18435D02*
X-20801Y727759D01*
G01X-18174Y727785D02*
X-17126Y727796D01*
G01X-19469Y730920D02*
X-18174Y730934D01*
G01X-18435D02*
X-20801Y730908D01*
G01X-18174Y730934D02*
X-17126Y730946D01*
G01X-19469Y734070D02*
X-18174Y734084D01*
G01X-18435D02*
X-20801Y734058D01*
G01X-18174Y734084D02*
X-17126Y734095D01*
G01X-15985Y705759D02*
X-14449Y705776D01*
G01X-14677D02*
X-18174Y705737D01*
G01X-14677Y705776D02*
X-16213Y705759D01*
G01X-15985Y708909D02*
X-14449Y708925D01*
G01X-14677D02*
X-18174Y708887D01*
G01X-14677Y708925D02*
X-16213Y708909D01*
G01X-15985Y712058D02*
X-14449Y712075D01*
G01X-14677D02*
X-18174Y712037D01*
G01X-14677Y712075D02*
X-16213Y712058D01*
G01X-15985Y715208D02*
X-14449Y715224D01*
G01X-14677D02*
X-18174Y715186D01*
G01X-14677Y715224D02*
X-16213Y715208D01*
G01X-15985Y718357D02*
X-14449Y718374D01*
G01X-14677D02*
X-18174Y718336D01*
G01X-14677Y718374D02*
X-16213Y718357D01*
G01X-15985Y721507D02*
X-14449Y721524D01*
G01X-14677D02*
X-18174Y721485D01*
G01X-14677Y721524D02*
X-16213Y721507D01*
G01X-15985Y724657D02*
X-14449Y724673D01*
G01X-14677D02*
X-18174Y724635D01*
G01X-14677Y724673D02*
X-16213Y724657D01*
G01X-15985Y727806D02*
X-14449Y727823D01*
G01X-14677D02*
X-18174Y727785D01*
G01X-14677Y727823D02*
X-16213Y727806D01*
G01X-15985Y730956D02*
X-14449Y730972D01*
G01X-14677D02*
X-18174Y730934D01*
G01X-14677Y730972D02*
X-16213Y730956D01*
G01X-15985Y734106D02*
X-14449Y734122D01*
G01X-14677D02*
X-18174Y734084D01*
G01X-14677Y734122D02*
X-16213Y734106D01*
G01X-19469Y705723D02*
X-20801Y705711D01*
G01X-19469Y708873D02*
X-20801Y708861D01*
G01X-19469Y712022D02*
X-20801Y712011D01*
G01X-19469Y715172D02*
X-20801Y715160D01*
G01X-19469Y718322D02*
X-20801Y718310D01*
G01X-19469Y721471D02*
X-20801Y721459D01*
G01X-19469Y724621D02*
X-20801Y724609D01*
G01X-19469Y727770D02*
X-20801Y727759D01*
G01X-19469Y730920D02*
X-20801Y730908D01*
G01X-19469Y734070D02*
X-20801Y734058D01*
G01X-15985Y705759D02*
X-17126Y705749D01*
G01D02*
X-18435Y705737D01*
G01X-15985Y708909D02*
X-17126Y708898D01*
G01D02*
X-18435Y708887D01*
G01X-15985Y712058D02*
X-17126Y712048D01*
G01D02*
X-18435Y712037D01*
G01X-15985Y715208D02*
X-17126Y715198D01*
G01D02*
X-18435Y715186D01*
G01X-15985Y718357D02*
X-17126Y718347D01*
G01D02*
X-18435Y718336D01*
G01X-15985Y721507D02*
X-17126Y721497D01*
G01D02*
X-18435Y721485D01*
G01X-15985Y724657D02*
X-17126Y724646D01*
G01D02*
X-18435Y724635D01*
G01X-15985Y727806D02*
X-17126Y727796D01*
G01D02*
X-18435Y727785D01*
G01X-15985Y730956D02*
X-17126Y730946D01*
G01D02*
X-18435Y730934D01*
G01X-15985Y734106D02*
X-17126Y734095D01*
G01D02*
X-18435Y734084D01*
G01X-18174Y705737D02*
X-18435D01*
G01X-15985Y705759D02*
X-16213D01*
G01X-14449Y705776D02*
X-14677D01*
G01X12410Y705874D02*
X315D01*
G01X-13009Y706071D02*
X-14147D01*
G01X512Y706465D02*
X0D01*
G01X512Y707252D02*
X0D01*
G01X-13009Y707646D02*
X-14147D01*
G01X12410Y707843D02*
X315D01*
G01X-14449Y707941D02*
X-14677D01*
G01X-15985Y707957D02*
X-16213D01*
G01X-18174Y707979D02*
X-18435D01*
G01X-18174Y708887D02*
X-18435D01*
G01X-15985Y708909D02*
X-16213D01*
G01X-14449Y708925D02*
X-14677D01*
G01X12410Y709024D02*
X315D01*
G01X-13009Y709220D02*
X-14147D01*
G01X512Y709614D02*
X0D01*
G01X512Y710402D02*
X0D01*
G01X-13009Y710795D02*
X-14147D01*
G01X12410Y710992D02*
X315D01*
G01X-14449Y711091D02*
X-14677D01*
G01X-15985Y711107D02*
X-16213D01*
G01X-18174Y711128D02*
X-18435D01*
G01X-18174Y712037D02*
X-18435D01*
G01X-15985Y712058D02*
X-16213D01*
G01X-14449Y712075D02*
X-14677D01*
G01X12410Y712173D02*
X315D01*
G01X-13009Y712370D02*
X-14147D01*
G01X512Y712764D02*
X0D01*
G01X512Y713551D02*
X0D01*
G01X-13009Y713945D02*
X-14147D01*
G01X12410Y714142D02*
X315D01*
G01X-14449Y714240D02*
X-14677D01*
G01X-15985Y714256D02*
X-16213D01*
G01X-18174Y714278D02*
X-18435D01*
G01X-18174Y715186D02*
X-18435D01*
G01X-15985Y715208D02*
X-16213D01*
G01X-14449Y715224D02*
X-14677D01*
G01X12410Y715323D02*
X315D01*
G01X-13009Y715520D02*
X-14147D01*
G01X512Y715913D02*
X0D01*
G01X512Y716701D02*
X0D01*
G01X-13009Y717094D02*
X-14147D01*
G01X12410Y717291D02*
X315D01*
G01X-14449Y717390D02*
X-14677D01*
G01X-15985Y717406D02*
X-16213D01*
G01X-18174Y717428D02*
X-18435D01*
G01X-18174Y718336D02*
X-18435D01*
G01X-15985Y718357D02*
X-16213D01*
G01X-14449Y718374D02*
X-14677D01*
G01X12410Y718472D02*
X315D01*
G01X-13009Y718669D02*
X-14147D01*
G01X512Y719063D02*
X0D01*
G01X512Y719850D02*
X0D01*
G01X-13009Y720244D02*
X-14147D01*
G01X12410Y720441D02*
X315D01*
G01X-14449Y720539D02*
X-14677D01*
G01X-15985Y720556D02*
X-16213D01*
G01X-18174Y720577D02*
X-18435D01*
G01X-18174Y721485D02*
X-18435D01*
G01X-15985Y721507D02*
X-16213D01*
G01X-14449Y721524D02*
X-14677D01*
G01X12410Y721622D02*
X315D01*
G01X-13009Y721819D02*
X-14147D01*
G01X512Y722213D02*
X0D01*
G01X512Y723000D02*
X0D01*
G01X-13009Y723394D02*
X-14147D01*
G01X12410Y723591D02*
X315D01*
G01X-14449Y723689D02*
X-14677D01*
G01X-15985Y723705D02*
X-16213D01*
G01X-18174Y723727D02*
X-18435D01*
G01X-18174Y724635D02*
X-18435D01*
G01X-15985Y724657D02*
X-16213D01*
G01X-14449Y724673D02*
X-14677D01*
G01X12410Y724772D02*
X315D01*
G01X-13009Y724969D02*
X-14147D01*
G01X512Y725362D02*
X0D01*
G01X512Y726150D02*
X0D01*
G01X-13009Y726543D02*
X-14147D01*
G01X12410Y726740D02*
X315D01*
G01X-14449Y726839D02*
X-14677D01*
G01X-15985Y726855D02*
X-16213D01*
G01X-18174Y726876D02*
X-18435D01*
G01X-18174Y727785D02*
X-18435D01*
G01X-15985Y727806D02*
X-16213D01*
G01X-14449Y727823D02*
X-14677D01*
G01X12410Y727921D02*
X315D01*
G01X-13009Y728118D02*
X-14147D01*
G01X512Y728512D02*
X0D01*
G01X512Y729299D02*
X0D01*
G01X-13009Y729693D02*
X-14147D01*
G01X12410Y729890D02*
X315D01*
G01X-14449Y729988D02*
X-14677D01*
G01X-15985Y730004D02*
X-16213D01*
G01X-18174Y730026D02*
X-18435D01*
G01X-18174Y730934D02*
X-18435D01*
G01X-15985Y730956D02*
X-16213D01*
G01X-14449Y730972D02*
X-14677D01*
G01X12410Y731071D02*
X315D01*
G01X-13009Y731268D02*
X-14147D01*
G01X512Y731661D02*
X0D01*
G01X512Y732449D02*
X0D01*
G01X-13009Y732843D02*
X-14147D01*
G01X12410Y733039D02*
X315D01*
G01X-14449Y733138D02*
X-14677D01*
G01X-15985Y733154D02*
X-16213D01*
G01X-18174Y733176D02*
X-18435D01*
G01X-18174Y734084D02*
X-18435D01*
G01X-15985Y734106D02*
X-16213D01*
G01X-14449Y734122D02*
X-14677D01*
G01X12410Y734220D02*
X315D01*
G01X-13009Y734417D02*
X-14147D01*
G01X512Y734811D02*
X0D01*
G01X1969Y737173D02*
X17323D01*
G01X17717Y737567D02*
X0D01*
G01X-26772D02*
X-7283D01*
G01X-19469Y707993D02*
X-20801Y708005D01*
G01X-15985Y707957D02*
X-18435Y707979D01*
G01X-19469Y711143D02*
X-20801Y711155D01*
G01X-15985Y711107D02*
X-18435Y711128D01*
G01X-19469Y714293D02*
X-20801Y714304D01*
G01X-15985Y714256D02*
X-18435Y714278D01*
G01X-19469Y717442D02*
X-20801Y717454D01*
G01X-15985Y717406D02*
X-18435Y717428D01*
G01X-19469Y720592D02*
X-20801Y720604D01*
G01X-15985Y720556D02*
X-18435Y720577D01*
G01X-19469Y723741D02*
X-20801Y723753D01*
G01X-15985Y723705D02*
X-18435Y723727D01*
G01X-19469Y726891D02*
X-20801Y726903D01*
G01X-15985Y726855D02*
X-18435Y726876D01*
G01X-19469Y730041D02*
X-20801Y730052D01*
G01X-15985Y730004D02*
X-18435Y730026D01*
G01X-19469Y733190D02*
X-20801Y733202D01*
G01X-15985Y733154D02*
X-18435Y733176D01*
G01X-15985Y707957D02*
X-14449Y707941D01*
G01X-15985Y711107D02*
X-14449Y711091D01*
G01X-15985Y714256D02*
X-14449Y714240D01*
G01X-15985Y717406D02*
X-14449Y717390D01*
G01X-15985Y720556D02*
X-14449Y720539D01*
G01X-15985Y723705D02*
X-14449Y723689D01*
G01X-15985Y726855D02*
X-14449Y726839D01*
G01X-15985Y730004D02*
X-14449Y729988D01*
G01X-15985Y733154D02*
X-14449Y733138D01*
G01X-18435Y707979D02*
X-20801Y708005D01*
G01X-18435Y711128D02*
X-20801Y711155D01*
G01X-18435Y714278D02*
X-20801Y714304D01*
G01X-18435Y717428D02*
X-20801Y717454D01*
G01X-18435Y720577D02*
X-20801Y720604D01*
G01X-18435Y723727D02*
X-20801Y723753D01*
G01X-18435Y726876D02*
X-20801Y726903D01*
G01X-18435Y730026D02*
X-20801Y730052D01*
G01X-18435Y733176D02*
X-20801Y733202D01*
G01X-19469Y707993D02*
X-16213Y707957D01*
G01X-18174Y707979D02*
X-14677Y707941D01*
G01X-19469Y711143D02*
X-16213Y711107D01*
G01X-18174Y711128D02*
X-14677Y711091D01*
G01X-19469Y714293D02*
X-16213Y714256D01*
G01X-18174Y714278D02*
X-14677Y714240D01*
G01X-19469Y717442D02*
X-16213Y717406D01*
G01X-18174Y717428D02*
X-14677Y717390D01*
G01X-19469Y720592D02*
X-16213Y720556D01*
G01X-18174Y720577D02*
X-14677Y720539D01*
G01X-19469Y723741D02*
X-16213Y723705D01*
G01X-18174Y723727D02*
X-14677Y723689D01*
G01X-19469Y726891D02*
X-16213Y726855D01*
G01X-18174Y726876D02*
X-14677Y726839D01*
G01X-19469Y730041D02*
X-16213Y730004D01*
G01X-18174Y730026D02*
X-14677Y729988D01*
G01X-19469Y733190D02*
X-16213Y733154D01*
G01X-18174Y733176D02*
X-14677Y733138D01*
G01X0Y735205D02*
X1969Y737173D01*
G01X-14537Y734210D02*
X-14677Y734122D01*
G01X-13977Y734417D02*
X-14449Y734122D01*
G01X-14537Y731060D02*
X-14677Y730972D01*
G01X-13977Y731268D02*
X-14449Y730972D01*
G01X-14537Y727911D02*
X-14677Y727823D01*
G01X-13977Y728118D02*
X-14449Y727823D01*
G01X-14537Y724761D02*
X-14677Y724673D01*
G01X-13977Y724969D02*
X-14449Y724673D01*
G01X-14537Y721611D02*
X-14677Y721524D01*
G01X-13977Y721819D02*
X-14449Y721524D01*
G01X-14537Y718462D02*
X-14677Y718374D01*
G01X-13977Y718669D02*
X-14449Y718374D01*
G01X-14537Y715312D02*
X-14677Y715224D01*
G01X-13977Y715520D02*
X-14449Y715224D01*
G01X-14537Y712163D02*
X-14677Y712075D01*
G01X-13977Y712370D02*
X-14449Y712075D01*
G01X-14537Y709013D02*
X-14677Y708925D01*
G01X-13977Y709220D02*
X-14449Y708925D01*
G01X-14537Y705863D02*
X-14677Y705776D01*
G01X-13977Y706071D02*
X-14449Y705776D01*
G01X-14147Y734417D02*
X-14537Y734210D01*
G01X-14147Y731268D02*
X-14537Y731060D01*
G01X-14147Y728118D02*
X-14537Y727911D01*
G01X-14147Y724969D02*
X-14537Y724761D01*
G01X-14147Y721819D02*
X-14537Y721611D01*
G01X-14147Y718669D02*
X-14537Y718462D01*
G01X-14147Y715520D02*
X-14537Y715312D01*
G01X-14147Y712370D02*
X-14537Y712163D01*
G01X-14147Y709220D02*
X-14537Y709013D01*
G01X-14147Y706071D02*
X-14537Y705863D01*
G01X-26772Y745441D02*
X-30709Y743472D01*
G01X-20801Y775003D02*
Y774147D01*
G01Y771853D02*
Y770997D01*
G01Y768704D02*
Y767848D01*
G01X-19469Y775009D02*
Y774141D01*
G01Y771859D02*
Y770991D01*
G01Y768709D02*
Y767842D01*
G01X-18435Y775029D02*
Y774120D01*
G01Y771879D02*
Y770971D01*
G01Y768730D02*
Y767821D01*
G01X-18174Y775029D02*
Y774120D01*
G01Y771879D02*
Y770971D01*
G01Y768730D02*
Y767821D01*
G01X-16213Y775050D02*
Y774099D01*
G01Y768751D02*
Y767800D01*
G01Y771901D02*
Y770949D01*
G01X-15985Y775050D02*
Y774099D01*
G01Y768751D02*
Y767800D01*
G01Y771901D02*
Y770949D01*
G01X-14537Y775155D02*
Y773995D01*
G01Y768856D02*
Y767696D01*
G01Y772005D02*
Y770845D01*
G01X-13009Y775362D02*
Y773787D01*
G01Y769063D02*
Y767488D01*
G01Y772213D02*
Y770638D01*
G01X315Y773984D02*
Y773394D01*
G01Y769457D02*
Y768866D01*
G01Y772606D02*
Y772016D01*
G01Y770835D02*
Y770244D01*
G01Y766307D02*
Y765717D01*
G01Y767685D02*
Y767094D01*
G01X512Y773984D02*
Y773394D01*
G01Y769457D02*
Y768866D01*
G01Y772606D02*
Y772016D01*
G01Y770835D02*
Y770244D01*
G01Y766307D02*
Y765717D01*
G01Y767685D02*
Y767094D01*
G01X709Y775165D02*
Y773984D01*
G01Y768866D02*
Y767685D01*
G01Y772016D02*
Y770835D01*
G01X1074Y775165D02*
Y773984D01*
G01Y768866D02*
Y767685D01*
G01Y772016D02*
Y770835D01*
G01X1184Y775165D02*
Y773984D01*
G01Y768866D02*
Y767685D01*
G01Y772016D02*
Y770835D01*
G01X9965Y775165D02*
Y773984D01*
G01Y768866D02*
Y767685D01*
G01Y772016D02*
Y770835D01*
G01X10075Y775165D02*
Y773984D01*
G01Y768866D02*
Y767685D01*
G01Y772016D02*
Y770835D01*
G01X-14677Y767783D02*
X-14537Y767696D01*
G01X-14449Y767783D02*
X-13977Y767488D01*
G01X-14677Y770933D02*
X-14537Y770845D01*
G01X-14449Y770933D02*
X-13977Y770638D01*
G01X-14677Y774083D02*
X-14537Y773995D01*
G01X-14449Y774083D02*
X-13977Y773787D01*
G01X-14537Y767696D02*
X-14147Y767488D01*
G01X-14537Y770845D02*
X-14147Y770638D01*
G01X-14537Y773995D02*
X-14147Y773787D01*
G01X-19469Y765566D02*
X-18174Y765580D01*
G01X-18435D02*
X-20801Y765554D01*
G01X-18174Y765580D02*
X-17126Y765591D01*
G01X-19469Y768715D02*
X-18174Y768730D01*
G01X-18435D02*
X-20801Y768704D01*
G01X-18174Y768730D02*
X-17126Y768741D01*
G01X-15985Y765602D02*
X-14449Y765618D01*
G01X-14677D02*
X-18174Y765580D01*
G01X-14677Y765618D02*
X-16213Y765602D01*
G01X-15985Y768751D02*
X-14449Y768768D01*
G01X-14677D02*
X-18174Y768730D01*
G01X-14677Y768768D02*
X-16213Y768751D01*
G01X-19469Y765566D02*
X-20801Y765554D01*
G01X-19469Y768715D02*
X-20801Y768704D01*
G01X-15985Y765602D02*
X-17126Y765591D01*
G01D02*
X-18435Y765580D01*
G01X-15985Y768751D02*
X-17126Y768741D01*
G01D02*
X-18435Y768730D01*
G01X-15985Y771901D02*
X-17126Y771891D01*
G01X-18174Y765580D02*
X-18435D01*
G01X-15985Y765602D02*
X-16213D01*
G01X-14449Y765618D02*
X-14677D01*
G01X12410Y765717D02*
X315D01*
G01X-13009Y765913D02*
X-14147D01*
G01X512Y766307D02*
X0D01*
G01X512Y767094D02*
X0D01*
G01X-13009Y767488D02*
X-14147D01*
G01X12410Y767685D02*
X315D01*
G01X-14449Y767783D02*
X-14677D01*
G01X-15985Y767800D02*
X-16213D01*
G01X-18174Y767821D02*
X-18435D01*
G01X-18174Y768730D02*
X-18435D01*
G01X-15985Y768751D02*
X-16213D01*
G01X-14449Y768768D02*
X-14677D01*
G01X12410Y768866D02*
X315D01*
G01X-13009Y769063D02*
X-14147D01*
G01X512Y769457D02*
X0D01*
G01X512Y770244D02*
X0D01*
G01X-13009Y770638D02*
X-14147D01*
G01X12410Y770835D02*
X315D01*
G01X-14449Y770933D02*
X-14677D01*
G01X-15985Y770949D02*
X-16213D01*
G01X-18174Y770971D02*
X-18435D01*
G01X-18174Y771879D02*
X-18435D01*
G01X-15985Y771901D02*
X-16213D01*
G01X-14449Y771917D02*
X-14677D01*
G01X12410Y772016D02*
X315D01*
G01X-13009Y772213D02*
X-14147D01*
G01X512Y772606D02*
X0D01*
G01X512Y773394D02*
X0D01*
G01X-13009Y773787D02*
X-14147D01*
G01X12410Y773984D02*
X315D01*
G01X-14449Y774083D02*
X-14677D01*
G01X-15985Y774099D02*
X-16213D01*
G01X-18174Y774120D02*
X-18435D01*
G01X-18174Y775029D02*
X-18435D01*
G01X-15985Y775050D02*
X-16213D01*
G01X-14449Y775067D02*
X-14677D01*
G01X-19469Y767836D02*
X-20801Y767848D01*
G01X-15985Y767800D02*
X-18435Y767821D01*
G01X-19469Y770985D02*
X-20801Y770997D01*
G01X-15985Y770949D02*
X-18435Y770971D01*
G01X-19469Y774135D02*
X-20801Y774147D01*
G01X-15985Y774099D02*
X-18435Y774120D01*
G01X-15985Y767800D02*
X-14449Y767783D01*
G01X-15985Y770949D02*
X-14449Y770933D01*
G01X-15985Y774099D02*
X-14449Y774083D01*
G01X-18435Y767821D02*
X-20801Y767848D01*
G01X-18435Y770971D02*
X-20801Y770997D01*
G01X-18435Y774120D02*
X-20801Y774147D01*
G01X-19469Y767836D02*
X-16213Y767800D01*
G01X-18174Y767821D02*
X-14677Y767783D01*
G01X-19469Y770985D02*
X-16213Y770949D01*
G01X-18174Y770971D02*
X-14677Y770933D01*
G01X-19469Y774135D02*
X-16213Y774099D01*
G01X-18174Y774120D02*
X-14677Y774083D01*
G01X-19469Y771865D02*
X-18174Y771879D01*
G01X-18435D02*
X-20801Y771853D01*
G01X-18174Y771879D02*
X-17126Y771891D01*
G01X-19469Y775015D02*
X-18174Y775029D01*
G01X-18435D02*
X-20801Y775003D01*
G01X-18174Y775029D02*
X-17126Y775040D01*
G01X-15985Y771901D02*
X-14449Y771917D01*
G01X-14677D02*
X-18174Y771879D01*
G01X-14677Y771917D02*
X-16213Y771901D01*
G01X-15985Y775050D02*
X-14449Y775067D01*
G01X-14677D02*
X-18174Y775029D01*
G01X-14677Y775067D02*
X-16213Y775050D01*
G01X-19469Y771865D02*
X-20801Y771853D01*
G01X-19469Y775015D02*
X-20801Y775003D01*
G01X-17126Y771891D02*
X-18435Y771879D01*
G01X-15985Y775050D02*
X-17126Y775040D01*
G01D02*
X-18435Y775029D01*
G01X-14537Y775155D02*
X-14677Y775067D01*
G01X-13977Y775362D02*
X-14449Y775067D01*
G01X-14537Y772005D02*
X-14677Y771917D01*
G01X-13977Y772213D02*
X-14449Y771917D01*
G01X-14537Y768856D02*
X-14677Y768768D01*
G01X-13977Y769063D02*
X-14449Y768768D01*
G01X-14537Y765706D02*
X-14677Y765618D01*
G01X-13977Y765913D02*
X-14449Y765618D01*
G01X-14147Y775362D02*
X-14537Y775155D01*
G01X-14147Y772213D02*
X-14537Y772005D01*
G01X-14147Y769063D02*
X-14537Y768856D01*
G01X-14147Y765913D02*
X-14537Y765706D01*
G01X-26772Y924575D02*
Y745441D01*
G01X-20801Y765554D02*
Y764698D01*
G01Y762404D02*
Y761548D01*
G01Y756105D02*
Y755249D01*
G01Y759255D02*
Y758399D01*
G01Y752956D02*
Y752100D01*
G01Y749806D02*
Y748950D01*
G01X-19469Y765560D02*
Y764692D01*
G01Y762410D02*
Y761543D01*
G01Y756111D02*
Y755243D01*
G01Y759261D02*
Y758393D01*
G01Y752961D02*
Y752094D01*
G01Y749812D02*
Y748944D01*
G01X-18435Y765580D02*
Y764672D01*
G01Y762430D02*
Y761522D01*
G01Y756131D02*
Y755223D01*
G01Y759281D02*
Y758372D01*
G01Y752981D02*
Y752073D01*
G01Y749832D02*
Y748924D01*
G01X-18174Y765580D02*
Y764672D01*
G01Y762430D02*
Y761522D01*
G01Y756131D02*
Y755223D01*
G01Y759281D02*
Y758372D01*
G01Y752981D02*
Y752073D01*
G01Y749832D02*
Y748924D01*
G01X-16213Y765602D02*
Y764650D01*
G01Y762452D02*
Y761500D01*
G01Y756153D02*
Y755201D01*
G01Y759302D02*
Y758351D01*
G01Y753003D02*
Y752052D01*
G01Y749854D02*
Y748902D01*
G01X-15985Y765602D02*
Y764650D01*
G01Y762452D02*
Y761500D01*
G01Y756153D02*
Y755201D01*
G01Y759302D02*
Y758351D01*
G01Y753003D02*
Y752052D01*
G01Y749854D02*
Y748902D01*
G01X1969Y745835D02*
X0Y747803D01*
G01X-14537Y765706D02*
Y764546D01*
G01Y759407D02*
Y758247D01*
G01Y762556D02*
Y761396D01*
G01Y756257D02*
Y755097D01*
G01Y753107D02*
Y751948D01*
G01Y749958D02*
Y748798D01*
G01X-13009Y765913D02*
Y764339D01*
G01Y759614D02*
Y758039D01*
G01Y762764D02*
Y761189D01*
G01Y756465D02*
Y754890D01*
G01Y750165D02*
Y748591D01*
G01Y753315D02*
Y751740D01*
G01X-7283Y926543D02*
Y745441D01*
G01X315Y764535D02*
Y763945D01*
G01Y760008D02*
Y759417D01*
G01Y763157D02*
Y762567D01*
G01Y761386D02*
Y760795D01*
G01Y756858D02*
Y756268D01*
G01Y755087D02*
Y754496D01*
G01Y758236D02*
Y757646D01*
G01Y750559D02*
Y749969D01*
G01Y753709D02*
Y753118D01*
G01Y751937D02*
Y751346D01*
G01Y748787D02*
Y748197D01*
G01X512Y764535D02*
Y763945D01*
G01Y760008D02*
Y759417D01*
G01Y763157D02*
Y762567D01*
G01Y761386D02*
Y760795D01*
G01Y756858D02*
Y756268D01*
G01Y755087D02*
Y754496D01*
G01Y758236D02*
Y757646D01*
G01Y750559D02*
Y749969D01*
G01Y753709D02*
Y753118D01*
G01Y751937D02*
Y751346D01*
G01Y748787D02*
Y748197D01*
G01X709Y765717D02*
Y764535D01*
G01Y759417D02*
Y758236D01*
G01Y762567D02*
Y761386D01*
G01Y756268D02*
Y755087D01*
G01Y753118D02*
Y751937D01*
G01Y749969D02*
Y748787D01*
G01X1074Y765717D02*
Y764535D01*
G01Y759417D02*
Y758236D01*
G01Y762567D02*
Y761386D01*
G01Y756268D02*
Y755087D01*
G01Y753118D02*
Y751937D01*
G01Y749969D02*
Y748787D01*
G01X1184Y765717D02*
Y764535D01*
G01Y759417D02*
Y758236D01*
G01Y762567D02*
Y761386D01*
G01Y756268D02*
Y755087D01*
G01Y753118D02*
Y751937D01*
G01Y749969D02*
Y748787D01*
G01X9965Y765717D02*
Y764535D01*
G01Y759417D02*
Y758236D01*
G01Y762567D02*
Y761386D01*
G01Y756268D02*
Y755087D01*
G01Y753118D02*
Y751937D01*
G01Y749969D02*
Y748787D01*
G01X10075Y765717D02*
Y764535D01*
G01Y759417D02*
Y758236D01*
G01Y762567D02*
Y761386D01*
G01Y756268D02*
Y755087D01*
G01Y753118D02*
Y751937D01*
G01Y749969D02*
Y748787D01*
G01X-14537Y748798D02*
X-14147Y748591D01*
G01X-14537Y751948D02*
X-14147Y751740D01*
G01X-14537Y755097D02*
X-14147Y754890D01*
G01X-14537Y758247D02*
X-14147Y758039D01*
G01X-14537Y761396D02*
X-14147Y761189D01*
G01X-14537Y764546D02*
X-14147Y764339D01*
G01X-14677Y748886D02*
X-14537Y748798D01*
G01X-14449Y748886D02*
X-13977Y748591D01*
G01X-14677Y752035D02*
X-14537Y751948D01*
G01X-14449Y752035D02*
X-13977Y751740D01*
G01X-14677Y755185D02*
X-14537Y755097D01*
G01X-14449Y755185D02*
X-13977Y754890D01*
G01X-14677Y758335D02*
X-14537Y758247D01*
G01X-14449Y758335D02*
X-13977Y758039D01*
G01X-14677Y761484D02*
X-14537Y761396D01*
G01X-14449Y761484D02*
X-13977Y761189D01*
G01X-14677Y764634D02*
X-14537Y764546D01*
G01X-14449Y764634D02*
X-13977Y764339D01*
G01X-19469Y749818D02*
X-18174Y749832D01*
G01X-18435D02*
X-20801Y749806D01*
G01X-18174Y749832D02*
X-17126Y749843D01*
G01X-19469Y752967D02*
X-18174Y752981D01*
G01X-18435D02*
X-20801Y752956D01*
G01X-18174Y752981D02*
X-17126Y752993D01*
G01X-19469Y756117D02*
X-18174Y756131D01*
G01X-18435D02*
X-20801Y756105D01*
G01X-18174Y756131D02*
X-17126Y756143D01*
G01X-19469Y759267D02*
X-18174Y759281D01*
G01X-18435D02*
X-20801Y759255D01*
G01X-18174Y759281D02*
X-17126Y759292D01*
G01X-19469Y762416D02*
X-18174Y762430D01*
G01X-18435D02*
X-20801Y762404D01*
G01X-18174Y762430D02*
X-17126Y762442D01*
G01X-15985Y749854D02*
X-14449Y749870D01*
G01X-14677D02*
X-18174Y749832D01*
G01X-14677Y749870D02*
X-16213Y749854D01*
G01X-15985Y753003D02*
X-14449Y753020D01*
G01X-14677D02*
X-18174Y752981D01*
G01X-14677Y753020D02*
X-16213Y753003D01*
G01X-15985Y756153D02*
X-14449Y756169D01*
G01X-14677D02*
X-18174Y756131D01*
G01X-14677Y756169D02*
X-16213Y756153D01*
G01X-15985Y759302D02*
X-14449Y759319D01*
G01X-14677D02*
X-18174Y759281D01*
G01X-14677Y759319D02*
X-16213Y759302D01*
G01X-15985Y762452D02*
X-14449Y762469D01*
G01X-14677D02*
X-18174Y762430D01*
G01X-14677Y762469D02*
X-16213Y762452D01*
G01X-19469Y749818D02*
X-20801Y749806D01*
G01X-19469Y752967D02*
X-20801Y752956D01*
G01X-19469Y756117D02*
X-20801Y756105D01*
G01X-19469Y759267D02*
X-20801Y759255D01*
G01X-19469Y762416D02*
X-20801Y762404D01*
G01X-15985Y749854D02*
X-17126Y749843D01*
G01D02*
X-18435Y749832D01*
G01X-15985Y753003D02*
X-17126Y752993D01*
G01D02*
X-18435Y752981D01*
G01X-15985Y756153D02*
X-17126Y756143D01*
G01D02*
X-18435Y756131D01*
G01X-15985Y759302D02*
X-17126Y759292D01*
G01D02*
X-18435Y759281D01*
G01X-15985Y762452D02*
X-17126Y762442D01*
G01D02*
X-18435Y762430D01*
G01X17717Y745441D02*
X0D01*
G01X-7283D02*
X-26772D01*
G01X17323Y745835D02*
X1969D01*
G01X512Y748197D02*
X0D01*
G01X-13009Y748591D02*
X-14147D01*
G01X12410Y748787D02*
X315D01*
G01X-14449Y748886D02*
X-14677D01*
G01X-15985Y748902D02*
X-16213D01*
G01X-18174Y748924D02*
X-18435D01*
G01X-18174Y749832D02*
X-18435D01*
G01X-15985Y749854D02*
X-16213D01*
G01X-14449Y749870D02*
X-14677D01*
G01X12410Y749969D02*
X315D01*
G01X-13009Y750165D02*
X-14147D01*
G01X512Y750559D02*
X0D01*
G01X512Y751346D02*
X0D01*
G01X-13009Y751740D02*
X-14147D01*
G01X12410Y751937D02*
X315D01*
G01X-14449Y752035D02*
X-14677D01*
G01X-15985Y752052D02*
X-16213D01*
G01X-18174Y752073D02*
X-18435D01*
G01X-18174Y752981D02*
X-18435D01*
G01X-15985Y753003D02*
X-16213D01*
G01X-14449Y753020D02*
X-14677D01*
G01X12410Y753118D02*
X315D01*
G01X-13009Y753315D02*
X-14147D01*
G01X512Y753709D02*
X0D01*
G01X512Y754496D02*
X0D01*
G01X-13009Y754890D02*
X-14147D01*
G01X12410Y755087D02*
X315D01*
G01X-14449Y755185D02*
X-14677D01*
G01X-15985Y755201D02*
X-16213D01*
G01X-18174Y755223D02*
X-18435D01*
G01X-18174Y756131D02*
X-18435D01*
G01X-15985Y756153D02*
X-16213D01*
G01X-14449Y756169D02*
X-14677D01*
G01X12410Y756268D02*
X315D01*
G01X-13009Y756465D02*
X-14147D01*
G01X512Y756858D02*
X0D01*
G01X512Y757646D02*
X0D01*
G01X-13009Y758039D02*
X-14147D01*
G01X12410Y758236D02*
X315D01*
G01X-14449Y758335D02*
X-14677D01*
G01X-15985Y758351D02*
X-16213D01*
G01X-18174Y758372D02*
X-18435D01*
G01X-18174Y759281D02*
X-18435D01*
G01X-15985Y759302D02*
X-16213D01*
G01X-14449Y759319D02*
X-14677D01*
G01X12410Y759417D02*
X315D01*
G01X-13009Y759614D02*
X-14147D01*
G01X512Y760008D02*
X0D01*
G01X512Y760795D02*
X0D01*
G01X-13009Y761189D02*
X-14147D01*
G01X12410Y761386D02*
X315D01*
G01X-14449Y761484D02*
X-14677D01*
G01X-15985Y761500D02*
X-16213D01*
G01X-18174Y761522D02*
X-18435D01*
G01X-18174Y762430D02*
X-18435D01*
G01X-15985Y762452D02*
X-16213D01*
G01X-14449Y762469D02*
X-14677D01*
G01X12410Y762567D02*
X315D01*
G01X-13009Y762764D02*
X-14147D01*
G01X512Y763157D02*
X0D01*
G01X512Y763945D02*
X0D01*
G01X-13009Y764339D02*
X-14147D01*
G01X12410Y764535D02*
X315D01*
G01X-14449Y764634D02*
X-14677D01*
G01X-15985Y764650D02*
X-16213D01*
G01X-18174Y764672D02*
X-18435D01*
G01X-19469Y748938D02*
X-20801Y748950D01*
G01X-15985Y748902D02*
X-18435Y748924D01*
G01X-19469Y752088D02*
X-20801Y752100D01*
G01X-15985Y752052D02*
X-18435Y752073D01*
G01X-19469Y755237D02*
X-20801Y755249D01*
G01X-15985Y755201D02*
X-18435Y755223D01*
G01X-19469Y758387D02*
X-20801Y758399D01*
G01X-15985Y758351D02*
X-18435Y758372D01*
G01X-19469Y761537D02*
X-20801Y761548D01*
G01X-15985Y761500D02*
X-18435Y761522D01*
G01X-19469Y764686D02*
X-20801Y764698D01*
G01X-15985Y764650D02*
X-18435Y764672D01*
G01X-15985Y748902D02*
X-14449Y748886D01*
G01X-15985Y752052D02*
X-14449Y752035D01*
G01X-15985Y755201D02*
X-14449Y755185D01*
G01X-15985Y758351D02*
X-14449Y758335D01*
G01X-15985Y761500D02*
X-14449Y761484D01*
G01X-15985Y764650D02*
X-14449Y764634D01*
G01X-18435Y748924D02*
X-20801Y748950D01*
G01X-18435Y752073D02*
X-20801Y752100D01*
G01X-18435Y755223D02*
X-20801Y755249D01*
G01X-18435Y758372D02*
X-20801Y758399D01*
G01X-18435Y761522D02*
X-20801Y761548D01*
G01X-18435Y764672D02*
X-20801Y764698D01*
G01X-19469Y748938D02*
X-16213Y748902D01*
G01X-18174Y748924D02*
X-14677Y748886D01*
G01X-19469Y752088D02*
X-16213Y752052D01*
G01X-18174Y752073D02*
X-14677Y752035D01*
G01X-19469Y755237D02*
X-16213Y755201D01*
G01X-18174Y755223D02*
X-14677Y755185D01*
G01X-19469Y758387D02*
X-16213Y758351D01*
G01X-18174Y758372D02*
X-14677Y758335D01*
G01X-19469Y761537D02*
X-16213Y761500D01*
G01X-18174Y761522D02*
X-14677Y761484D01*
G01X-19469Y764686D02*
X-16213Y764650D01*
G01X-18174Y764672D02*
X-14677Y764634D01*
G01X-14537Y762556D02*
X-14677Y762469D01*
G01X-13977Y762764D02*
X-14449Y762469D01*
G01X-14537Y759407D02*
X-14677Y759319D01*
G01X-13977Y759614D02*
X-14449Y759319D01*
G01X-14537Y756257D02*
X-14677Y756169D01*
G01X-13977Y756465D02*
X-14449Y756169D01*
G01X-14537Y753107D02*
X-14677Y753020D01*
G01X-13977Y753315D02*
X-14449Y753020D01*
G01X-14537Y749958D02*
X-14677Y749870D01*
G01X-13977Y750165D02*
X-14449Y749870D01*
G01X-14147Y762764D02*
X-14537Y762556D01*
G01X-14147Y759614D02*
X-14537Y759407D01*
G01X-14147Y756465D02*
X-14537Y756257D01*
G01X-14147Y753315D02*
X-14537Y753107D01*
G01X-14147Y750165D02*
X-14537Y749958D01*
G01X-20801Y705711D02*
Y704856D01*
G01X-19469Y705717D02*
Y704850D01*
G01X-18435Y705737D02*
Y704829D01*
G01X-18174Y705737D02*
Y704829D01*
G01X-16213Y705759D02*
Y704807D01*
G01X-15985Y705759D02*
Y704807D01*
G01X-14537Y705863D02*
Y704704D01*
G01X-13009Y706071D02*
Y704496D01*
G01X315Y703315D02*
Y702724D01*
G01Y704693D02*
Y704102D01*
G01X512Y703315D02*
Y702724D01*
G01Y704693D02*
Y704102D01*
G01X709Y705874D02*
Y704693D01*
G01X1074Y705874D02*
Y704693D01*
G01X1184Y705874D02*
Y704693D01*
G01X9965Y705874D02*
Y704693D01*
G01X10075Y705874D02*
Y704693D01*
G01X-14537Y704704D02*
X-14147Y704496D01*
G01X-14677Y704791D02*
X-14537Y704704D01*
G01X-14449Y704791D02*
X-13977Y704496D01*
G01X-15985Y704807D02*
X-14449Y704791D01*
G01X-18435Y704829D02*
X-20801Y704856D01*
G01X-19469Y704844D02*
X-16213Y704807D01*
G01X-18174Y704829D02*
X-14677Y704791D01*
G01X-19469Y702574D02*
X-18174Y702588D01*
G01X-18435D02*
X-20801Y702562D01*
G01X-18174Y702588D02*
X-17126Y702599D01*
G01X-15985Y702609D02*
X-14449Y702626D01*
G01X-14677D02*
X-18174Y702588D01*
G01X-14677Y702626D02*
X-16213Y702609D01*
G01X-19469Y702574D02*
X-20801Y702562D01*
G01X-15985Y702609D02*
X-17126Y702599D01*
G01D02*
X-18435Y702588D01*
G01X-18174D02*
X-18435D01*
G01X-15985Y702609D02*
X-16213D01*
G01X-14449Y702626D02*
X-14677D01*
G01X12410Y702724D02*
X315D01*
G01X-13009Y702921D02*
X-14147D01*
G01X512Y703315D02*
X0D01*
G01X512Y704102D02*
X0D01*
G01X-13009Y704496D02*
X-14147D01*
G01X12410Y704693D02*
X315D01*
G01X-14449Y704791D02*
X-14677D01*
G01X-15985Y704807D02*
X-16213D01*
G01X-18174Y704829D02*
X-18435D01*
G01X-19469Y704844D02*
X-20801Y704856D01*
G01X-15985Y704807D02*
X-18435Y704829D01*
G01X-14537Y702714D02*
X-14677Y702626D01*
G01X-13977Y702921D02*
X-14449Y702626D01*
G01X-14147Y702921D02*
X-14537Y702714D01*
G01X12057Y844457D02*
Y843276D01*
G01Y847606D02*
Y846425D01*
G01Y841307D02*
Y840126D01*
G01Y835008D02*
Y833827D01*
G01Y838157D02*
Y836976D01*
G01Y831858D02*
Y830677D01*
G01Y828709D02*
Y827528D01*
G01X12410Y844457D02*
Y843276D01*
G01Y847606D02*
Y846425D01*
G01Y841307D02*
Y840126D01*
G01Y835008D02*
Y833827D01*
G01Y838157D02*
Y836976D01*
G01Y831858D02*
Y830677D01*
G01Y828709D02*
Y827528D01*
G01X13353Y844201D02*
Y843531D01*
G01Y847350D02*
Y846681D01*
G01Y841051D02*
Y840382D01*
G01Y834752D02*
Y834083D01*
G01Y837902D02*
Y837232D01*
G01Y831602D02*
Y830933D01*
G01Y828453D02*
Y827783D01*
G01X13701Y844201D02*
Y843531D01*
G01Y847350D02*
Y846681D01*
G01Y841051D02*
Y840382D01*
G01Y834752D02*
Y834083D01*
G01Y837902D02*
Y837232D01*
G01Y831602D02*
Y830933D01*
G01Y828453D02*
Y827783D01*
G01X12057Y825559D02*
X12287Y825303D01*
G01X12057Y828709D02*
X12287Y828453D01*
G01X12057Y831858D02*
X12287Y831602D01*
G01X12057Y835008D02*
X12287Y834752D01*
G01X12057Y838157D02*
X12287Y837902D01*
G01X12057Y841307D02*
X12287Y841051D01*
G01X12057Y844457D02*
X12287Y844201D01*
G01X12057Y847606D02*
X12287Y847350D01*
G01X12416Y825573D02*
X12634Y825303D01*
G01X12416Y828723D02*
X12634Y828453D01*
G01X12416Y831872D02*
X12634Y831602D01*
G01X12416Y835022D02*
X12634Y834752D01*
G01X12416Y838172D02*
X12634Y837902D01*
G01X12416Y841321D02*
X12634Y841051D01*
G01X12416Y844471D02*
X12634Y844201D01*
G01X12416Y847620D02*
X12634Y847350D01*
G01Y846681D02*
X12416Y846411D01*
G01X12634Y843531D02*
X12416Y843261D01*
G01X12634Y840382D02*
X12416Y840112D01*
G01X12634Y837232D02*
X12416Y836962D01*
G01X12634Y834083D02*
X12416Y833813D01*
G01X12634Y830933D02*
X12416Y830663D01*
G01X12634Y827783D02*
X12416Y827513D01*
G01X12287Y846681D02*
X12057Y846425D01*
G01X12287Y843531D02*
X12057Y843276D01*
G01X12287Y840382D02*
X12057Y840126D01*
G01X12287Y837232D02*
X12057Y836976D01*
G01X12287Y834083D02*
X12057Y833827D01*
G01X12287Y830933D02*
X12057Y830677D01*
G01X12287Y827783D02*
X12057Y827528D01*
G01X13701Y825303D02*
X12287D01*
G01X13701Y827783D02*
X12287D01*
G01X13701Y828453D02*
X12287D01*
G01X13701Y830933D02*
X12287D01*
G01X13701Y831602D02*
X12287D01*
G01X13701Y834083D02*
X12287D01*
G01X13701Y834752D02*
X12287D01*
G01X13701Y837232D02*
X12287D01*
G01X13701Y837902D02*
X12287D01*
G01X13701Y840382D02*
X12287D01*
G01X13701Y841051D02*
X12287D01*
G01X13701Y843531D02*
X12287D01*
G01X13701Y844201D02*
X12287D01*
G01X13701Y846681D02*
X12287D01*
G01X13701Y847350D02*
X12287D01*
G01X35827Y839744D02*
Y841476D01*
G01Y839744D02*
X40551Y835098D01*
G01X35827Y840847D02*
X40547Y836206D01*
G01X39236Y843445D02*
X35827Y841476D01*
G01X12057Y825559D02*
Y824378D01*
G01Y822409D02*
Y821228D01*
G01Y816110D02*
Y814929D01*
G01Y819260D02*
Y818079D01*
G01Y812961D02*
Y811780D01*
G01Y806661D02*
Y805480D01*
G01Y809811D02*
Y808630D01*
G01Y803512D02*
Y802331D01*
G01Y797213D02*
Y796031D01*
G01Y800362D02*
Y799181D01*
G01Y794063D02*
Y792882D01*
G01Y787764D02*
Y786583D01*
G01Y790913D02*
Y789732D01*
G01Y784614D02*
Y783433D01*
G01Y778315D02*
Y777134D01*
G01Y781465D02*
Y780283D01*
G01X12410Y825559D02*
Y824378D01*
G01Y822409D02*
Y821228D01*
G01Y816110D02*
Y814929D01*
G01Y819260D02*
Y818079D01*
G01Y812961D02*
Y811780D01*
G01Y806661D02*
Y805480D01*
G01Y809811D02*
Y808630D01*
G01Y803512D02*
Y802331D01*
G01Y797213D02*
Y796031D01*
G01Y800362D02*
Y799181D01*
G01Y794063D02*
Y792882D01*
G01Y787764D02*
Y786583D01*
G01Y790913D02*
Y789732D01*
G01Y784614D02*
Y783433D01*
G01Y778315D02*
Y777134D01*
G01Y781465D02*
Y780283D01*
G01X13353Y825303D02*
Y824634D01*
G01Y822154D02*
Y821484D01*
G01Y815854D02*
Y815185D01*
G01Y819004D02*
Y818335D01*
G01Y812705D02*
Y812035D01*
G01Y806406D02*
Y805736D01*
G01Y809555D02*
Y808886D01*
G01Y803256D02*
Y802587D01*
G01Y796957D02*
Y796287D01*
G01Y800106D02*
Y799437D01*
G01Y793807D02*
Y793138D01*
G01Y787508D02*
Y786839D01*
G01Y790657D02*
Y789988D01*
G01Y784358D02*
Y783689D01*
G01Y781209D02*
Y780539D01*
G01Y778059D02*
Y777390D01*
G01X13701Y825303D02*
Y824634D01*
G01Y822154D02*
Y821484D01*
G01Y815854D02*
Y815185D01*
G01Y819004D02*
Y818335D01*
G01Y812705D02*
Y812035D01*
G01Y806406D02*
Y805736D01*
G01Y809555D02*
Y808886D01*
G01Y803256D02*
Y802587D01*
G01Y796957D02*
Y796287D01*
G01Y800106D02*
Y799437D01*
G01Y793807D02*
Y793138D01*
G01Y787508D02*
Y786839D01*
G01Y790657D02*
Y789988D01*
G01Y784358D02*
Y783689D01*
G01Y781209D02*
Y780539D01*
G01Y778059D02*
Y777390D01*
G01X12057Y778315D02*
X12287Y778059D01*
G01X12057Y781465D02*
X12287Y781209D01*
G01X12057Y784614D02*
X12287Y784358D01*
G01X12057Y787764D02*
X12287Y787508D01*
G01X12057Y790913D02*
X12287Y790657D01*
G01X12057Y794063D02*
X12287Y793807D01*
G01X12057Y797213D02*
X12287Y796957D01*
G01X12057Y800362D02*
X12287Y800106D01*
G01X12057Y803512D02*
X12287Y803256D01*
G01X12057Y806661D02*
X12287Y806406D01*
G01X12057Y809811D02*
X12287Y809555D01*
G01X12057Y812961D02*
X12287Y812705D01*
G01X12057Y816110D02*
X12287Y815854D01*
G01X12057Y819260D02*
X12287Y819004D01*
G01X12057Y822409D02*
X12287Y822154D01*
G01X12416Y778329D02*
X12634Y778059D01*
G01X12416Y781479D02*
X12634Y781209D01*
G01X12416Y784628D02*
X12634Y784358D01*
G01X12416Y787778D02*
X12634Y787508D01*
G01X12416Y790928D02*
X12634Y790657D01*
G01X12416Y794077D02*
X12634Y793807D01*
G01X12416Y797227D02*
X12634Y796957D01*
G01X12416Y800376D02*
X12634Y800106D01*
G01X12416Y803526D02*
X12634Y803256D01*
G01X12416Y806676D02*
X12634Y806406D01*
G01X12416Y809825D02*
X12634Y809555D01*
G01X12416Y812975D02*
X12634Y812705D01*
G01X12416Y816124D02*
X12634Y815854D01*
G01X12416Y819274D02*
X12634Y819004D01*
G01X12416Y822424D02*
X12634Y822154D01*
G01Y824634D02*
X12416Y824364D01*
G01X12634Y821484D02*
X12416Y821214D01*
G01X12634Y818335D02*
X12416Y818065D01*
G01X12634Y815185D02*
X12416Y814915D01*
G01X12634Y812035D02*
X12416Y811765D01*
G01X12634Y808886D02*
X12416Y808616D01*
G01X12634Y805736D02*
X12416Y805466D01*
G01X12634Y802587D02*
X12416Y802317D01*
G01X12634Y799437D02*
X12416Y799167D01*
G01X12634Y796287D02*
X12416Y796017D01*
G01X12634Y793138D02*
X12416Y792868D01*
G01X12634Y789988D02*
X12416Y789718D01*
G01X12634Y786839D02*
X12416Y786569D01*
G01X12634Y783689D02*
X12416Y783419D01*
G01X12634Y780539D02*
X12416Y780269D01*
G01X12634Y777390D02*
X12416Y777120D01*
G01X12287Y824634D02*
X12057Y824378D01*
G01X12287Y821484D02*
X12057Y821228D01*
G01X12287Y818335D02*
X12057Y818079D01*
G01X12287Y815185D02*
X12057Y814929D01*
G01X12287Y812035D02*
X12057Y811780D01*
G01X12287Y808886D02*
X12057Y808630D01*
G01X12287Y805736D02*
X12057Y805480D01*
G01X12287Y802587D02*
X12057Y802331D01*
G01X12287Y799437D02*
X12057Y799181D01*
G01X12287Y796287D02*
X12057Y796031D01*
G01X12287Y793138D02*
X12057Y792882D01*
G01X12287Y789988D02*
X12057Y789732D01*
G01X12287Y786839D02*
X12057Y786583D01*
G01X12287Y783689D02*
X12057Y783433D01*
G01X12287Y780539D02*
X12057Y780283D01*
G01X12287Y777390D02*
X12057Y777134D01*
G01X13701Y777390D02*
X12287D01*
G01X13701Y778059D02*
X12287D01*
G01X13701Y780539D02*
X12287D01*
G01X13701Y781209D02*
X12287D01*
G01X13701Y783689D02*
X12287D01*
G01X13701Y784358D02*
X12287D01*
G01X13701Y786839D02*
X12287D01*
G01X13701Y787508D02*
X12287D01*
G01X13701Y789988D02*
X12287D01*
G01X13701Y790657D02*
X12287D01*
G01X13701Y793138D02*
X12287D01*
G01X13701Y793807D02*
X12287D01*
G01X13701Y796287D02*
X12287D01*
G01X13701Y796957D02*
X12287D01*
G01X13701Y799437D02*
X12287D01*
G01X13701Y800106D02*
X12287D01*
G01X13701Y802587D02*
X12287D01*
G01X13701Y803256D02*
X12287D01*
G01X13701Y805736D02*
X12287D01*
G01X13701Y806406D02*
X12287D01*
G01X13701Y808886D02*
X12287D01*
G01X13701Y809555D02*
X12287D01*
G01X13701Y812035D02*
X12287D01*
G01X13701Y812705D02*
X12287D01*
G01X13701Y815185D02*
X12287D01*
G01X13701Y815854D02*
X12287D01*
G01X13701Y818335D02*
X12287D01*
G01X13701Y819004D02*
X12287D01*
G01X13701Y821484D02*
X12287D01*
G01X13701Y822154D02*
X12287D01*
G01X13701Y824634D02*
X12287D01*
G01X-20801Y844294D02*
Y843438D01*
G01Y847444D02*
Y846588D01*
G01Y841144D02*
Y840289D01*
G01Y834845D02*
Y833989D01*
G01Y837995D02*
Y837139D01*
G01Y831696D02*
Y830840D01*
G01Y828546D02*
Y827690D01*
G01X-19469Y844300D02*
Y843432D01*
G01Y847450D02*
Y846582D01*
G01Y841150D02*
Y840283D01*
G01Y834851D02*
Y833983D01*
G01Y838001D02*
Y837133D01*
G01Y831702D02*
Y830834D01*
G01Y828552D02*
Y827684D01*
G01X-18435Y844320D02*
Y843412D01*
G01Y847470D02*
Y846561D01*
G01Y841170D02*
Y840262D01*
G01Y834871D02*
Y833963D01*
G01Y838021D02*
Y837113D01*
G01Y831722D02*
Y830813D01*
G01Y828572D02*
Y827664D01*
G01X-18174Y844320D02*
Y843412D01*
G01Y847470D02*
Y846561D01*
G01Y841170D02*
Y840262D01*
G01Y834871D02*
Y833963D01*
G01Y838021D02*
Y837113D01*
G01Y831722D02*
Y830813D01*
G01Y828572D02*
Y827664D01*
G01X-16213Y844342D02*
Y843390D01*
G01Y847491D02*
Y846540D01*
G01Y841192D02*
Y840241D01*
G01Y834893D02*
Y833941D01*
G01Y838043D02*
Y837091D01*
G01Y831743D02*
Y830792D01*
G01Y828594D02*
Y827642D01*
G01X-15985Y844342D02*
Y843390D01*
G01Y847491D02*
Y846540D01*
G01Y841192D02*
Y840241D01*
G01Y834893D02*
Y833941D01*
G01Y838043D02*
Y837091D01*
G01Y831743D02*
Y830792D01*
G01Y828594D02*
Y827642D01*
G01X-14537Y844446D02*
Y843286D01*
G01Y847596D02*
Y846436D01*
G01Y841296D02*
Y840137D01*
G01Y834997D02*
Y833837D01*
G01Y838147D02*
Y836987D01*
G01Y831848D02*
Y830688D01*
G01Y828698D02*
Y827538D01*
G01X-13009Y844654D02*
Y843079D01*
G01Y847803D02*
Y846228D01*
G01Y841504D02*
Y839929D01*
G01Y835205D02*
Y833630D01*
G01Y838354D02*
Y836780D01*
G01Y832055D02*
Y830480D01*
G01Y828906D02*
Y827331D01*
G01X315Y845047D02*
Y844457D01*
G01Y848197D02*
Y847606D01*
G01Y846425D02*
Y845835D01*
G01Y841898D02*
Y841307D01*
G01Y840126D02*
Y839535D01*
G01Y843276D02*
Y842685D01*
G01Y835598D02*
Y835008D01*
G01Y838748D02*
Y838157D01*
G01Y836976D02*
Y836386D01*
G01Y832449D02*
Y831858D01*
G01Y830677D02*
Y830087D01*
G01Y833827D02*
Y833236D01*
G01Y826150D02*
Y825559D01*
G01Y829299D02*
Y828709D01*
G01Y827528D02*
Y826937D01*
G01X512Y845047D02*
Y844457D01*
G01Y848197D02*
Y847606D01*
G01Y846425D02*
Y845835D01*
G01Y841898D02*
Y841307D01*
G01Y840126D02*
Y839535D01*
G01Y843276D02*
Y842685D01*
G01Y835598D02*
Y835008D01*
G01Y838748D02*
Y838157D01*
G01Y836976D02*
Y836386D01*
G01Y832449D02*
Y831858D01*
G01Y830677D02*
Y830087D01*
G01Y833827D02*
Y833236D01*
G01Y826150D02*
Y825559D01*
G01Y829299D02*
Y828709D01*
G01Y827528D02*
Y826937D01*
G01X709Y844457D02*
Y843276D01*
G01Y847606D02*
Y846425D01*
G01Y841307D02*
Y840126D01*
G01Y835008D02*
Y833827D01*
G01Y838157D02*
Y836976D01*
G01Y831858D02*
Y830677D01*
G01Y828709D02*
Y827528D01*
G01X1074Y844457D02*
Y843276D01*
G01Y847606D02*
Y846425D01*
G01Y841307D02*
Y840126D01*
G01Y835008D02*
Y833827D01*
G01Y838157D02*
Y836976D01*
G01Y831858D02*
Y830677D01*
G01Y828709D02*
Y827528D01*
G01X1184Y844457D02*
Y843276D01*
G01Y847606D02*
Y846425D01*
G01Y841307D02*
Y840126D01*
G01Y835008D02*
Y833827D01*
G01Y838157D02*
Y836976D01*
G01Y831858D02*
Y830677D01*
G01Y828709D02*
Y827528D01*
G01X9965Y844457D02*
Y843276D01*
G01Y847606D02*
Y846425D01*
G01Y841307D02*
Y840126D01*
G01Y835008D02*
Y833827D01*
G01Y838157D02*
Y836976D01*
G01Y831858D02*
Y830677D01*
G01Y828709D02*
Y827528D01*
G01X10075Y844457D02*
Y843276D01*
G01Y847606D02*
Y846425D01*
G01Y841307D02*
Y840126D01*
G01Y835008D02*
Y833827D01*
G01Y838157D02*
Y836976D01*
G01Y831858D02*
Y830677D01*
G01Y828709D02*
Y827528D01*
G01X-14537Y827538D02*
X-14147Y827331D01*
G01X-14537Y830688D02*
X-14147Y830480D01*
G01X-14537Y833837D02*
X-14147Y833630D01*
G01X-14537Y836987D02*
X-14147Y836780D01*
G01X-14537Y840137D02*
X-14147Y839929D01*
G01X-14537Y843286D02*
X-14147Y843079D01*
G01X-14537Y846436D02*
X-14147Y846228D01*
G01X-14677Y827626D02*
X-14537Y827538D01*
G01X-14449Y827626D02*
X-13977Y827331D01*
G01X-14677Y830776D02*
X-14537Y830688D01*
G01X-14449Y830776D02*
X-13977Y830480D01*
G01X-14677Y833925D02*
X-14537Y833837D01*
G01X-14449Y833925D02*
X-13977Y833630D01*
G01X-14677Y837075D02*
X-14537Y836987D01*
G01X-14449Y837075D02*
X-13977Y836780D01*
G01X-14677Y840224D02*
X-14537Y840137D01*
G01X-14449Y840224D02*
X-13977Y839929D01*
G01X-14677Y843374D02*
X-14537Y843286D01*
G01X-14449Y843374D02*
X-13977Y843079D01*
G01X-14677Y846524D02*
X-14537Y846436D01*
G01X-14449Y846524D02*
X-13977Y846228D01*
G01X-14537Y847596D02*
X-14677Y847508D01*
G01X-13977Y847803D02*
X-14449Y847508D01*
G01X-14537Y844446D02*
X-14677Y844358D01*
G01X-13977Y844654D02*
X-14449Y844358D01*
G01X-14537Y841296D02*
X-14677Y841209D01*
G01X-13977Y841504D02*
X-14449Y841209D01*
G01X-14537Y838147D02*
X-14677Y838059D01*
G01X-13977Y838354D02*
X-14449Y838059D01*
G01X-19469Y825408D02*
X-18174Y825422D01*
G01X-18435D02*
X-20801Y825396D01*
G01X-18174Y825422D02*
X-17126Y825434D01*
G01X-19469Y828558D02*
X-18174Y828572D01*
G01X-18435D02*
X-20801Y828546D01*
G01X-18174Y828572D02*
X-17126Y828583D01*
G01X-19469Y831707D02*
X-18174Y831722D01*
G01X-18435D02*
X-20801Y831696D01*
G01X-18174Y831722D02*
X-17126Y831733D01*
G01X-19469Y834857D02*
X-18174Y834871D01*
G01X-18435D02*
X-20801Y834845D01*
G01X-18174Y834871D02*
X-17126Y834883D01*
G01X-19469Y838007D02*
X-18174Y838021D01*
G01X-18435D02*
X-20801Y837995D01*
G01X-18174Y838021D02*
X-17126Y838032D01*
G01X-19469Y841156D02*
X-18174Y841170D01*
G01X-18435D02*
X-20801Y841144D01*
G01X-18174Y841170D02*
X-17126Y841182D01*
G01X-19469Y844306D02*
X-18174Y844320D01*
G01X-18435D02*
X-20801Y844294D01*
G01X-18174Y844320D02*
X-17126Y844331D01*
G01X-15985Y825444D02*
X-14449Y825461D01*
G01X-14677D02*
X-18174Y825422D01*
G01X-14677Y825461D02*
X-16213Y825444D01*
G01X-15985Y828594D02*
X-14449Y828610D01*
G01X-14677D02*
X-18174Y828572D01*
G01X-14677Y828610D02*
X-16213Y828594D01*
G01X-15985Y831743D02*
X-14449Y831760D01*
G01X-14677D02*
X-18174Y831722D01*
G01X-14677Y831760D02*
X-16213Y831743D01*
G01X-15985Y834893D02*
X-14449Y834909D01*
G01X-14677D02*
X-18174Y834871D01*
G01X-14677Y834909D02*
X-16213Y834893D01*
G01X-15985Y838043D02*
X-14449Y838059D01*
G01X-14677D02*
X-18174Y838021D01*
G01X-14677Y838059D02*
X-16213Y838043D01*
G01X-15985Y841192D02*
X-14449Y841209D01*
G01X-14677D02*
X-18174Y841170D01*
G01X-14677Y841209D02*
X-16213Y841192D01*
G01X-15985Y844342D02*
X-14449Y844358D01*
G01X-14677D02*
X-18174Y844320D01*
G01X-14677Y844358D02*
X-16213Y844342D01*
G01X-15985Y847491D02*
X-14449Y847508D01*
G01X-14677D02*
X-16213Y847491D01*
G01X-19469Y825408D02*
X-20801Y825396D01*
G01X-19469Y828558D02*
X-20801Y828546D01*
G01X-19469Y831707D02*
X-20801Y831696D01*
G01X-19469Y834857D02*
X-20801Y834845D01*
G01X-19469Y838007D02*
X-20801Y837995D01*
G01X-19469Y841156D02*
X-20801Y841144D01*
G01X-19469Y844306D02*
X-20801Y844294D01*
G01X-19469Y847456D02*
X-20801Y847444D01*
G01X-15985Y825444D02*
X-17126Y825434D01*
G01D02*
X-18435Y825422D01*
G01X-15985Y828594D02*
X-17126Y828583D01*
G01D02*
X-18435Y828572D01*
G01X-15985Y831743D02*
X-17126Y831733D01*
G01D02*
X-18435Y831722D01*
G01X-15985Y834893D02*
X-17126Y834883D01*
G01D02*
X-18435Y834871D01*
G01X-15985Y838043D02*
X-17126Y838032D01*
G01D02*
X-18435Y838021D01*
G01X-15985Y841192D02*
X-17126Y841182D01*
G01D02*
X-18435Y841170D01*
G01X-15985Y844342D02*
X-17126Y844331D01*
G01D02*
X-18435Y844320D01*
G01X-15985Y847491D02*
X-17126Y847481D01*
G01D02*
X-18435Y847470D01*
G01X-18174Y825422D02*
X-18435D01*
G01X-15985Y825444D02*
X-16213D01*
G01X-14449Y825461D02*
X-14677D01*
G01X12410Y825559D02*
X315D01*
G01X-13009Y825756D02*
X-14147D01*
G01X512Y826150D02*
X0D01*
G01X512Y826937D02*
X0D01*
G01X-13009Y827331D02*
X-14147D01*
G01X12410Y827528D02*
X315D01*
G01X-14449Y827626D02*
X-14677D01*
G01X-15985Y827642D02*
X-16213D01*
G01X-18174Y827664D02*
X-18435D01*
G01X-18174Y828572D02*
X-18435D01*
G01X-15985Y828594D02*
X-16213D01*
G01X-14449Y828610D02*
X-14677D01*
G01X12410Y828709D02*
X315D01*
G01X-13009Y828906D02*
X-14147D01*
G01X512Y829299D02*
X0D01*
G01X512Y830087D02*
X0D01*
G01X-13009Y830480D02*
X-14147D01*
G01X12410Y830677D02*
X315D01*
G01X-14449Y830776D02*
X-14677D01*
G01X-15985Y830792D02*
X-16213D01*
G01X-18174Y830813D02*
X-18435D01*
G01X-18174Y831722D02*
X-18435D01*
G01X-15985Y831743D02*
X-16213D01*
G01X-14449Y831760D02*
X-14677D01*
G01X12410Y831858D02*
X315D01*
G01X-13009Y832055D02*
X-14147D01*
G01X512Y832449D02*
X0D01*
G01X512Y833236D02*
X0D01*
G01X-13009Y833630D02*
X-14147D01*
G01X12410Y833827D02*
X315D01*
G01X-14449Y833925D02*
X-14677D01*
G01X-15985Y833941D02*
X-16213D01*
G01X-18174Y833963D02*
X-18435D01*
G01X-18174Y834871D02*
X-18435D01*
G01X-15985Y834893D02*
X-16213D01*
G01X-14449Y834909D02*
X-14677D01*
G01X12410Y835008D02*
X315D01*
G01X-13009Y835205D02*
X-14147D01*
G01X512Y835598D02*
X0D01*
G01X512Y836386D02*
X0D01*
G01X-13009Y836780D02*
X-14147D01*
G01X12410Y836976D02*
X315D01*
G01X-14449Y837075D02*
X-14677D01*
G01X-15985Y837091D02*
X-16213D01*
G01X-18174Y837113D02*
X-18435D01*
G01X-18174Y838021D02*
X-18435D01*
G01X-15985Y838043D02*
X-16213D01*
G01X-14449Y838059D02*
X-14677D01*
G01X12410Y838157D02*
X315D01*
G01X-13009Y838354D02*
X-14147D01*
G01X512Y838748D02*
X0D01*
G01X512Y839535D02*
X0D01*
G01X-13009Y839929D02*
X-14147D01*
G01X12410Y840126D02*
X315D01*
G01X-14449Y840224D02*
X-14677D01*
G01X-15985Y840241D02*
X-16213D01*
G01X-18174Y840262D02*
X-18435D01*
G01X-18174Y841170D02*
X-18435D01*
G01X-15985Y841192D02*
X-16213D01*
G01X-14449Y841209D02*
X-14677D01*
G01X12410Y841307D02*
X315D01*
G01X-13009Y841504D02*
X-14147D01*
G01X512Y841898D02*
X0D01*
G01X512Y842685D02*
X0D01*
G01X-13009Y843079D02*
X-14147D01*
G01X12410Y843276D02*
X315D01*
G01X-14449Y843374D02*
X-14677D01*
G01X-15985Y843390D02*
X-16213D01*
G01X-18174Y843412D02*
X-18435D01*
G01X-18174Y844320D02*
X-18435D01*
G01X-15985Y844342D02*
X-16213D01*
G01X-14449Y844358D02*
X-14677D01*
G01X12410Y844457D02*
X315D01*
G01X-13009Y844654D02*
X-14147D01*
G01X512Y845047D02*
X0D01*
G01X512Y845835D02*
X0D01*
G01X-13009Y846228D02*
X-14147D01*
G01X12410Y846425D02*
X315D01*
G01X-14449Y846524D02*
X-14677D01*
G01X-15985Y846540D02*
X-16213D01*
G01X-18174Y846561D02*
X-18435D01*
G01Y847470D02*
X-18174D01*
G01X-15985Y847491D02*
X-16213D01*
G01X-14449Y847508D02*
X-14677D01*
G01X12410Y847606D02*
X315D01*
G01X-13009Y847803D02*
X-14147D01*
G01X-19469Y827678D02*
X-20801Y827690D01*
G01X-15985Y827642D02*
X-18435Y827664D01*
G01X-19469Y830828D02*
X-20801Y830840D01*
G01X-15985Y830792D02*
X-18435Y830813D01*
G01X-19469Y833978D02*
X-20801Y833989D01*
G01X-15985Y833941D02*
X-18435Y833963D01*
G01X-19469Y837127D02*
X-20801Y837139D01*
G01X-15985Y837091D02*
X-18435Y837113D01*
G01X-19469Y840277D02*
X-20801Y840289D01*
G01X-15985Y840241D02*
X-18435Y840262D01*
G01X-19469Y843426D02*
X-20801Y843438D01*
G01X-15985Y843390D02*
X-18435Y843412D01*
G01X-19469Y846576D02*
X-20801Y846588D01*
G01X-15985Y846540D02*
X-18435Y846561D01*
G01X-15985Y827642D02*
X-14449Y827626D01*
G01X-15985Y830792D02*
X-14449Y830776D01*
G01X-15985Y833941D02*
X-14449Y833925D01*
G01X-15985Y837091D02*
X-14449Y837075D01*
G01X-15985Y840241D02*
X-14449Y840224D01*
G01X-15985Y843390D02*
X-14449Y843374D01*
G01X-15985Y846540D02*
X-14449Y846524D01*
G01X-18435Y827664D02*
X-20801Y827690D01*
G01X-18435Y830813D02*
X-20801Y830840D01*
G01X-18435Y833963D02*
X-20801Y833989D01*
G01X-18435Y837113D02*
X-20801Y837139D01*
G01X-18435Y840262D02*
X-20801Y840289D01*
G01X-18435Y843412D02*
X-20801Y843438D01*
G01X-18435Y846561D02*
X-20801Y846588D01*
G01X-19469Y827678D02*
X-16213Y827642D01*
G01X-18174Y827664D02*
X-14677Y827626D01*
G01X-19469Y830828D02*
X-16213Y830792D01*
G01X-18174Y830813D02*
X-14677Y830776D01*
G01X-19469Y833978D02*
X-16213Y833941D01*
G01X-18174Y833963D02*
X-14677Y833925D01*
G01X-19469Y837127D02*
X-16213Y837091D01*
G01X-18174Y837113D02*
X-14677Y837075D01*
G01X-19469Y840277D02*
X-16213Y840241D01*
G01X-18174Y840262D02*
X-14677Y840224D01*
G01X-19469Y843426D02*
X-16213Y843390D01*
G01X-18174Y843412D02*
X-14677Y843374D01*
G01X-19469Y846576D02*
X-16213Y846540D01*
G01X-18174Y846561D02*
X-14677Y846524D01*
G01X-14537Y834997D02*
X-14677Y834909D01*
G01X-13977Y835205D02*
X-14449Y834909D01*
G01X-14537Y831848D02*
X-14677Y831760D01*
G01X-13977Y832055D02*
X-14449Y831760D01*
G01X-14537Y828698D02*
X-14677Y828610D01*
G01X-13977Y828906D02*
X-14449Y828610D01*
G01X-14537Y825548D02*
X-14677Y825461D01*
G01X-13977Y825756D02*
X-14449Y825461D01*
G01X-14147Y847803D02*
X-14537Y847596D01*
G01X-14147Y844654D02*
X-14537Y844446D01*
G01X-14147Y841504D02*
X-14537Y841296D01*
G01X-14147Y838354D02*
X-14537Y838147D01*
G01X-14147Y835205D02*
X-14537Y834997D01*
G01X-14147Y832055D02*
X-14537Y831848D01*
G01X-14147Y828906D02*
X-14537Y828698D01*
G01X-14147Y825756D02*
X-14537Y825548D01*
G01X-17126Y847481D02*
X-16213Y847491D01*
G01X-19469Y847456D02*
X-18174Y847470D01*
G01X-18435D02*
X-20801Y847444D01*
G01X-18174Y847470D02*
X-17126Y847481D01*
G01X-18174Y847470D02*
X-17126Y847481D01*
G01X-20801Y825396D02*
Y824541D01*
G01Y822247D02*
Y821391D01*
G01Y815948D02*
Y815092D01*
G01Y819097D02*
Y818241D01*
G01Y812798D02*
Y811942D01*
G01Y806499D02*
Y805643D01*
G01Y809648D02*
Y808793D01*
G01Y803349D02*
Y802493D01*
G01Y797050D02*
Y796194D01*
G01Y800200D02*
Y799344D01*
G01Y793900D02*
Y793044D01*
G01Y787601D02*
Y786745D01*
G01Y790751D02*
Y789895D01*
G01Y784452D02*
Y783596D01*
G01Y778152D02*
Y777296D01*
G01Y781302D02*
Y780446D01*
G01X-19469Y825402D02*
Y824535D01*
G01Y822253D02*
Y821385D01*
G01Y815954D02*
Y815086D01*
G01Y819103D02*
Y818235D01*
G01Y812804D02*
Y811936D01*
G01Y806505D02*
Y805637D01*
G01Y809654D02*
Y808787D01*
G01Y803355D02*
Y802487D01*
G01Y797056D02*
Y796188D01*
G01Y800206D02*
Y799338D01*
G01Y793906D02*
Y793039D01*
G01Y787607D02*
Y786739D01*
G01Y790757D02*
Y789889D01*
G01Y784457D02*
Y783590D01*
G01Y778158D02*
Y777291D01*
G01Y781308D02*
Y780440D01*
G01X-18435Y825422D02*
Y824514D01*
G01Y822273D02*
Y821365D01*
G01Y815974D02*
Y815065D01*
G01Y819123D02*
Y818215D01*
G01Y812824D02*
Y811916D01*
G01Y806525D02*
Y805617D01*
G01Y809674D02*
Y808766D01*
G01Y803375D02*
Y802467D01*
G01Y797076D02*
Y796168D01*
G01Y800226D02*
Y799317D01*
G01Y793926D02*
Y793018D01*
G01Y787627D02*
Y786719D01*
G01Y790777D02*
Y789869D01*
G01Y784478D02*
Y783569D01*
G01Y778178D02*
Y777270D01*
G01Y781328D02*
Y780420D01*
G01X-18174Y825422D02*
Y824514D01*
G01Y822273D02*
Y821365D01*
G01Y815974D02*
Y815065D01*
G01Y819123D02*
Y818215D01*
G01Y812824D02*
Y811916D01*
G01Y806525D02*
Y805617D01*
G01Y809674D02*
Y808766D01*
G01Y803375D02*
Y802467D01*
G01Y797076D02*
Y796168D01*
G01Y800226D02*
Y799317D01*
G01Y793926D02*
Y793018D01*
G01Y787627D02*
Y786719D01*
G01Y790777D02*
Y789869D01*
G01Y784478D02*
Y783569D01*
G01Y778178D02*
Y777270D01*
G01Y781328D02*
Y780420D01*
G01X-16213Y825444D02*
Y824493D01*
G01Y822294D02*
Y821343D01*
G01Y815995D02*
Y815044D01*
G01Y819145D02*
Y818193D01*
G01Y812846D02*
Y811894D01*
G01Y806546D02*
Y805595D01*
G01Y809696D02*
Y808744D01*
G01Y803397D02*
Y802445D01*
G01Y797098D02*
Y796146D01*
G01Y800247D02*
Y799296D01*
G01Y793948D02*
Y792996D01*
G01Y787649D02*
Y786697D01*
G01Y790798D02*
Y789847D01*
G01Y784499D02*
Y783548D01*
G01Y778200D02*
Y777248D01*
G01Y781350D02*
Y780398D01*
G01X-15985Y825444D02*
Y824493D01*
G01Y822294D02*
Y821343D01*
G01Y815995D02*
Y815044D01*
G01Y819145D02*
Y818193D01*
G01Y812846D02*
Y811894D01*
G01Y806546D02*
Y805595D01*
G01Y809696D02*
Y808744D01*
G01Y803397D02*
Y802445D01*
G01Y797098D02*
Y796146D01*
G01Y800247D02*
Y799296D01*
G01Y793948D02*
Y792996D01*
G01Y787649D02*
Y786697D01*
G01Y790798D02*
Y789847D01*
G01Y784499D02*
Y783548D01*
G01Y778200D02*
Y777248D01*
G01Y781350D02*
Y780398D01*
G01X-14537Y825548D02*
Y824389D01*
G01Y822399D02*
Y821239D01*
G01Y816100D02*
Y814940D01*
G01Y819249D02*
Y818089D01*
G01Y812950D02*
Y811790D01*
G01Y806651D02*
Y805491D01*
G01Y809800D02*
Y808641D01*
G01Y803501D02*
Y802341D01*
G01Y797202D02*
Y796042D01*
G01Y800352D02*
Y799192D01*
G01Y794052D02*
Y792893D01*
G01Y787753D02*
Y786593D01*
G01Y790903D02*
Y789743D01*
G01Y784604D02*
Y783444D01*
G01Y778304D02*
Y777144D01*
G01Y781454D02*
Y780294D01*
G01X-13009Y825756D02*
Y824181D01*
G01Y822606D02*
Y821031D01*
G01Y816307D02*
Y814732D01*
G01Y819457D02*
Y817882D01*
G01Y813157D02*
Y811583D01*
G01Y806858D02*
Y805283D01*
G01Y810008D02*
Y808433D01*
G01Y803709D02*
Y802134D01*
G01Y797409D02*
Y795835D01*
G01Y800559D02*
Y798984D01*
G01Y794260D02*
Y792685D01*
G01Y787961D02*
Y786386D01*
G01Y791110D02*
Y789535D01*
G01Y784811D02*
Y783236D01*
G01Y778512D02*
Y776937D01*
G01Y781661D02*
Y780087D01*
G01X315Y823000D02*
Y822409D01*
G01Y821228D02*
Y820638D01*
G01Y824378D02*
Y823787D01*
G01Y816701D02*
Y816110D01*
G01Y819850D02*
Y819260D01*
G01Y818079D02*
Y817488D01*
G01Y813551D02*
Y812961D01*
G01Y811780D02*
Y811189D01*
G01Y814929D02*
Y814339D01*
G01Y807252D02*
Y806661D01*
G01Y810402D02*
Y809811D01*
G01Y808630D02*
Y808039D01*
G01Y804102D02*
Y803512D01*
G01Y802331D02*
Y801740D01*
G01Y805480D02*
Y804890D01*
G01Y797803D02*
Y797213D01*
G01Y800953D02*
Y800362D01*
G01Y799181D02*
Y798591D01*
G01Y794654D02*
Y794063D01*
G01Y792882D02*
Y792291D01*
G01Y796031D02*
Y795441D01*
G01Y788354D02*
Y787764D01*
G01Y791504D02*
Y790913D01*
G01Y789732D02*
Y789142D01*
G01Y785205D02*
Y784614D01*
G01Y783433D02*
Y782843D01*
G01Y786583D02*
Y785992D01*
G01Y778906D02*
Y778315D01*
G01Y782055D02*
Y781465D01*
G01Y780283D02*
Y779693D01*
G01Y775756D02*
Y775165D01*
G01Y777134D02*
Y776543D01*
G01X512Y823000D02*
Y822409D01*
G01Y821228D02*
Y820638D01*
G01Y824378D02*
Y823787D01*
G01Y816701D02*
Y816110D01*
G01Y819850D02*
Y819260D01*
G01Y818079D02*
Y817488D01*
G01Y813551D02*
Y812961D01*
G01Y811780D02*
Y811189D01*
G01Y814929D02*
Y814339D01*
G01Y807252D02*
Y806661D01*
G01Y810402D02*
Y809811D01*
G01Y808630D02*
Y808039D01*
G01Y804102D02*
Y803512D01*
G01Y802331D02*
Y801740D01*
G01Y805480D02*
Y804890D01*
G01Y797803D02*
Y797213D01*
G01Y800953D02*
Y800362D01*
G01Y799181D02*
Y798591D01*
G01Y794654D02*
Y794063D01*
G01Y792882D02*
Y792291D01*
G01Y796031D02*
Y795441D01*
G01Y788354D02*
Y787764D01*
G01Y791504D02*
Y790913D01*
G01Y789732D02*
Y789142D01*
G01Y785205D02*
Y784614D01*
G01Y783433D02*
Y782843D01*
G01Y786583D02*
Y785992D01*
G01Y778906D02*
Y778315D01*
G01Y782055D02*
Y781465D01*
G01Y780283D02*
Y779693D01*
G01Y775756D02*
Y775165D01*
G01Y777134D02*
Y776543D01*
G01X709Y825559D02*
Y824378D01*
G01Y822409D02*
Y821228D01*
G01Y816110D02*
Y814929D01*
G01Y819260D02*
Y818079D01*
G01Y812961D02*
Y811780D01*
G01Y806661D02*
Y805480D01*
G01Y809811D02*
Y808630D01*
G01Y803512D02*
Y802331D01*
G01Y797213D02*
Y796031D01*
G01Y800362D02*
Y799181D01*
G01Y794063D02*
Y792882D01*
G01Y787764D02*
Y786583D01*
G01Y790913D02*
Y789732D01*
G01Y784614D02*
Y783433D01*
G01Y778315D02*
Y777134D01*
G01Y781465D02*
Y780283D01*
G01X1074Y825559D02*
Y824378D01*
G01Y822409D02*
Y821228D01*
G01Y816110D02*
Y814929D01*
G01Y819260D02*
Y818079D01*
G01Y812961D02*
Y811780D01*
G01Y806661D02*
Y805480D01*
G01Y809811D02*
Y808630D01*
G01Y803512D02*
Y802331D01*
G01Y797213D02*
Y796031D01*
G01Y800362D02*
Y799181D01*
G01Y794063D02*
Y792882D01*
G01Y787764D02*
Y786583D01*
G01Y790913D02*
Y789732D01*
G01Y784614D02*
Y783433D01*
G01Y778315D02*
Y777134D01*
G01Y781465D02*
Y780283D01*
G01X1184Y825559D02*
Y824378D01*
G01Y822409D02*
Y821228D01*
G01Y816110D02*
Y814929D01*
G01Y819260D02*
Y818079D01*
G01Y812961D02*
Y811780D01*
G01Y806661D02*
Y805480D01*
G01Y809811D02*
Y808630D01*
G01Y803512D02*
Y802331D01*
G01Y797213D02*
Y796031D01*
G01Y800362D02*
Y799181D01*
G01Y794063D02*
Y792882D01*
G01Y787764D02*
Y786583D01*
G01Y790913D02*
Y789732D01*
G01Y784614D02*
Y783433D01*
G01Y778315D02*
Y777134D01*
G01Y781465D02*
Y780283D01*
G01X9965Y825559D02*
Y824378D01*
G01Y822409D02*
Y821228D01*
G01Y816110D02*
Y814929D01*
G01Y819260D02*
Y818079D01*
G01Y812961D02*
Y811780D01*
G01Y806661D02*
Y805480D01*
G01Y809811D02*
Y808630D01*
G01Y803512D02*
Y802331D01*
G01Y797213D02*
Y796031D01*
G01Y800362D02*
Y799181D01*
G01Y794063D02*
Y792882D01*
G01Y787764D02*
Y786583D01*
G01Y790913D02*
Y789732D01*
G01Y784614D02*
Y783433D01*
G01Y778315D02*
Y777134D01*
G01Y781465D02*
Y780283D01*
G01X10075Y825559D02*
Y824378D01*
G01Y822409D02*
Y821228D01*
G01Y816110D02*
Y814929D01*
G01Y819260D02*
Y818079D01*
G01Y812961D02*
Y811780D01*
G01Y806661D02*
Y805480D01*
G01Y809811D02*
Y808630D01*
G01Y803512D02*
Y802331D01*
G01Y797213D02*
Y796031D01*
G01Y800362D02*
Y799181D01*
G01Y794063D02*
Y792882D01*
G01Y787764D02*
Y786583D01*
G01Y790913D02*
Y789732D01*
G01Y784614D02*
Y783433D01*
G01Y778315D02*
Y777134D01*
G01Y781465D02*
Y780283D01*
G01X-14677Y777232D02*
X-14537Y777144D01*
G01X-14449Y777232D02*
X-13977Y776937D01*
G01X-14677Y780382D02*
X-14537Y780294D01*
G01X-14449Y780382D02*
X-13977Y780087D01*
G01X-14677Y783531D02*
X-14537Y783444D01*
G01X-14449Y783531D02*
X-13977Y783236D01*
G01X-14677Y786681D02*
X-14537Y786593D01*
G01X-14449Y786681D02*
X-13977Y786386D01*
G01X-14677Y789831D02*
X-14537Y789743D01*
G01X-14449Y789831D02*
X-13977Y789535D01*
G01X-14677Y792980D02*
X-14537Y792893D01*
G01X-14449Y792980D02*
X-13977Y792685D01*
G01X-14537Y777144D02*
X-14147Y776937D01*
G01X-14537Y780294D02*
X-14147Y780087D01*
G01X-14537Y783444D02*
X-14147Y783236D01*
G01X-14537Y786593D02*
X-14147Y786386D01*
G01X-14537Y789743D02*
X-14147Y789535D01*
G01X-14537Y792893D02*
X-14147Y792685D01*
G01X-14537Y796042D02*
X-14147Y795835D01*
G01X-14537Y799192D02*
X-14147Y798984D01*
G01X-14537Y802341D02*
X-14147Y802134D01*
G01X-14537Y805491D02*
X-14147Y805283D01*
G01X-14537Y808641D02*
X-14147Y808433D01*
G01X-14537Y811790D02*
X-14147Y811583D01*
G01X-14537Y814940D02*
X-14147Y814732D01*
G01X-14537Y818089D02*
X-14147Y817882D01*
G01X-14537Y821239D02*
X-14147Y821031D01*
G01X-14537Y824389D02*
X-14147Y824181D01*
G01X-14677Y796130D02*
X-14537Y796042D01*
G01X-14449Y796130D02*
X-13977Y795835D01*
G01X-14677Y799280D02*
X-14537Y799192D01*
G01X-14449Y799280D02*
X-13977Y798984D01*
G01X-14677Y802429D02*
X-14537Y802341D01*
G01X-14449Y802429D02*
X-13977Y802134D01*
G01X-14677Y805579D02*
X-14537Y805491D01*
G01X-14449Y805579D02*
X-13977Y805283D01*
G01X-14677Y808728D02*
X-14537Y808641D01*
G01X-14449Y808728D02*
X-13977Y808433D01*
G01X-14677Y811878D02*
X-14537Y811790D01*
G01X-14449Y811878D02*
X-13977Y811583D01*
G01X-14677Y815028D02*
X-14537Y814940D01*
G01X-14449Y815028D02*
X-13977Y814732D01*
G01X-14677Y818177D02*
X-14537Y818089D01*
G01X-14449Y818177D02*
X-13977Y817882D01*
G01X-14677Y821327D02*
X-14537Y821239D01*
G01X-14449Y821327D02*
X-13977Y821031D01*
G01X-14677Y824476D02*
X-14537Y824389D01*
G01X-14449Y824476D02*
X-13977Y824181D01*
G01X12410Y775165D02*
X315D01*
G01X-13009Y775362D02*
X-14147D01*
G01X512Y775756D02*
X0D01*
G01X512Y776543D02*
X0D01*
G01X-19469Y777285D02*
X-20801Y777296D01*
G01X-15985Y777248D02*
X-18435Y777270D01*
G01X-19469Y780434D02*
X-20801Y780446D01*
G01X-15985Y780398D02*
X-18435Y780420D01*
G01X-15985Y777248D02*
X-14449Y777232D01*
G01X-15985Y780398D02*
X-14449Y780382D01*
G01X-18435Y777270D02*
X-20801Y777296D01*
G01X-18435Y780420D02*
X-20801Y780446D01*
G01X-19469Y777285D02*
X-16213Y777248D01*
G01X-18174Y777270D02*
X-14677Y777232D01*
G01X-19469Y780434D02*
X-16213Y780398D01*
G01X-18174Y780420D02*
X-14677Y780382D01*
G01X-19469Y778164D02*
X-18174Y778178D01*
G01X-18435D02*
X-20801Y778152D01*
G01X-18174Y778178D02*
X-17126Y778190D01*
G01X-19469Y781314D02*
X-18174Y781328D01*
G01X-18435D02*
X-20801Y781302D01*
G01X-18174Y781328D02*
X-17126Y781339D01*
G01X-19469Y784463D02*
X-18174Y784478D01*
G01X-18435D02*
X-20801Y784452D01*
G01X-18174Y784478D02*
X-17126Y784489D01*
G01X-19469Y787613D02*
X-18174Y787627D01*
G01X-18435D02*
X-20801Y787601D01*
G01X-18174Y787627D02*
X-17126Y787639D01*
G01X-19469Y790763D02*
X-18174Y790777D01*
G01X-18435D02*
X-20801Y790751D01*
G01X-18174Y790777D02*
X-17126Y790788D01*
G01X-19469Y793912D02*
X-18174Y793926D01*
G01X-18435D02*
X-20801Y793900D01*
G01X-18174Y793926D02*
X-17126Y793938D01*
G01X-19469Y797062D02*
X-18174Y797076D01*
G01X-18435D02*
X-20801Y797050D01*
G01X-18174Y797076D02*
X-17126Y797087D01*
G01X-19469Y800211D02*
X-18174Y800226D01*
G01X-18435D02*
X-20801Y800200D01*
G01X-18174Y800226D02*
X-17126Y800237D01*
G01X-19469Y803361D02*
X-18174Y803375D01*
G01X-18435D02*
X-20801Y803349D01*
G01X-18174Y803375D02*
X-17126Y803387D01*
G01X-19469Y806511D02*
X-18174Y806525D01*
G01X-18435D02*
X-20801Y806499D01*
G01X-18174Y806525D02*
X-17126Y806536D01*
G01X-19469Y809660D02*
X-18174Y809674D01*
G01X-18435D02*
X-20801Y809648D01*
G01X-18174Y809674D02*
X-17126Y809686D01*
G01X-19469Y812810D02*
X-18174Y812824D01*
G01X-18435D02*
X-20801Y812798D01*
G01X-18174Y812824D02*
X-17126Y812835D01*
G01X-19469Y815959D02*
X-18174Y815974D01*
G01X-18435D02*
X-20801Y815948D01*
G01X-18174Y815974D02*
X-17126Y815985D01*
G01X-19469Y819109D02*
X-18174Y819123D01*
G01X-18435D02*
X-20801Y819097D01*
G01X-18174Y819123D02*
X-17126Y819135D01*
G01X-19469Y822259D02*
X-18174Y822273D01*
G01X-18435D02*
X-20801Y822247D01*
G01X-18174Y822273D02*
X-17126Y822284D01*
G01X-15985Y778200D02*
X-14449Y778217D01*
G01X-14677D02*
X-18174Y778178D01*
G01X-14677Y778217D02*
X-16213Y778200D01*
G01X-15985Y781350D02*
X-14449Y781366D01*
G01X-14677D02*
X-18174Y781328D01*
G01X-14677Y781366D02*
X-16213Y781350D01*
G01X-15985Y784499D02*
X-14449Y784516D01*
G01X-14677D02*
X-18174Y784478D01*
G01X-14677Y784516D02*
X-16213Y784499D01*
G01X-15985Y787649D02*
X-14449Y787665D01*
G01X-14677D02*
X-18174Y787627D01*
G01X-14677Y787665D02*
X-16213Y787649D01*
G01X-15985Y790798D02*
X-14449Y790815D01*
G01X-14677D02*
X-18174Y790777D01*
G01X-14677Y790815D02*
X-16213Y790798D01*
G01X-15985Y793948D02*
X-14449Y793965D01*
G01X-14677D02*
X-18174Y793926D01*
G01X-14677Y793965D02*
X-16213Y793948D01*
G01X-15985Y797098D02*
X-14449Y797114D01*
G01X-14677D02*
X-18174Y797076D01*
G01X-14677Y797114D02*
X-16213Y797098D01*
G01X-15985Y800247D02*
X-14449Y800264D01*
G01X-14677D02*
X-18174Y800226D01*
G01X-14677Y800264D02*
X-16213Y800247D01*
G01X-15985Y803397D02*
X-14449Y803413D01*
G01X-14677D02*
X-18174Y803375D01*
G01X-14677Y803413D02*
X-16213Y803397D01*
G01X-15985Y806546D02*
X-14449Y806563D01*
G01X-14677D02*
X-18174Y806525D01*
G01X-14677Y806563D02*
X-16213Y806546D01*
G01X-15985Y809696D02*
X-14449Y809713D01*
G01X-14677D02*
X-18174Y809674D01*
G01X-14677Y809713D02*
X-16213Y809696D01*
G01X-15985Y812846D02*
X-14449Y812862D01*
G01X-14677D02*
X-18174Y812824D01*
G01X-14677Y812862D02*
X-16213Y812846D01*
G01X-15985Y815995D02*
X-14449Y816012D01*
G01X-14677D02*
X-18174Y815974D01*
G01X-14677Y816012D02*
X-16213Y815995D01*
G01X-15985Y819145D02*
X-14449Y819161D01*
G01X-14677D02*
X-18174Y819123D01*
G01X-14677Y819161D02*
X-16213Y819145D01*
G01X-15985Y822294D02*
X-14449Y822311D01*
G01X-14677D02*
X-18174Y822273D01*
G01X-14677Y822311D02*
X-16213Y822294D01*
G01X-19469Y778164D02*
X-20801Y778152D01*
G01X-19469Y781314D02*
X-20801Y781302D01*
G01X-19469Y784463D02*
X-20801Y784452D01*
G01X-19469Y787613D02*
X-20801Y787601D01*
G01X-19469Y790763D02*
X-20801Y790751D01*
G01X-19469Y793912D02*
X-20801Y793900D01*
G01X-19469Y797062D02*
X-20801Y797050D01*
G01X-19469Y800211D02*
X-20801Y800200D01*
G01X-19469Y803361D02*
X-20801Y803349D01*
G01X-19469Y806511D02*
X-20801Y806499D01*
G01X-19469Y809660D02*
X-20801Y809648D01*
G01X-19469Y812810D02*
X-20801Y812798D01*
G01X-19469Y815959D02*
X-20801Y815948D01*
G01X-19469Y819109D02*
X-20801Y819097D01*
G01X-19469Y822259D02*
X-20801Y822247D01*
G01X-15985Y778200D02*
X-17126Y778190D01*
G01D02*
X-18435Y778178D01*
G01X-15985Y781350D02*
X-17126Y781339D01*
G01D02*
X-18435Y781328D01*
G01X-15985Y784499D02*
X-17126Y784489D01*
G01X-18435Y784478D02*
X-17126Y784489D01*
G01X-15985Y787649D02*
X-17126Y787639D01*
G01D02*
X-18435Y787627D01*
G01X-15985Y790798D02*
X-17126Y790788D01*
G01D02*
X-18435Y790777D01*
G01X-15985Y793948D02*
X-17126Y793938D01*
G01D02*
X-18435Y793926D01*
G01X-15985Y797098D02*
X-17126Y797087D01*
G01D02*
X-18435Y797076D01*
G01X-15985Y800247D02*
X-17126Y800237D01*
G01D02*
X-18435Y800226D01*
G01X-15985Y803397D02*
X-17126Y803387D01*
G01D02*
X-18435Y803375D01*
G01X-15985Y806546D02*
X-17126Y806536D01*
G01D02*
X-18435Y806525D01*
G01X-15985Y809696D02*
X-17126Y809686D01*
G01D02*
X-18435Y809674D01*
G01X-15985Y812846D02*
X-17126Y812835D01*
G01D02*
X-18435Y812824D01*
G01X-15985Y815995D02*
X-17126Y815985D01*
G01D02*
X-18435Y815974D01*
G01X-15985Y819145D02*
X-17126Y819135D01*
G01D02*
X-18435Y819123D01*
G01X-15985Y822294D02*
X-17126Y822284D01*
G01D02*
X-18435Y822273D01*
G01X-13009Y776937D02*
X-14147D01*
G01X12410Y777134D02*
X315D01*
G01X-14449Y777232D02*
X-14677D01*
G01X-15985Y777248D02*
X-16213D01*
G01X-18174Y777270D02*
X-18435D01*
G01X-18174Y778178D02*
X-18435D01*
G01X-15985Y778200D02*
X-16213D01*
G01X-14449Y778217D02*
X-14677D01*
G01X12410Y778315D02*
X315D01*
G01X-13009Y778512D02*
X-14147D01*
G01X512Y778906D02*
X0D01*
G01X512Y779693D02*
X0D01*
G01X-13009Y780087D02*
X-14147D01*
G01X12410Y780283D02*
X315D01*
G01X-14449Y780382D02*
X-14677D01*
G01X-15985Y780398D02*
X-16213D01*
G01X-18174Y780420D02*
X-18435D01*
G01X-18174Y781328D02*
X-18435D01*
G01X-15985Y781350D02*
X-16213D01*
G01X-14449Y781366D02*
X-14677D01*
G01X12410Y781465D02*
X315D01*
G01X-13009Y781661D02*
X-14147D01*
G01X512Y782055D02*
X0D01*
G01X512Y782843D02*
X0D01*
G01X-13009Y783236D02*
X-14147D01*
G01X12410Y783433D02*
X315D01*
G01X-14449Y783531D02*
X-14677D01*
G01X-15985Y783548D02*
X-16213D01*
G01X-18174Y783569D02*
X-18435D01*
G01X-18174Y784478D02*
X-18435D01*
G01X-15985Y784499D02*
X-16213D01*
G01X-14449Y784516D02*
X-14677D01*
G01X12410Y784614D02*
X315D01*
G01X-13009Y784811D02*
X-14147D01*
G01X512Y785205D02*
X0D01*
G01X512Y785992D02*
X0D01*
G01X-13009Y786386D02*
X-14147D01*
G01X12410Y786583D02*
X315D01*
G01X-14449Y786681D02*
X-14677D01*
G01X-15985Y786697D02*
X-16213D01*
G01X-18174Y786719D02*
X-18435D01*
G01X-18174Y787627D02*
X-18435D01*
G01X-15985Y787649D02*
X-16213D01*
G01X-14449Y787665D02*
X-14677D01*
G01X12410Y787764D02*
X315D01*
G01X-13009Y787961D02*
X-14147D01*
G01X512Y788354D02*
X0D01*
G01X512Y789142D02*
X0D01*
G01X-13009Y789535D02*
X-14147D01*
G01X12410Y789732D02*
X315D01*
G01X-14449Y789831D02*
X-14677D01*
G01X-15985Y789847D02*
X-16213D01*
G01X-18174Y789869D02*
X-18435D01*
G01X-18174Y790777D02*
X-18435D01*
G01X-15985Y790798D02*
X-16213D01*
G01X-14449Y790815D02*
X-14677D01*
G01X12410Y790913D02*
X315D01*
G01X-13009Y791110D02*
X-14147D01*
G01X512Y791504D02*
X0D01*
G01X512Y792291D02*
X0D01*
G01X-13009Y792685D02*
X-14147D01*
G01X12410Y792882D02*
X315D01*
G01X-14449Y792980D02*
X-14677D01*
G01X-15985Y792996D02*
X-16213D01*
G01X-18174Y793018D02*
X-18435D01*
G01X-18174Y793926D02*
X-18435D01*
G01X-15985Y793948D02*
X-16213D01*
G01X-14449Y793965D02*
X-14677D01*
G01X12410Y794063D02*
X315D01*
G01X-13009Y794260D02*
X-14147D01*
G01X512Y794654D02*
X0D01*
G01X512Y795441D02*
X0D01*
G01X-13009Y795835D02*
X-14147D01*
G01X12410Y796031D02*
X315D01*
G01X-14449Y796130D02*
X-14677D01*
G01X-15985Y796146D02*
X-16213D01*
G01X-18174Y796168D02*
X-18435D01*
G01X-18174Y797076D02*
X-18435D01*
G01X-15985Y797098D02*
X-16213D01*
G01X-14449Y797114D02*
X-14677D01*
G01X12410Y797213D02*
X315D01*
G01X-13009Y797409D02*
X-14147D01*
G01X512Y797803D02*
X0D01*
G01X512Y798591D02*
X0D01*
G01X-13009Y798984D02*
X-14147D01*
G01X12410Y799181D02*
X315D01*
G01X-14449Y799280D02*
X-14677D01*
G01X-15985Y799296D02*
X-16213D01*
G01X-18174Y799317D02*
X-18435D01*
G01X-18174Y800226D02*
X-18435D01*
G01X-15985Y800247D02*
X-16213D01*
G01X-14449Y800264D02*
X-14677D01*
G01X12410Y800362D02*
X315D01*
G01X-13009Y800559D02*
X-14147D01*
G01X512Y800953D02*
X0D01*
G01X512Y801740D02*
X0D01*
G01X-13009Y802134D02*
X-14147D01*
G01X12410Y802331D02*
X315D01*
G01X-14449Y802429D02*
X-14677D01*
G01X-15985Y802445D02*
X-16213D01*
G01X-18174Y802467D02*
X-18435D01*
G01X-18174Y803375D02*
X-18435D01*
G01X-15985Y803397D02*
X-16213D01*
G01X-14449Y803413D02*
X-14677D01*
G01X12410Y803512D02*
X315D01*
G01X-13009Y803709D02*
X-14147D01*
G01X512Y804102D02*
X0D01*
G01X512Y804890D02*
X0D01*
G01X-13009Y805283D02*
X-14147D01*
G01X12410Y805480D02*
X315D01*
G01X-14449Y805579D02*
X-14677D01*
G01X-15985Y805595D02*
X-16213D01*
G01X-18174Y805617D02*
X-18435D01*
G01X-18174Y806525D02*
X-18435D01*
G01X-15985Y806546D02*
X-16213D01*
G01X-14449Y806563D02*
X-14677D01*
G01X12410Y806661D02*
X315D01*
G01X-13009Y806858D02*
X-14147D01*
G01X512Y807252D02*
X0D01*
G01X512Y808039D02*
X0D01*
G01X-13009Y808433D02*
X-14147D01*
G01X12410Y808630D02*
X315D01*
G01X-14449Y808728D02*
X-14677D01*
G01X-15985Y808744D02*
X-16213D01*
G01X-18174Y808766D02*
X-18435D01*
G01X-18174Y809674D02*
X-18435D01*
G01X-15985Y809696D02*
X-16213D01*
G01X-14449Y809713D02*
X-14677D01*
G01X12410Y809811D02*
X315D01*
G01X-13009Y810008D02*
X-14147D01*
G01X512Y810402D02*
X0D01*
G01X512Y811189D02*
X0D01*
G01X-13009Y811583D02*
X-14147D01*
G01X12410Y811780D02*
X315D01*
G01X-14449Y811878D02*
X-14677D01*
G01X-15985Y811894D02*
X-16213D01*
G01X-18174Y811916D02*
X-18435D01*
G01X-18174Y812824D02*
X-18435D01*
G01X-15985Y812846D02*
X-16213D01*
G01X-14449Y812862D02*
X-14677D01*
G01X12410Y812961D02*
X315D01*
G01X-13009Y813157D02*
X-14147D01*
G01X512Y813551D02*
X0D01*
G01X512Y814339D02*
X0D01*
G01X-13009Y814732D02*
X-14147D01*
G01X12410Y814929D02*
X315D01*
G01X-14449Y815028D02*
X-14677D01*
G01X-15985Y815044D02*
X-16213D01*
G01X-18174Y815065D02*
X-18435D01*
G01X-18174Y815974D02*
X-18435D01*
G01X-15985Y815995D02*
X-16213D01*
G01X-14449Y816012D02*
X-14677D01*
G01X12410Y816110D02*
X315D01*
G01X-13009Y816307D02*
X-14147D01*
G01X512Y816701D02*
X0D01*
G01X512Y817488D02*
X0D01*
G01X-13009Y817882D02*
X-14147D01*
G01X12410Y818079D02*
X315D01*
G01X-14449Y818177D02*
X-14677D01*
G01X-15985Y818193D02*
X-16213D01*
G01X-18174Y818215D02*
X-18435D01*
G01X-18174Y819123D02*
X-18435D01*
G01X-16213Y819145D02*
X-15985D01*
G01X-14449Y819161D02*
X-14677D01*
G01X12410Y819260D02*
X315D01*
G01X-13009Y819457D02*
X-14147D01*
G01X512Y819850D02*
X0D01*
G01X512Y820638D02*
X0D01*
G01X-13009Y821031D02*
X-14147D01*
G01X12410Y821228D02*
X315D01*
G01X-14449Y821327D02*
X-14677D01*
G01X-15985Y821343D02*
X-16213D01*
G01X-18174Y821365D02*
X-18435D01*
G01X-18174Y822273D02*
X-18435D01*
G01X-15985Y822294D02*
X-16213D01*
G01X-14449Y822311D02*
X-14677D01*
G01X12410Y822409D02*
X315D01*
G01X-13009Y822606D02*
X-14147D01*
G01X512Y823000D02*
X0D01*
G01X512Y823787D02*
X0D01*
G01X-13009Y824181D02*
X-14147D01*
G01X12410Y824378D02*
X315D01*
G01X-14449Y824476D02*
X-14677D01*
G01X-15985Y824493D02*
X-16213D01*
G01X-18174Y824514D02*
X-18435D01*
G01X-19469Y783584D02*
X-20801Y783596D01*
G01X-15985Y783548D02*
X-18435Y783569D01*
G01X-19469Y786733D02*
X-20801Y786745D01*
G01X-15985Y786697D02*
X-18435Y786719D01*
G01X-19469Y789883D02*
X-20801Y789895D01*
G01X-15985Y789847D02*
X-18435Y789869D01*
G01X-19469Y793033D02*
X-20801Y793044D01*
G01X-15985Y792996D02*
X-18435Y793018D01*
G01X-19469Y796182D02*
X-20801Y796194D01*
G01X-15985Y796146D02*
X-18435Y796168D01*
G01X-19469Y799332D02*
X-20801Y799344D01*
G01X-15985Y799296D02*
X-18435Y799317D01*
G01X-19469Y802481D02*
X-20801Y802493D01*
G01X-15985Y802445D02*
X-18435Y802467D01*
G01X-19469Y805631D02*
X-20801Y805643D01*
G01X-15985Y805595D02*
X-18435Y805617D01*
G01X-19469Y808781D02*
X-20801Y808793D01*
G01X-15985Y808744D02*
X-18435Y808766D01*
G01X-19469Y811930D02*
X-20801Y811942D01*
G01X-15985Y811894D02*
X-18435Y811916D01*
G01X-19469Y815080D02*
X-20801Y815092D01*
G01X-15985Y815044D02*
X-18435Y815065D01*
G01X-19469Y818230D02*
X-20801Y818241D01*
G01X-15985Y818193D02*
X-18435Y818215D01*
G01X-19469Y821379D02*
X-20801Y821391D01*
G01X-15985Y821343D02*
X-18435Y821365D01*
G01X-19469Y824529D02*
X-20801Y824541D01*
G01X-15985Y824493D02*
X-18435Y824514D01*
G01X-15985Y783548D02*
X-14449Y783531D01*
G01X-15985Y786697D02*
X-14449Y786681D01*
G01X-15985Y789847D02*
X-14449Y789831D01*
G01X-15985Y792996D02*
X-14449Y792980D01*
G01X-15985Y796146D02*
X-14449Y796130D01*
G01X-15985Y799296D02*
X-14449Y799280D01*
G01X-15985Y802445D02*
X-14449Y802429D01*
G01X-15985Y805595D02*
X-14449Y805579D01*
G01X-15985Y808744D02*
X-14449Y808728D01*
G01X-15985Y811894D02*
X-14449Y811878D01*
G01X-15985Y815044D02*
X-14449Y815028D01*
G01X-15985Y818193D02*
X-14449Y818177D01*
G01X-15985Y821343D02*
X-14449Y821327D01*
G01X-15985Y824493D02*
X-14449Y824476D01*
G01X-18435Y783569D02*
X-20801Y783596D01*
G01X-18435Y786719D02*
X-20801Y786745D01*
G01X-18435Y789869D02*
X-20801Y789895D01*
G01X-18435Y793018D02*
X-20801Y793044D01*
G01X-18435Y796168D02*
X-20801Y796194D01*
G01X-18435Y799317D02*
X-20801Y799344D01*
G01X-18435Y802467D02*
X-20801Y802493D01*
G01X-18435Y805617D02*
X-20801Y805643D01*
G01X-18435Y808766D02*
X-20801Y808793D01*
G01X-18435Y811916D02*
X-20801Y811942D01*
G01X-18435Y815065D02*
X-20801Y815092D01*
G01X-18435Y818215D02*
X-20801Y818241D01*
G01X-18435Y821365D02*
X-20801Y821391D01*
G01X-18435Y824514D02*
X-20801Y824541D01*
G01X-19469Y783584D02*
X-16213Y783548D01*
G01X-18174Y783569D02*
X-14677Y783531D01*
G01X-19469Y786733D02*
X-16213Y786697D01*
G01X-18174Y786719D02*
X-14677Y786681D01*
G01X-19469Y789883D02*
X-16213Y789847D01*
G01X-18174Y789869D02*
X-14677Y789831D01*
G01X-19469Y793033D02*
X-16213Y792996D01*
G01X-18174Y793018D02*
X-14677Y792980D01*
G01X-19469Y796182D02*
X-16213Y796146D01*
G01X-18174Y796168D02*
X-14677Y796130D01*
G01X-19469Y799332D02*
X-16213Y799296D01*
G01X-18174Y799317D02*
X-14677Y799280D01*
G01X-19469Y802481D02*
X-16213Y802445D01*
G01X-18174Y802467D02*
X-14677Y802429D01*
G01X-19469Y805631D02*
X-16213Y805595D01*
G01X-18174Y805617D02*
X-14677Y805579D01*
G01X-19469Y808781D02*
X-16213Y808744D01*
G01X-18174Y808766D02*
X-14677Y808728D01*
G01X-19469Y811930D02*
X-16213Y811894D01*
G01X-18174Y811916D02*
X-14677Y811878D01*
G01X-19469Y815080D02*
X-16213Y815044D01*
G01X-18174Y815065D02*
X-14677Y815028D01*
G01X-19469Y818230D02*
X-16213Y818193D01*
G01X-18174Y818215D02*
X-14677Y818177D01*
G01X-19469Y821379D02*
X-16213Y821343D01*
G01X-18174Y821365D02*
X-14677Y821327D01*
G01X-19469Y824529D02*
X-16213Y824493D01*
G01X-18174Y824514D02*
X-14677Y824476D01*
G01X-14537Y822399D02*
X-14677Y822311D01*
G01X-13977Y822606D02*
X-14449Y822311D01*
G01X-14537Y819249D02*
X-14677Y819161D01*
G01X-13977Y819457D02*
X-14449Y819161D01*
G01X-14537Y816100D02*
X-14677Y816012D01*
G01X-13977Y816307D02*
X-14449Y816012D01*
G01X-14537Y812950D02*
X-14677Y812862D01*
G01X-13977Y813157D02*
X-14449Y812862D01*
G01X-14537Y809800D02*
X-14677Y809713D01*
G01X-13977Y810008D02*
X-14449Y809713D01*
G01X-14537Y806651D02*
X-14677Y806563D01*
G01X-13977Y806858D02*
X-14449Y806563D01*
G01X-14537Y803501D02*
X-14677Y803413D01*
G01X-13977Y803709D02*
X-14449Y803413D01*
G01X-14537Y800352D02*
X-14677Y800264D01*
G01X-13977Y800559D02*
X-14449Y800264D01*
G01X-14537Y797202D02*
X-14677Y797114D01*
G01X-13977Y797409D02*
X-14449Y797114D01*
G01X-14537Y794052D02*
X-14677Y793965D01*
G01X-13977Y794260D02*
X-14449Y793965D01*
G01X-14537Y790903D02*
X-14677Y790815D01*
G01X-13977Y791110D02*
X-14449Y790815D01*
G01X-14537Y787753D02*
X-14677Y787665D01*
G01X-13977Y787961D02*
X-14449Y787665D01*
G01X-14537Y784604D02*
X-14677Y784516D01*
G01X-13977Y784811D02*
X-14449Y784516D01*
G01X-14537Y781454D02*
X-14677Y781366D01*
G01X-13977Y781661D02*
X-14449Y781366D01*
G01X-14537Y778304D02*
X-14677Y778217D01*
G01X-13977Y778512D02*
X-14449Y778217D01*
G01X-14147Y822606D02*
X-14537Y822399D01*
G01X-14147Y819457D02*
X-14537Y819249D01*
G01X-14147Y816307D02*
X-14537Y816100D01*
G01X-14147Y813157D02*
X-14537Y812950D01*
G01X-14147Y810008D02*
X-14537Y809800D01*
G01X-14147Y806858D02*
X-14537Y806651D01*
G01X-14147Y803709D02*
X-14537Y803501D01*
G01X-14147Y800559D02*
X-14537Y800352D01*
G01X-14147Y797409D02*
X-14537Y797202D01*
G01X-14147Y794260D02*
X-14537Y794052D01*
G01X-14147Y791110D02*
X-14537Y790903D01*
G01X-14147Y787961D02*
X-14537Y787753D01*
G01X-14147Y784811D02*
X-14537Y784604D01*
G01X-14147Y781661D02*
X-14537Y781454D01*
G01X-14147Y778512D02*
X-14537Y778304D01*
G01X12057Y863354D02*
Y862173D01*
G01Y860205D02*
Y859024D01*
G01Y853906D02*
Y852724D01*
G01Y857055D02*
Y855874D01*
G01Y850756D02*
Y849575D01*
G01X12410Y863354D02*
Y862173D01*
G01Y860205D02*
Y859024D01*
G01Y853906D02*
Y852724D01*
G01Y857055D02*
Y855874D01*
G01Y850756D02*
Y849575D01*
G01X13353Y863098D02*
Y862429D01*
G01Y859949D02*
Y859280D01*
G01Y853650D02*
Y852980D01*
G01Y856799D02*
Y856130D01*
G01Y850500D02*
Y849831D01*
G01X13701Y863098D02*
Y862429D01*
G01Y859949D02*
Y859280D01*
G01Y853650D02*
Y852980D01*
G01Y856799D02*
Y856130D01*
G01Y850500D02*
Y849831D01*
G01X12057Y850756D02*
X12287Y850500D01*
G01X12057Y853906D02*
X12287Y853650D01*
G01X12057Y857055D02*
X12287Y856799D01*
G01X12057Y860205D02*
X12287Y859949D01*
G01X12057Y863354D02*
X12287Y863098D01*
G01X12416Y850770D02*
X12634Y850500D01*
G01X12416Y853920D02*
X12634Y853650D01*
G01X12416Y857069D02*
X12634Y856799D01*
G01X12416Y860219D02*
X12634Y859949D01*
G01X12416Y863369D02*
X12634Y863098D01*
G01Y862429D02*
X12416Y862159D01*
G01X12634Y859280D02*
X12416Y859009D01*
G01X12634Y856130D02*
X12416Y855860D01*
G01X12634Y852980D02*
X12416Y852710D01*
G01X12634Y849831D02*
X12416Y849561D01*
G01X12287Y862429D02*
X12057Y862173D01*
G01X12287Y859280D02*
X12057Y859024D01*
G01X12287Y856130D02*
X12057Y855874D01*
G01X12287Y852980D02*
X12057Y852724D01*
G01X12287Y849831D02*
X12057Y849575D01*
G01X13701Y849831D02*
X12287D01*
G01X13701Y850500D02*
X12287D01*
G01X13701Y852980D02*
X12287D01*
G01X13701Y853650D02*
X12287D01*
G01X13701Y856130D02*
X12287D01*
G01X13701Y856799D02*
X12287D01*
G01X13701Y859280D02*
X12287D01*
G01X13701Y859949D02*
X12287D01*
G01X13701Y862429D02*
X12287D01*
G01X13701Y863098D02*
X12287D01*
G01X12057Y920047D02*
Y918866D01*
G01Y916898D02*
Y915717D01*
G01Y910598D02*
Y909417D01*
G01Y913748D02*
Y912567D01*
G01Y907449D02*
Y906268D01*
G01Y901150D02*
Y899969D01*
G01Y904299D02*
Y903118D01*
G01Y898000D02*
Y896819D01*
G01Y891701D02*
Y890520D01*
G01Y894850D02*
Y893669D01*
G01Y888551D02*
Y887370D01*
G01X12410Y920047D02*
Y918866D01*
G01Y916898D02*
Y915717D01*
G01Y910598D02*
Y909417D01*
G01Y913748D02*
Y912567D01*
G01Y907449D02*
Y906268D01*
G01Y901150D02*
Y899969D01*
G01Y904299D02*
Y903118D01*
G01Y898000D02*
Y896819D01*
G01Y891701D02*
Y890520D01*
G01Y894850D02*
Y893669D01*
G01Y888551D02*
Y887370D01*
G01X13353Y919791D02*
Y919122D01*
G01Y916642D02*
Y915972D01*
G01Y910343D02*
Y909673D01*
G01Y913492D02*
Y912823D01*
G01Y907193D02*
Y906524D01*
G01Y900894D02*
Y900224D01*
G01Y904043D02*
Y903374D01*
G01Y897744D02*
Y897075D01*
G01Y891445D02*
Y890776D01*
G01Y894594D02*
Y893925D01*
G01Y888295D02*
Y887626D01*
G01X13701Y919791D02*
Y919122D01*
G01Y916642D02*
Y915972D01*
G01Y910343D02*
Y909673D01*
G01Y913492D02*
Y912823D01*
G01Y907193D02*
Y906524D01*
G01Y900894D02*
Y900224D01*
G01Y904043D02*
Y903374D01*
G01Y897744D02*
Y897075D01*
G01Y891445D02*
Y890776D01*
G01Y894594D02*
Y893925D01*
G01Y888295D02*
Y887626D01*
G01X12416Y888565D02*
X12634Y888295D01*
G01X12416Y891715D02*
X12634Y891445D01*
G01X12416Y894865D02*
X12634Y894594D01*
G01X12057Y888551D02*
X12287Y888295D01*
G01X12057Y891701D02*
X12287Y891445D01*
G01X12057Y894850D02*
X12287Y894594D01*
G01X12057Y898000D02*
X12287Y897744D01*
G01X12057Y901150D02*
X12287Y900894D01*
G01X12057Y904299D02*
X12287Y904043D01*
G01X12057Y907449D02*
X12287Y907193D01*
G01X12057Y910598D02*
X12287Y910343D01*
G01X12057Y913748D02*
X12287Y913492D01*
G01X12057Y916898D02*
X12287Y916642D01*
G01X12057Y920047D02*
X12287Y919791D01*
G01X12416Y898014D02*
X12634Y897744D01*
G01X12416Y901164D02*
X12634Y900894D01*
G01X12416Y904313D02*
X12634Y904043D01*
G01X12416Y907463D02*
X12634Y907193D01*
G01X12416Y910613D02*
X12634Y910343D01*
G01X12416Y913762D02*
X12634Y913492D01*
G01X12416Y916912D02*
X12634Y916642D01*
G01X12416Y920061D02*
X12634Y919791D01*
G01Y919122D02*
X12416Y918852D01*
G01X12634Y915972D02*
X12416Y915702D01*
G01X12634Y912823D02*
X12416Y912553D01*
G01X12634Y909673D02*
X12416Y909403D01*
G01X12634Y906524D02*
X12416Y906254D01*
G01X12634Y903374D02*
X12416Y903104D01*
G01X12634Y900224D02*
X12416Y899954D01*
G01X12634Y897075D02*
X12416Y896805D01*
G01X12634Y893925D02*
X12416Y893655D01*
G01X12634Y890776D02*
X12416Y890506D01*
G01X12634Y887626D02*
X12416Y887356D01*
G01X12287Y919122D02*
X12057Y918866D01*
G01X12287Y915972D02*
X12057Y915717D01*
G01X12287Y912823D02*
X12057Y912567D01*
G01X12287Y909673D02*
X12057Y909417D01*
G01X12287Y906524D02*
X12057Y906268D01*
G01X12287Y903374D02*
X12057Y903118D01*
G01X12287Y900224D02*
X12057Y899969D01*
G01X12287Y897075D02*
X12057Y896819D01*
G01X12287Y893925D02*
X12057Y893669D01*
G01X12287Y890776D02*
X12057Y890520D01*
G01X12287Y887626D02*
X12057Y887370D01*
G01X13701Y887626D02*
X12287D01*
G01X13701Y888295D02*
X12287D01*
G01X13701Y890776D02*
X12287D01*
G01X13701Y891445D02*
X12287D01*
G01X13701Y893925D02*
X12287D01*
G01X13701Y894594D02*
X12287D01*
G01X13701Y897075D02*
X12287D01*
G01X13701Y897744D02*
X12287D01*
G01X13701Y900224D02*
X12287D01*
G01X13701Y900894D02*
X12287D01*
G01X13701Y903374D02*
X12287D01*
G01X13701Y904043D02*
X12287D01*
G01X13701Y906524D02*
X12287D01*
G01X13701Y907193D02*
X12287D01*
G01X13701Y909673D02*
X12287D01*
G01X13701Y910343D02*
X12287D01*
G01X13701Y912823D02*
X12287D01*
G01X13701Y913492D02*
X12287D01*
G01X13701Y915972D02*
X12287D01*
G01X13701Y916642D02*
X12287D01*
G01X13701Y919122D02*
X12287D01*
G01X13701Y919791D02*
X12287D01*
G01X12057Y882252D02*
Y881071D01*
G01Y885402D02*
Y884220D01*
G01Y879102D02*
Y877921D01*
G01Y872803D02*
Y871622D01*
G01Y875953D02*
Y874772D01*
G01Y869654D02*
Y868472D01*
G01Y866504D02*
Y865323D01*
G01X12410Y882252D02*
Y881071D01*
G01Y885402D02*
Y884220D01*
G01Y879102D02*
Y877921D01*
G01Y872803D02*
Y871622D01*
G01Y875953D02*
Y874772D01*
G01Y869654D02*
Y868472D01*
G01Y866504D02*
Y865323D01*
G01X13353Y881996D02*
Y881327D01*
G01Y885146D02*
Y884476D01*
G01Y878846D02*
Y878177D01*
G01Y872547D02*
Y871878D01*
G01Y875697D02*
Y875028D01*
G01Y869398D02*
Y868728D01*
G01Y866248D02*
Y865579D01*
G01X13701Y881996D02*
Y881327D01*
G01Y885146D02*
Y884476D01*
G01Y878846D02*
Y878177D01*
G01Y872547D02*
Y871878D01*
G01Y875697D02*
Y875028D01*
G01Y869398D02*
Y868728D01*
G01Y866248D02*
Y865579D01*
G01X12057Y866504D02*
X12287Y866248D01*
G01X12057Y869654D02*
X12287Y869398D01*
G01X12057Y872803D02*
X12287Y872547D01*
G01X12057Y875953D02*
X12287Y875697D01*
G01X12416Y866518D02*
X12634Y866248D01*
G01X12416Y869668D02*
X12634Y869398D01*
G01X12416Y872817D02*
X12634Y872547D01*
G01X12416Y875967D02*
X12634Y875697D01*
G01X12416Y879117D02*
X12634Y878846D01*
G01X12416Y882266D02*
X12634Y881996D01*
G01X12416Y885416D02*
X12634Y885146D01*
G01X12057Y879102D02*
X12287Y878846D01*
G01X12057Y882252D02*
X12287Y881996D01*
G01X12057Y885402D02*
X12287Y885146D01*
G01X12634Y884476D02*
X12416Y884206D01*
G01X12634Y881327D02*
X12416Y881057D01*
G01X12634Y878177D02*
X12416Y877907D01*
G01X12634Y875028D02*
X12416Y874757D01*
G01X12634Y871878D02*
X12416Y871608D01*
G01X12634Y868728D02*
X12416Y868458D01*
G01X12634Y865579D02*
X12416Y865309D01*
G01X12287Y884476D02*
X12057Y884220D01*
G01X12287Y881327D02*
X12057Y881071D01*
G01X12287Y878177D02*
X12057Y877921D01*
G01X12287Y875028D02*
X12057Y874772D01*
G01X12287Y871878D02*
X12057Y871622D01*
G01X12287Y868728D02*
X12057Y868472D01*
G01X12287Y865579D02*
X12057Y865323D01*
G01X13701Y865579D02*
X12287D01*
G01X13701Y866248D02*
X12287D01*
G01X13701Y868728D02*
X12287D01*
G01X13701Y869398D02*
X12287D01*
G01X13701Y871878D02*
X12287D01*
G01X13701Y872547D02*
X12287D01*
G01X13701Y875028D02*
X12287D01*
G01X13701Y875697D02*
X12287D01*
G01X13701Y878177D02*
X12287D01*
G01X13701Y878846D02*
X12287D01*
G01X13701Y881327D02*
X12287D01*
G01X13701Y881996D02*
X12287D01*
G01X13701Y884476D02*
X12287D01*
G01X13701Y885146D02*
X12287D01*
G01X-20801Y863192D02*
Y862336D01*
G01Y860042D02*
Y859186D01*
G01Y853743D02*
Y852887D01*
G01Y856893D02*
Y856037D01*
G01Y850593D02*
Y849737D01*
G01X-19469Y863198D02*
Y862330D01*
G01Y860048D02*
Y859180D01*
G01Y853749D02*
Y852881D01*
G01Y856898D02*
Y856031D01*
G01Y850599D02*
Y849731D01*
G01X-18435Y863218D02*
Y862309D01*
G01Y860068D02*
Y859160D01*
G01Y853769D02*
Y852861D01*
G01Y856919D02*
Y856010D01*
G01Y850619D02*
Y849711D01*
G01X-18174Y863218D02*
Y862309D01*
G01Y860068D02*
Y859160D01*
G01Y853769D02*
Y852861D01*
G01Y856919D02*
Y856010D01*
G01Y850619D02*
Y849711D01*
G01X-16213Y863239D02*
Y862288D01*
G01Y860090D02*
Y859138D01*
G01Y853791D02*
Y852839D01*
G01Y856940D02*
Y855989D01*
G01Y850641D02*
Y849689D01*
G01X-15985Y863239D02*
Y862288D01*
G01Y860090D02*
Y859138D01*
G01Y853791D02*
Y852839D01*
G01Y856940D02*
Y855989D01*
G01Y850641D02*
Y849689D01*
G01X-14537Y863344D02*
Y862184D01*
G01Y860194D02*
Y859034D01*
G01Y853895D02*
Y852735D01*
G01Y857044D02*
Y855885D01*
G01Y850745D02*
Y849585D01*
G01X-13009Y863551D02*
Y861976D01*
G01Y866701D02*
Y865126D01*
G01Y860402D02*
Y858827D01*
G01Y854102D02*
Y852528D01*
G01Y857252D02*
Y855677D01*
G01Y850953D02*
Y849378D01*
G01X315Y863945D02*
Y863354D01*
G01Y865323D02*
Y864732D01*
G01Y860795D02*
Y860205D01*
G01Y859024D02*
Y858433D01*
G01Y862173D02*
Y861583D01*
G01Y854496D02*
Y853906D01*
G01Y857646D02*
Y857055D01*
G01Y855874D02*
Y855283D01*
G01Y851346D02*
Y850756D01*
G01Y849575D02*
Y848984D01*
G01Y852724D02*
Y852134D01*
G01X512Y863945D02*
Y863354D01*
G01Y865323D02*
Y864732D01*
G01Y860795D02*
Y860205D01*
G01Y859024D02*
Y858433D01*
G01Y862173D02*
Y861583D01*
G01Y854496D02*
Y853906D01*
G01Y857646D02*
Y857055D01*
G01Y855874D02*
Y855283D01*
G01Y851346D02*
Y850756D01*
G01Y849575D02*
Y848984D01*
G01Y852724D02*
Y852134D01*
G01X709Y863354D02*
Y862173D01*
G01Y860205D02*
Y859024D01*
G01Y853906D02*
Y852724D01*
G01Y857055D02*
Y855874D01*
G01Y850756D02*
Y849575D01*
G01X1074Y863354D02*
Y862173D01*
G01Y860205D02*
Y859024D01*
G01Y853906D02*
Y852724D01*
G01Y857055D02*
Y855874D01*
G01Y850756D02*
Y849575D01*
G01X1184Y863354D02*
Y862173D01*
G01Y860205D02*
Y859024D01*
G01Y853906D02*
Y852724D01*
G01Y857055D02*
Y855874D01*
G01Y850756D02*
Y849575D01*
G01X9965Y863354D02*
Y862173D01*
G01Y860205D02*
Y859024D01*
G01Y853906D02*
Y852724D01*
G01Y857055D02*
Y855874D01*
G01Y850756D02*
Y849575D01*
G01X10075Y863354D02*
Y862173D01*
G01Y860205D02*
Y859024D01*
G01Y853906D02*
Y852724D01*
G01Y857055D02*
Y855874D01*
G01Y850756D02*
Y849575D01*
G01X-14537Y849585D02*
X-14147Y849378D01*
G01X-14537Y852735D02*
X-14147Y852528D01*
G01X-14677Y849673D02*
X-14537Y849585D01*
G01X-14449Y849673D02*
X-13977Y849378D01*
G01X-14677Y852823D02*
X-14537Y852735D01*
G01X-14449Y852823D02*
X-13977Y852528D01*
G01X-14677Y855972D02*
X-14537Y855885D01*
G01X-14449Y855972D02*
X-13977Y855677D01*
G01X-14677Y859122D02*
X-14537Y859034D01*
G01X-14449Y859122D02*
X-13977Y858827D01*
G01X-14677Y862272D02*
X-14537Y862184D01*
G01X-14449Y862272D02*
X-13977Y861976D01*
G01X-14449Y865421D02*
X-13977Y865126D01*
G01X-14537Y855885D02*
X-14147Y855677D01*
G01X-14537Y859034D02*
X-14147Y858827D01*
G01X-14537Y862184D02*
X-14147Y861976D01*
G01X-14537Y865333D02*
X-14147Y865126D01*
G01X-14537Y863344D02*
X-14677Y863256D01*
G01X-13977Y863551D02*
X-14449Y863256D01*
G01X-14537Y860194D02*
X-14677Y860106D01*
G01X-13977Y860402D02*
X-14449Y860106D01*
G01X-14537Y857044D02*
X-14677Y856957D01*
G01X-13977Y857252D02*
X-14449Y856957D01*
G01X-14537Y853895D02*
X-14677Y853807D01*
G01X-13977Y854102D02*
X-14449Y853807D01*
G01X-14537Y850745D02*
X-14677Y850657D01*
G01X-13977Y850953D02*
X-14449Y850657D01*
G01X512Y848197D02*
X0D01*
G01X512Y848984D02*
X0D01*
G01X-13009Y849378D02*
X-14147D01*
G01X12410Y849575D02*
X315D01*
G01X-14449Y849673D02*
X-14677D01*
G01X-15985Y849689D02*
X-16213D01*
G01X-18174Y849711D02*
X-18435D01*
G01X-18174Y850619D02*
X-18435D01*
G01X-15985Y850641D02*
X-16213D01*
G01X-14449Y850657D02*
X-14677D01*
G01X12410Y850756D02*
X315D01*
G01X-13009Y850953D02*
X-14147D01*
G01X512Y851346D02*
X0D01*
G01X512Y852134D02*
X0D01*
G01X-13009Y852528D02*
X-14147D01*
G01X12410Y852724D02*
X315D01*
G01X-14449Y852823D02*
X-14677D01*
G01X-15985Y852839D02*
X-16213D01*
G01X-18174Y852861D02*
X-18435D01*
G01X-19469Y849726D02*
X-20801Y849737D01*
G01X-15985Y849689D02*
X-18435Y849711D01*
G01X-19469Y852875D02*
X-20801Y852887D01*
G01X-15985Y852839D02*
X-18435Y852861D01*
G01X-19469Y856025D02*
X-20801Y856037D01*
G01X-15985Y855989D02*
X-18435Y856010D01*
G01X-15985Y849689D02*
X-14449Y849673D01*
G01X-15985Y852839D02*
X-14449Y852823D01*
G01X-15985Y855989D02*
X-14449Y855972D01*
G01X-18435Y849711D02*
X-20801Y849737D01*
G01X-18435Y852861D02*
X-20801Y852887D01*
G01X-18435Y856010D02*
X-20801Y856037D01*
G01X-19469Y849726D02*
X-16213Y849689D01*
G01X-18174Y849711D02*
X-14677Y849673D01*
G01X-19469Y852875D02*
X-16213Y852839D01*
G01X-18174Y852861D02*
X-14677Y852823D01*
G01X-19469Y856025D02*
X-16213Y855989D01*
G01X-18174Y856010D02*
X-14677Y855972D01*
G01X-14147Y863551D02*
X-14537Y863344D01*
G01X-14147Y860402D02*
X-14537Y860194D01*
G01X-14147Y857252D02*
X-14537Y857044D01*
G01X-14147Y854102D02*
X-14537Y853895D01*
G01X-14147Y850953D02*
X-14537Y850745D01*
G01X-19469Y850605D02*
X-18174Y850619D01*
G01X-18435D02*
X-20801Y850593D01*
G01X-18174Y850619D02*
X-17126Y850631D01*
G01X-19469Y853755D02*
X-18174Y853769D01*
G01X-18435D02*
X-20801Y853743D01*
G01X-18174Y853769D02*
X-17126Y853780D01*
G01X-19469Y856904D02*
X-18174Y856919D01*
G01X-18435D02*
X-20801Y856893D01*
G01X-18174Y856919D02*
X-17126Y856930D01*
G01X-19469Y860054D02*
X-18174Y860068D01*
G01X-18435D02*
X-20801Y860042D01*
G01X-18174Y860068D02*
X-17126Y860080D01*
G01X-19469Y863204D02*
X-18174Y863218D01*
G01X-18435D02*
X-20801Y863192D01*
G01X-18174Y863218D02*
X-17126Y863229D01*
G01X-15985Y850641D02*
X-14449Y850657D01*
G01X-14677D02*
X-18174Y850619D01*
G01X-14677Y850657D02*
X-16213Y850641D01*
G01X-15985Y853791D02*
X-14449Y853807D01*
G01X-14677D02*
X-18174Y853769D01*
G01X-14677Y853807D02*
X-16213Y853791D01*
G01X-15985Y856940D02*
X-14449Y856957D01*
G01X-14677D02*
X-18174Y856919D01*
G01X-14677Y856957D02*
X-16213Y856940D01*
G01X-15985Y860090D02*
X-14449Y860106D01*
G01X-14677D02*
X-18174Y860068D01*
G01X-14677Y860106D02*
X-16213Y860090D01*
G01X-15985Y863239D02*
X-14449Y863256D01*
G01X-14677D02*
X-18174Y863218D01*
G01X-14677Y863256D02*
X-16213Y863239D01*
G01X-19469Y850605D02*
X-20801Y850593D01*
G01X-19469Y853755D02*
X-20801Y853743D01*
G01X-19469Y856904D02*
X-20801Y856893D01*
G01X-19469Y860054D02*
X-20801Y860042D01*
G01X-19469Y863204D02*
X-20801Y863192D01*
G01X-15985Y850641D02*
X-17126Y850631D01*
G01D02*
X-18435Y850619D01*
G01X-15985Y853791D02*
X-17126Y853780D01*
G01D02*
X-18435Y853769D01*
G01X-15985Y856940D02*
X-17126Y856930D01*
G01D02*
X-18435Y856919D01*
G01X-15985Y860090D02*
X-17126Y860080D01*
G01D02*
X-18435Y860068D01*
G01X-15985Y863239D02*
X-17126Y863229D01*
G01D02*
X-18435Y863218D01*
G01X-18174Y853769D02*
X-18435D01*
G01X-15985Y853791D02*
X-16213D01*
G01X-14449Y853807D02*
X-14677D01*
G01X12410Y853906D02*
X315D01*
G01X-13009Y854102D02*
X-14147D01*
G01X512Y854496D02*
X0D01*
G01X512Y855283D02*
X0D01*
G01X-13009Y855677D02*
X-14147D01*
G01X12410Y855874D02*
X315D01*
G01X-14449Y855972D02*
X-14677D01*
G01X-15985Y855989D02*
X-16213D01*
G01X-18174Y856010D02*
X-18435D01*
G01X-18174Y856919D02*
X-18435D01*
G01X-16213Y856940D02*
X-15985D01*
G01X-14449Y856957D02*
X-14677D01*
G01X12410Y857055D02*
X315D01*
G01X-13009Y857252D02*
X-14147D01*
G01X512Y857646D02*
X0D01*
G01X512Y858433D02*
X0D01*
G01X-13009Y858827D02*
X-14147D01*
G01X12410Y859024D02*
X315D01*
G01X-14449Y859122D02*
X-14677D01*
G01X-15985Y859138D02*
X-16213D01*
G01X-18174Y859160D02*
X-18435D01*
G01X-18174Y860068D02*
X-18435D01*
G01X-15985Y860090D02*
X-16213D01*
G01X-14449Y860106D02*
X-14677D01*
G01X12410Y860205D02*
X315D01*
G01X-13009Y860402D02*
X-14147D01*
G01X512Y860795D02*
X0D01*
G01X512Y861583D02*
X0D01*
G01X-13009Y861976D02*
X-14147D01*
G01X12410Y862173D02*
X315D01*
G01X-14449Y862272D02*
X-14677D01*
G01X-15985Y862288D02*
X-16213D01*
G01X-18174Y862309D02*
X-18435D01*
G01X-18174Y863218D02*
X-18435D01*
G01X-15985Y863239D02*
X-16213D01*
G01X-14449Y863256D02*
X-14677D01*
G01X12410Y863354D02*
X315D01*
G01X-13009Y863551D02*
X-14147D01*
G01X512Y863945D02*
X0D01*
G01X512Y864732D02*
X0D01*
G01X-13009Y865126D02*
X-14147D01*
G01X-19469Y859174D02*
X-20801Y859186D01*
G01X-15985Y859138D02*
X-18435Y859160D01*
G01X-19469Y862324D02*
X-20801Y862336D01*
G01X-15985Y862288D02*
X-18435Y862309D01*
G01X-15985Y859138D02*
X-14449Y859122D01*
G01X-15985Y862288D02*
X-14449Y862272D01*
G01X-18435Y859160D02*
X-20801Y859186D01*
G01X-18435Y862309D02*
X-20801Y862336D01*
G01X-19469Y859174D02*
X-16213Y859138D01*
G01X-18174Y859160D02*
X-14677Y859122D01*
G01X-19469Y862324D02*
X-16213Y862288D01*
G01X-18174Y862309D02*
X-14677Y862272D01*
G01X-23622Y917029D02*
Y916209D01*
G01Y892094D02*
Y891274D01*
G01X-21109Y912928D02*
Y911615D01*
G01Y906694D02*
Y906038D01*
G01Y904561D02*
Y903741D01*
G01Y894227D02*
Y893571D01*
G01Y887993D02*
Y887009D01*
G01X-20801Y919885D02*
Y919029D01*
G01Y916735D02*
Y915879D01*
G01Y910436D02*
Y909580D01*
G01Y913585D02*
Y912730D01*
G01Y907286D02*
Y906430D01*
G01Y900987D02*
Y900131D01*
G01Y904137D02*
Y903281D01*
G01Y897837D02*
Y896981D01*
G01Y891538D02*
Y890682D01*
G01Y894688D02*
Y893832D01*
G01Y888389D02*
Y887533D01*
G01X-20439Y912600D02*
Y911943D01*
G01X-20272Y887993D02*
Y887009D01*
G01X-19469Y919891D02*
Y919023D01*
G01Y916741D02*
Y915873D01*
G01Y910442D02*
Y909574D01*
G01Y913591D02*
Y912724D01*
G01Y907292D02*
Y906424D01*
G01Y900993D02*
Y900125D01*
G01Y904143D02*
Y903275D01*
G01Y897843D02*
Y896976D01*
G01Y891544D02*
Y890676D01*
G01Y894694D02*
Y893826D01*
G01Y888394D02*
Y887527D01*
G01X-19099Y901609D02*
Y898164D01*
G01X-18435Y919911D02*
Y919002D01*
G01Y916761D02*
Y915853D01*
G01Y910462D02*
Y909554D01*
G01Y913611D02*
Y912703D01*
G01Y907312D02*
Y906404D01*
G01Y901013D02*
Y900105D01*
G01Y904163D02*
Y903254D01*
G01Y897863D02*
Y896955D01*
G01Y891564D02*
Y890656D01*
G01Y894714D02*
Y893806D01*
G01Y888415D02*
Y887506D01*
G01X-18429Y902429D02*
Y898000D01*
G01X-18174Y919911D02*
Y919002D01*
G01Y916761D02*
Y915853D01*
G01Y910462D02*
Y909554D01*
G01Y913611D02*
Y912703D01*
G01Y907312D02*
Y906404D01*
G01Y901013D02*
Y900105D01*
G01Y904163D02*
Y903254D01*
G01Y897863D02*
Y896955D01*
G01Y891564D02*
Y890656D01*
G01Y894714D02*
Y893806D01*
G01Y888415D02*
Y887506D01*
G01X-17424Y902429D02*
Y901609D01*
G01X-16586Y887665D02*
Y887009D01*
G01X-16418Y912600D02*
Y911943D01*
G01X-16213Y919932D02*
Y918981D01*
G01Y916783D02*
Y915831D01*
G01Y910483D02*
Y909532D01*
G01Y913633D02*
Y912681D01*
G01Y907334D02*
Y906382D01*
G01Y901035D02*
Y900083D01*
G01Y904184D02*
Y903233D01*
G01Y897885D02*
Y896933D01*
G01Y891586D02*
Y890634D01*
G01Y894735D02*
Y893784D01*
G01Y888436D02*
Y887485D01*
G01X-15985Y919932D02*
Y918981D01*
G01Y916783D02*
Y915831D01*
G01Y910483D02*
Y909532D01*
G01Y913633D02*
Y912681D01*
G01Y907334D02*
Y906382D01*
G01Y901035D02*
Y900083D01*
G01Y904184D02*
Y903233D01*
G01Y897885D02*
Y896933D01*
G01Y891586D02*
Y890634D01*
G01Y894735D02*
Y893784D01*
G01Y888436D02*
Y887485D01*
G01X-15748Y917029D02*
Y916209D01*
G01Y912928D02*
Y911615D01*
G01Y904561D02*
Y903741D01*
G01Y908335D02*
Y907514D01*
G01Y895867D02*
Y895047D01*
G01Y892094D02*
Y891274D01*
G01Y887993D02*
Y887009D01*
G01X-20942Y898984D02*
X-20774Y898492D01*
G01X-21109Y887009D02*
X-20942Y886353D01*
G01X-20272Y887009D02*
X-20104Y886353D01*
G01X-21109Y893571D02*
X-20942Y892915D01*
G01X-20439Y893571D02*
X-20272Y892915D01*
G01X-20439Y899804D02*
X-20272Y899148D01*
G01X-16754Y888321D02*
X-16586Y887665D01*
G01X-21109Y906038D02*
X-20942Y905382D01*
G01X-20439Y906038D02*
X-20272Y905382D01*
G01X-15916Y888650D02*
X-15748Y887993D01*
G01X-21109Y911615D02*
X-20942Y910959D01*
G01X-20439Y911943D02*
X-20272Y911287D01*
G01X-16586Y913256D02*
X-16418Y912600D01*
G01X-15916Y913584D02*
X-15748Y912928D01*
G01X-21109Y899969D02*
X-20942Y898984D01*
G01X-16586Y900953D02*
X-16418Y899804D01*
G01X-15916Y901117D02*
X-15748Y899969D01*
G01X-14537Y920037D02*
Y918877D01*
G01Y916887D02*
Y915727D01*
G01Y910588D02*
Y909428D01*
G01Y913737D02*
Y912578D01*
G01Y907438D02*
Y906278D01*
G01Y901139D02*
Y899979D01*
G01Y904289D02*
Y903129D01*
G01Y897989D02*
Y896830D01*
G01Y891690D02*
Y890530D01*
G01Y894840D02*
Y893680D01*
G01Y888541D02*
Y887381D01*
G01X-13009Y920244D02*
Y918669D01*
G01Y913945D02*
Y912370D01*
G01Y917094D02*
Y915520D01*
G01Y910795D02*
Y909220D01*
G01Y904496D02*
Y902921D01*
G01Y907646D02*
Y906071D01*
G01Y901346D02*
Y899772D01*
G01Y898197D02*
Y896622D01*
G01Y891898D02*
Y890323D01*
G01Y895047D02*
Y893472D01*
G01Y888748D02*
Y887173D01*
G01X315Y920638D02*
Y920047D01*
G01Y918866D02*
Y918276D01*
G01Y914339D02*
Y913748D01*
G01Y917488D02*
Y916898D01*
G01Y915717D02*
Y915126D01*
G01Y911189D02*
Y910598D01*
G01Y909417D02*
Y908827D01*
G01Y912567D02*
Y911976D01*
G01Y904890D02*
Y904299D01*
G01Y908039D02*
Y907449D01*
G01Y906268D02*
Y905677D01*
G01Y901740D02*
Y901150D01*
G01Y899969D02*
Y899378D01*
G01Y903118D02*
Y902528D01*
G01Y895441D02*
Y894850D01*
G01Y898591D02*
Y898000D01*
G01Y896819D02*
Y896228D01*
G01Y892291D02*
Y891701D01*
G01Y890520D02*
Y889929D01*
G01Y893669D02*
Y893079D01*
G01Y885992D02*
Y885402D01*
G01Y889142D02*
Y888551D01*
G01Y887370D02*
Y886780D01*
G01X512Y920638D02*
Y920047D01*
G01Y918866D02*
Y918276D01*
G01Y914339D02*
Y913748D01*
G01Y917488D02*
Y916898D01*
G01Y915717D02*
Y915126D01*
G01Y911189D02*
Y910598D01*
G01Y909417D02*
Y908827D01*
G01Y912567D02*
Y911976D01*
G01Y904890D02*
Y904299D01*
G01Y908039D02*
Y907449D01*
G01Y906268D02*
Y905677D01*
G01Y901740D02*
Y901150D01*
G01Y899969D02*
Y899378D01*
G01Y903118D02*
Y902528D01*
G01Y895441D02*
Y894850D01*
G01Y898591D02*
Y898000D01*
G01Y896819D02*
Y896228D01*
G01Y892291D02*
Y891701D01*
G01Y890520D02*
Y889929D01*
G01Y893669D02*
Y893079D01*
G01Y885992D02*
Y885402D01*
G01Y889142D02*
Y888551D01*
G01Y887370D02*
Y886780D01*
G01X709Y920047D02*
Y918866D01*
G01Y916898D02*
Y915717D01*
G01Y910598D02*
Y909417D01*
G01Y913748D02*
Y912567D01*
G01Y907449D02*
Y906268D01*
G01Y901150D02*
Y899969D01*
G01Y904299D02*
Y903118D01*
G01Y898000D02*
Y896819D01*
G01Y891701D02*
Y890520D01*
G01Y894850D02*
Y893669D01*
G01Y888551D02*
Y887370D01*
G01X1074Y920047D02*
Y918866D01*
G01Y916898D02*
Y915717D01*
G01Y910598D02*
Y909417D01*
G01Y913748D02*
Y912567D01*
G01Y907449D02*
Y906268D01*
G01Y901150D02*
Y899969D01*
G01Y904299D02*
Y903118D01*
G01Y898000D02*
Y896819D01*
G01Y891701D02*
Y890520D01*
G01Y894850D02*
Y893669D01*
G01Y888551D02*
Y887370D01*
G01X1184Y920047D02*
Y918866D01*
G01Y916898D02*
Y915717D01*
G01Y910598D02*
Y909417D01*
G01Y913748D02*
Y912567D01*
G01Y907449D02*
Y906268D01*
G01Y901150D02*
Y899969D01*
G01Y904299D02*
Y903118D01*
G01Y898000D02*
Y896819D01*
G01Y891701D02*
Y890520D01*
G01Y894850D02*
Y893669D01*
G01Y888551D02*
Y887370D01*
G01X9965Y920047D02*
Y918866D01*
G01Y916898D02*
Y915717D01*
G01Y910598D02*
Y909417D01*
G01Y913748D02*
Y912567D01*
G01Y907449D02*
Y906268D01*
G01Y901150D02*
Y899969D01*
G01Y904299D02*
Y903118D01*
G01Y898000D02*
Y896819D01*
G01Y891701D02*
Y890520D01*
G01Y894850D02*
Y893669D01*
G01Y888551D02*
Y887370D01*
G01X10075Y920047D02*
Y918866D01*
G01Y916898D02*
Y915717D01*
G01Y910598D02*
Y909417D01*
G01Y913748D02*
Y912567D01*
G01Y907449D02*
Y906268D01*
G01Y901150D02*
Y899969D01*
G01Y904299D02*
Y903118D01*
G01Y898000D02*
Y896819D01*
G01Y891701D02*
Y890520D01*
G01Y894850D02*
Y893669D01*
G01Y888551D02*
Y887370D01*
G01X-20942Y900953D02*
X-21109Y899969D01*
G01X-20272Y900789D02*
X-20439Y899804D01*
G01X-15748Y899969D02*
X-15916Y898984D01*
G01X-20942Y913584D02*
X-21109Y912928D01*
G01X-20272Y913256D02*
X-20439Y912600D01*
G01X-20272Y906694D02*
X-20439Y906038D01*
G01X-16418Y911943D02*
X-16586Y911287D01*
G01X-20272Y894227D02*
X-20439Y893571D01*
G01X-15748Y911615D02*
X-15916Y910959D01*
G01X-20942Y888650D02*
X-21109Y887993D01*
G01X-16418Y899804D02*
X-16586Y899148D01*
G01Y887009D02*
X-16754Y886353D01*
G01X-15748Y887009D02*
X-15916Y886353D01*
G01X-20942Y907186D02*
X-21109Y906694D01*
G01X-20942Y894719D02*
X-21109Y894227D01*
G01X-15916Y898984D02*
X-16083Y898492D01*
G01X-20774Y886025D02*
X-20439Y885697D01*
G01X-20104Y886353D02*
X-19769Y885861D01*
G01X-20942Y892915D02*
X-20607Y892422D01*
G01X-20272Y892915D02*
X-19937Y892422D01*
G01X-17089Y888813D02*
X-16754Y888321D01*
G01X-16251Y889142D02*
X-15916Y888650D01*
G01X-20774Y898492D02*
X-20439Y898000D01*
G01X-20942Y905382D02*
X-20607Y904890D01*
G01X-20272Y905382D02*
X-19937Y904890D01*
G01X-16921Y901445D02*
X-16586Y900953D01*
G01X-20942Y886353D02*
X-20774Y886025D01*
G01X-20272Y899148D02*
X-20104Y898820D01*
G01X-20942Y910959D02*
X-20774Y910631D01*
G01X-16251Y901773D02*
X-15916Y901117D01*
G01X-16083Y913912D02*
X-15916Y913584D01*
G01X-20774Y913912D02*
X-20942Y913584D01*
G01X-20104Y907022D02*
X-20272Y906694D01*
G01X-15916Y910959D02*
X-16083Y910631D01*
G01X-20104Y894555D02*
X-20272Y894227D01*
G01X-16586Y899148D02*
X-16754Y898820D01*
G01X-19937Y888650D02*
X-20272Y887993D01*
G01X-15916Y886353D02*
X-16083Y886025D01*
G01X-20439Y901773D02*
X-20942Y900953D01*
G01X-20607Y907678D02*
X-20942Y907186D01*
G01X-19937Y901281D02*
X-20272Y900789D01*
G01X-20607Y895211D02*
X-20942Y894719D01*
G01X-16083Y898492D02*
X-16418Y898000D01*
G01X-20607Y889142D02*
X-20942Y888650D01*
G01X-16754Y886353D02*
X-17089Y885861D01*
G01X-19769D02*
X-19267Y885533D01*
G01X-17089Y889798D02*
X-16251Y889142D01*
G01X-20607Y892422D02*
X-20272Y892094D01*
G01X-19937Y892422D02*
X-19602Y892094D01*
G01X-20439Y898000D02*
X-20104Y897672D01*
G01Y898820D02*
X-19602Y898328D01*
G01X-20607Y904890D02*
X-20272Y904561D01*
G01X-19937Y904890D02*
X-19602Y904561D01*
G01X-16754Y902265D02*
X-16251Y901773D01*
G01X-20774Y910631D02*
X-20439Y910303D01*
G01X-20272Y911287D02*
X-19937Y910959D01*
G01X-16921Y913584D02*
X-16586Y913256D01*
G01X-16418Y914240D02*
X-16083Y913912D01*
G01X-20439Y914240D02*
X-20774Y913912D01*
G01X-19937Y913584D02*
X-20272Y913256D01*
G01Y908006D02*
X-20607Y907678D01*
G01X-16586Y911287D02*
X-16921Y910959D01*
G01X-19769Y907350D02*
X-20104Y907022D01*
G01X-16083Y910631D02*
X-16418Y910303D01*
G01X-20272Y895539D02*
X-20607Y895211D01*
G01X-16754Y898820D02*
X-17256Y898328D01*
G01X-19769Y894883D02*
X-20104Y894555D01*
G01X-16418Y898000D02*
X-16754Y897672D01*
G01X-20439Y885697D02*
X-20104Y885533D01*
G01X-17424Y888978D02*
X-17089Y888813D01*
G01X-20104Y897672D02*
X-19434Y897344D01*
G01X-19602Y898328D02*
X-19267Y898164D01*
G01X-14537Y887381D02*
X-14147Y887173D01*
G01X-14537Y890530D02*
X-14147Y890323D01*
G01X-14537Y893680D02*
X-14147Y893472D01*
G01X-14537Y896830D02*
X-14147Y896622D01*
G01X-14537Y899979D02*
X-14147Y899772D01*
G01X-14537Y903129D02*
X-14147Y902921D01*
G01X-14537Y906278D02*
X-14147Y906071D01*
G01X-14537Y909428D02*
X-14147Y909220D01*
G01X-14537Y912578D02*
X-14147Y912370D01*
G01X-14537Y915727D02*
X-14147Y915520D01*
G01X-14537Y918877D02*
X-14147Y918669D01*
G01X-14677Y887469D02*
X-14537Y887381D01*
G01X-14449Y887469D02*
X-13977Y887173D01*
G01X-14677Y890618D02*
X-14537Y890530D01*
G01X-14449Y890618D02*
X-13977Y890323D01*
G01X-14677Y893768D02*
X-14537Y893680D01*
G01X-14449Y893768D02*
X-13977Y893472D01*
G01X-14677Y896917D02*
X-14537Y896830D01*
G01X-14449Y896917D02*
X-13977Y896622D01*
G01X-14677Y900067D02*
X-14537Y899979D01*
G01X-14449Y900067D02*
X-13977Y899772D01*
G01X-14677Y903217D02*
X-14537Y903129D01*
G01X-14449Y903217D02*
X-13977Y902921D01*
G01X-14677Y906366D02*
X-14537Y906278D01*
G01X-14449Y906366D02*
X-13977Y906071D01*
G01X-14677Y909516D02*
X-14537Y909428D01*
G01X-14449Y909516D02*
X-13977Y909220D01*
G01X-14677Y912665D02*
X-14537Y912578D01*
G01X-14449Y912665D02*
X-13977Y912370D01*
G01X-14677Y915815D02*
X-14537Y915727D01*
G01X-14449Y915815D02*
X-13977Y915520D01*
G01X-14677Y918965D02*
X-14537Y918877D01*
G01X-14449Y918965D02*
X-13977Y918669D01*
G01X-20439Y910303D02*
X-19937Y909975D01*
G01Y910959D02*
X-19434Y910631D01*
G01X-17424Y913912D02*
X-16921Y913584D01*
G01Y914568D02*
X-16418Y914240D01*
G01X-20104Y889634D02*
X-20607Y889142D01*
G01X-16083Y886025D02*
X-16418Y885697D01*
G01X-19769Y902265D02*
X-20439Y901773D01*
G01X-19937Y914568D02*
X-20439Y914240D01*
G01X-19434Y913912D02*
X-19937Y913584D01*
G01X-17089Y889798D02*
X-17759Y889962D01*
G01X-16921Y914568D02*
X-18094Y914896D01*
G01X-17424Y888978D02*
X-17926Y889142D01*
G01X-16921Y901445D02*
X-17424Y901609D01*
G01X-19434Y909811D02*
X-19937Y909975D01*
G01X-16921Y910959D02*
X-17424Y910631D01*
G01X-16418Y910303D02*
X-16921Y909975D01*
G01X-19434Y901609D02*
X-19937Y901281D01*
G01X-19434Y888978D02*
X-19937Y888650D01*
G01X-17089Y885861D02*
X-17591Y885533D01*
G01X-14537Y920037D02*
X-14677Y919949D01*
G01X-13977Y920244D02*
X-14449Y919949D01*
G01X-14537Y916887D02*
X-14677Y916799D01*
G01X-13977Y917094D02*
X-14449Y916799D01*
G01X-14537Y913737D02*
X-14677Y913650D01*
G01X-13977Y913945D02*
X-14449Y913650D01*
G01X-14537Y910588D02*
X-14677Y910500D01*
G01X-13977Y910795D02*
X-14449Y910500D01*
G01X-14537Y907438D02*
X-14677Y907350D01*
G01X-13977Y907646D02*
X-14449Y907350D01*
G01X-14537Y904289D02*
X-14677Y904201D01*
G01X-13977Y904496D02*
X-14449Y904201D01*
G01X-14537Y901139D02*
X-14677Y901051D01*
G01X-13977Y901346D02*
X-14449Y901051D01*
G01X-14537Y897989D02*
X-14677Y897902D01*
G01X-13977Y898197D02*
X-14449Y897902D01*
G01X-14537Y894840D02*
X-14677Y894752D01*
G01X-13977Y895047D02*
X-14449Y894752D01*
G01X-14537Y891690D02*
X-14677Y891602D01*
G01X-13977Y891898D02*
X-14449Y891602D01*
G01X-14537Y888541D02*
X-14677Y888453D01*
G01X-13977Y888748D02*
X-14449Y888453D01*
G01X-14537Y885391D02*
X-14677Y885303D01*
G01X-13977Y885598D02*
X-14449Y885303D01*
G01X-14147Y920244D02*
X-14537Y920037D01*
G01X-14147Y917094D02*
X-14537Y916887D01*
G01X-14147Y913945D02*
X-14537Y913737D01*
G01X-14147Y910795D02*
X-14537Y910588D01*
G01X-14147Y907646D02*
X-14537Y907438D01*
G01X-14147Y904496D02*
X-14537Y904289D01*
G01X-14147Y901346D02*
X-14537Y901139D01*
G01X-14147Y898197D02*
X-14537Y897989D01*
G01X-14147Y895047D02*
X-14537Y894840D01*
G01X-14147Y891898D02*
X-14537Y891690D01*
G01X-14147Y888748D02*
X-14537Y888541D01*
G01X-14147Y885598D02*
X-14537Y885391D01*
G01X-17256Y898328D02*
X-17591Y898164D01*
G01X-16754Y897672D02*
X-17424Y897344D01*
G01X-19937Y895703D02*
X-20272Y895539D01*
G01X-18429Y897180D02*
X-19434Y897344D01*
G01X-16754Y902265D02*
X-17424Y902429D01*
G01X-18764Y909647D02*
X-19434Y909811D01*
G01X-18764Y910467D02*
X-19434Y910631D01*
G01X-17424Y913912D02*
X-18094Y914076D01*
G01X-19769Y889798D02*
X-20104Y889634D01*
G01X-16418Y885697D02*
X-16754Y885533D01*
G01X-19434Y914732D02*
X-19937Y914568D01*
G01X-19769Y908170D02*
X-20272Y908006D01*
G01X-17591Y898164D02*
X-18094Y898000D01*
G01X-19469Y888400D02*
X-18174Y888415D01*
G01X-18435D02*
X-20801Y888389D01*
G01X-18174Y888415D02*
X-17126Y888426D01*
G01X-19469Y891550D02*
X-18174Y891564D01*
G01X-18435D02*
X-20801Y891538D01*
G01X-18174Y891564D02*
X-17126Y891576D01*
G01X-19469Y894700D02*
X-18174Y894714D01*
G01X-18435D02*
X-20801Y894688D01*
G01X-18174Y894714D02*
X-17126Y894725D01*
G01X-19469Y897849D02*
X-18174Y897863D01*
G01X-18435D02*
X-20801Y897837D01*
G01X-18174Y897863D02*
X-17126Y897875D01*
G01X-19469Y900999D02*
X-18174Y901013D01*
G01X-18435D02*
X-20801Y900987D01*
G01X-18174Y901013D02*
X-17126Y901024D01*
G01X-19469Y904148D02*
X-18174Y904163D01*
G01X-18435D02*
X-20801Y904137D01*
G01X-18174Y904163D02*
X-17126Y904174D01*
G01X-19469Y907298D02*
X-18174Y907312D01*
G01X-18435D02*
X-20801Y907286D01*
G01X-18174Y907312D02*
X-17126Y907324D01*
G01X-19469Y910448D02*
X-18174Y910462D01*
G01X-18435D02*
X-20801Y910436D01*
G01X-18174Y910462D02*
X-17126Y910473D01*
G01X-19469Y913597D02*
X-18174Y913611D01*
G01X-18435D02*
X-20801Y913585D01*
G01X-18174Y913611D02*
X-17126Y913623D01*
G01X-19469Y916747D02*
X-18174Y916761D01*
G01X-18435D02*
X-20801Y916735D01*
G01X-18174Y916761D02*
X-17126Y916772D01*
G01X-19469Y919896D02*
X-18174Y919911D01*
G01X-18435D02*
X-20801Y919885D01*
G01X-18174Y919911D02*
X-17126Y919922D01*
G01X-15985Y885287D02*
X-14449Y885303D01*
G01X-14677D02*
X-16213Y885287D01*
G01X-15985Y888436D02*
X-14449Y888453D01*
G01X-14677D02*
X-18174Y888415D01*
G01X-14677Y888453D02*
X-16213Y888436D01*
G01X-15985Y891586D02*
X-14449Y891602D01*
G01X-14677D02*
X-18174Y891564D01*
G01X-14677Y891602D02*
X-16213Y891586D01*
G01X-15985Y894735D02*
X-14449Y894752D01*
G01X-14677D02*
X-18174Y894714D01*
G01X-14677Y894752D02*
X-16213Y894735D01*
G01X-15985Y897885D02*
X-14449Y897902D01*
G01X-14677D02*
X-18174Y897863D01*
G01X-14677Y897902D02*
X-16213Y897885D01*
G01X-15985Y901035D02*
X-14449Y901051D01*
G01X-14677D02*
X-18174Y901013D01*
G01X-14677Y901051D02*
X-16213Y901035D01*
G01X-15985Y904184D02*
X-14449Y904201D01*
G01X-14677D02*
X-18174Y904163D01*
G01X-14677Y904201D02*
X-16213Y904184D01*
G01X-15985Y907334D02*
X-14449Y907350D01*
G01X-14677D02*
X-18174Y907312D01*
G01X-14677Y907350D02*
X-16213Y907334D01*
G01X-15985Y910483D02*
X-14449Y910500D01*
G01X-14677D02*
X-18174Y910462D01*
G01X-14677Y910500D02*
X-16213Y910483D01*
G01X-15985Y913633D02*
X-14449Y913650D01*
G01X-14677D02*
X-18174Y913611D01*
G01X-14677Y913650D02*
X-16213Y913633D01*
G01X-15985Y916783D02*
X-14449Y916799D01*
G01X-14677D02*
X-18174Y916761D01*
G01X-14677Y916799D02*
X-16213Y916783D01*
G01X-15985Y919932D02*
X-14449Y919949D01*
G01X-14677D02*
X-18174Y919911D01*
G01X-14677Y919949D02*
X-16213Y919932D01*
G01X-19469Y888400D02*
X-20801Y888389D01*
G01X-19469Y891550D02*
X-20801Y891538D01*
G01X-19469Y894700D02*
X-20801Y894688D01*
G01X-19469Y897849D02*
X-20801Y897837D01*
G01X-19469Y900999D02*
X-20801Y900987D01*
G01X-19469Y904148D02*
X-20801Y904137D01*
G01X-19469Y907298D02*
X-20801Y907286D01*
G01X-19469Y910448D02*
X-20801Y910436D01*
G01X-19469Y913597D02*
X-20801Y913585D01*
G01X-19469Y916747D02*
X-20801Y916735D01*
G01X-19469Y919896D02*
X-20801Y919885D01*
G01X-15985Y885287D02*
X-17126Y885276D01*
G01X-15985Y888436D02*
X-17126Y888426D01*
G01D02*
X-18435Y888415D01*
G01X-15985Y891586D02*
X-17126Y891576D01*
G01D02*
X-18435Y891564D01*
G01X-15985Y894735D02*
X-17126Y894725D01*
G01D02*
X-18435Y894714D01*
G01X-15985Y897885D02*
X-17126Y897875D01*
G01D02*
X-18435Y897863D01*
G01X-15985Y901035D02*
X-17126Y901024D01*
G01D02*
X-18435Y901013D01*
G01X-15985Y904184D02*
X-17126Y904174D01*
G01D02*
X-18435Y904163D01*
G01X-15985Y907334D02*
X-17126Y907324D01*
G01D02*
X-18435Y907312D01*
G01X-15985Y910483D02*
X-17126Y910473D01*
G01D02*
X-18435Y910462D01*
G01X-15985Y913633D02*
X-17126Y913623D01*
G01D02*
X-18435Y913611D01*
G01X-15985Y916783D02*
X-17126Y916772D01*
G01X-18435Y916761D02*
X-17126Y916772D01*
G01X-15985Y919932D02*
X-17126Y919922D01*
G01D02*
X-18435Y919911D01*
G01X-15985Y885287D02*
X-16213D01*
G01X-14449Y885303D02*
X-14677D01*
G01X12410Y885402D02*
X315D01*
G01X-13068Y885533D02*
X-16754D01*
G01X-17591D02*
X-19267D01*
G01X-20104D02*
X-21109D01*
G01X-13009Y885598D02*
X-14147D01*
G01X512Y885992D02*
X0D01*
G01X512Y886780D02*
X0D01*
G01X-13009Y887173D02*
X-14147D01*
G01X12410Y887370D02*
X315D01*
G01X-14449Y887469D02*
X-14677D01*
G01X-15985Y887485D02*
X-16213D01*
G01X-18174Y887506D02*
X-18435D01*
G01X-18174Y888415D02*
X-18435D01*
G01X-15985Y888436D02*
X-16213D01*
G01X-14449Y888453D02*
X-14677D01*
G01X12410Y888551D02*
X315D01*
G01X-13009Y888748D02*
X-14147D01*
G01X512Y889142D02*
X0D01*
G01X-17926D02*
X-18931D01*
G01X512Y889929D02*
X0D01*
G01X-17759Y889962D02*
X-19099D01*
G01X-13009Y890323D02*
X-14147D01*
G01X12410Y890520D02*
X315D01*
G01X-14449Y890618D02*
X-14677D01*
G01X-15985Y890634D02*
X-16213D01*
G01X-18174Y890656D02*
X-18435D01*
G01X-15748Y891274D02*
X-23622D01*
G01X-18174Y891564D02*
X-18435D01*
G01X-15985Y891586D02*
X-16213D01*
G01X-14449Y891602D02*
X-14677D01*
G01X12410Y891701D02*
X315D01*
G01X-13009Y891898D02*
X-14147D01*
G01X-15748Y892094D02*
X-19602D01*
G01X-20272D02*
X-23622D01*
G01X512Y892291D02*
X0D01*
G01X512Y893079D02*
X0D01*
G01X-13009Y893472D02*
X-14147D01*
G01X12410Y893669D02*
X315D01*
G01X-14449Y893768D02*
X-14677D01*
G01X-15985Y893784D02*
X-16213D01*
G01X-18174Y893806D02*
X-18435D01*
G01X-18174Y894714D02*
X-18435D01*
G01X-15985Y894735D02*
X-16213D01*
G01X-14449Y894752D02*
X-14677D01*
G01X12410Y894850D02*
X315D01*
G01X-13009Y895047D02*
X-14147D01*
G01X-15748D02*
X-19099D01*
G01X512Y895441D02*
X0D01*
G01X-15748Y895867D02*
X-19099D01*
G01X512Y896228D02*
X0D01*
G01X-13009Y896622D02*
X-14147D01*
G01X12410Y896819D02*
X315D01*
G01X-14449Y896917D02*
X-14677D01*
G01X-15985Y896933D02*
X-16213D01*
G01X-18174Y896955D02*
X-18435D01*
G01X-18174Y897863D02*
X-18435D01*
G01X-15985Y897885D02*
X-16213D01*
G01X-14449Y897902D02*
X-14677D01*
G01X12410Y898000D02*
X315D01*
G01X-18094D02*
X-18429D01*
G01X-19099Y898164D02*
X-19267D01*
G01X-13009Y898197D02*
X-14147D01*
G01X512Y898591D02*
X0D01*
G01X512Y899378D02*
X0D01*
G01X-13009Y899772D02*
X-14147D01*
G01X12410Y899969D02*
X315D01*
G01X-14449Y900067D02*
X-14677D01*
G01X-15985Y900083D02*
X-16213D01*
G01X-18174Y900105D02*
X-18435D01*
G01X-18174Y901013D02*
X-18435D01*
G01X-15985Y901035D02*
X-16213D01*
G01X-14449Y901051D02*
X-14677D01*
G01X12410Y901150D02*
X315D01*
G01X-13009Y901346D02*
X-14147D01*
G01X-19099Y901609D02*
X-19434D01*
G01X512Y901740D02*
X0D01*
G01X-18429Y902429D02*
X-19099D01*
G01X512Y902528D02*
X0D01*
G01X-13009Y902921D02*
X-14147D01*
G01X12410Y903118D02*
X315D01*
G01X-14449Y903217D02*
X-14677D01*
G01X-15985Y903233D02*
X-16213D01*
G01X-18174Y903254D02*
X-18435D01*
G01X-15748Y903741D02*
X-21109D01*
G01X-18174Y904163D02*
X-18435D01*
G01X-15985Y904184D02*
X-16213D01*
G01X-14449Y904201D02*
X-14677D01*
G01X12410Y904299D02*
X315D01*
G01X-13009Y904496D02*
X-14147D01*
G01X-15748Y904561D02*
X-19602D01*
G01X-20272D02*
X-21109D01*
G01X512Y904890D02*
X0D01*
G01X512Y905677D02*
X0D01*
G01X-13009Y906071D02*
X-14147D01*
G01X12410Y906268D02*
X315D01*
G01X-14449Y906366D02*
X-14677D01*
G01X-15985Y906382D02*
X-16213D01*
G01X-18174Y906404D02*
X-18435D01*
G01X-18174Y907312D02*
X-18435D01*
G01X-15985Y907334D02*
X-16213D01*
G01X-14449Y907350D02*
X-14677D01*
G01X12410Y907449D02*
X315D01*
G01X-15748Y907514D02*
X-18931D01*
G01X-13009Y907646D02*
X-14147D01*
G01X512Y908039D02*
X0D01*
G01X-15748Y908335D02*
X-18931D01*
G01X512Y908827D02*
X0D01*
G01X-13009Y909220D02*
X-14147D01*
G01X12410Y909417D02*
X315D01*
G01X-14449Y909516D02*
X-14677D01*
G01X-15985Y909532D02*
X-16213D01*
G01X-18174Y909554D02*
X-18435D01*
G01X-18094Y909647D02*
X-18764D01*
G01X-18174Y910462D02*
X-18435D01*
G01X-18094Y910467D02*
X-18764D01*
G01X-15985Y910483D02*
X-16213D01*
G01X-14449Y910500D02*
X-14677D01*
G01X12410Y910598D02*
X315D01*
G01X-13009Y910795D02*
X-14147D01*
G01X512Y911189D02*
X0D01*
G01X512Y911976D02*
X0D01*
G01X-13009Y912370D02*
X-14147D01*
G01X12410Y912567D02*
X315D01*
G01X-14449Y912665D02*
X-14677D01*
G01X-15985Y912681D02*
X-16213D01*
G01X-18174Y912703D02*
X-18435D01*
G01X-18174Y913611D02*
X-18435D01*
G01X-15985Y913633D02*
X-16213D01*
G01X-14449Y913650D02*
X-14677D01*
G01X12410Y913748D02*
X315D01*
G01X-13009Y913945D02*
X-14147D01*
G01X-18094Y914076D02*
X-18764D01*
G01X512Y914339D02*
X0D01*
G01X-18094Y914896D02*
X-18764D01*
G01X512Y915126D02*
X0D01*
G01X-13009Y915520D02*
X-14147D01*
G01X12410Y915717D02*
X315D01*
G01X-14449Y915815D02*
X-14677D01*
G01X-15985Y915831D02*
X-16213D01*
G01X-18174Y915853D02*
X-18435D01*
G01X-15748Y916209D02*
X-23622D01*
G01X-18174Y916761D02*
X-18435D01*
G01X-15985Y916783D02*
X-16213D01*
G01X-14449Y916799D02*
X-14677D01*
G01X12410Y916898D02*
X315D01*
G01X-15748Y917029D02*
X-23622D01*
G01X-13009Y917094D02*
X-14147D01*
G01X512Y917488D02*
X0D01*
G01X512Y918276D02*
X0D01*
G01X-13009Y918669D02*
X-14147D01*
G01X12410Y918866D02*
X315D01*
G01X-14449Y918965D02*
X-14677D01*
G01X-15985Y918981D02*
X-16213D01*
G01X-18174Y919002D02*
X-18435D01*
G01X-18174Y919911D02*
X-18435D01*
G01X-15985Y919932D02*
X-16213D01*
G01X-14449Y919949D02*
X-14677D01*
G01X12410Y920047D02*
X315D01*
G01X-13009Y920244D02*
X-14147D01*
G01X512Y920638D02*
X0D01*
G01X-19469Y887521D02*
X-20801Y887533D01*
G01X-15985Y887485D02*
X-18435Y887506D01*
G01X-19469Y890670D02*
X-20801Y890682D01*
G01X-15985Y890634D02*
X-18435Y890656D01*
G01X-19469Y893820D02*
X-20801Y893832D01*
G01X-15985Y893784D02*
X-18435Y893806D01*
G01X-19469Y896970D02*
X-20801Y896981D01*
G01X-15985Y896933D02*
X-18435Y896955D01*
G01X-19469Y900119D02*
X-20801Y900131D01*
G01X-15985Y900083D02*
X-18435Y900105D01*
G01X-19469Y903269D02*
X-20801Y903281D01*
G01X-15985Y903233D02*
X-18435Y903254D01*
G01X-19469Y906419D02*
X-20801Y906430D01*
G01X-15985Y906382D02*
X-18435Y906404D01*
G01X-19469Y909568D02*
X-20801Y909580D01*
G01X-15985Y909532D02*
X-18435Y909554D01*
G01X-19469Y912718D02*
X-20801Y912730D01*
G01X-15985Y912681D02*
X-18435Y912703D01*
G01X-19469Y915867D02*
X-20801Y915879D01*
G01X-15985Y915831D02*
X-18435Y915853D01*
G01X-19469Y919017D02*
X-20801Y919029D01*
G01X-15985Y918981D02*
X-18435Y919002D01*
G01X-15985Y887485D02*
X-14449Y887469D01*
G01X-15985Y890634D02*
X-14449Y890618D01*
G01X-15985Y893784D02*
X-14449Y893768D01*
G01X-15985Y896933D02*
X-14449Y896917D01*
G01X-15985Y900083D02*
X-14449Y900067D01*
G01X-15985Y903233D02*
X-14449Y903217D01*
G01X-15985Y906382D02*
X-14449Y906366D01*
G01X-15985Y909532D02*
X-14449Y909516D01*
G01X-15985Y912681D02*
X-14449Y912665D01*
G01X-15985Y915831D02*
X-14449Y915815D01*
G01X-15985Y918981D02*
X-14449Y918965D01*
G01X-18435Y887506D02*
X-20801Y887533D01*
G01X-18435Y890656D02*
X-20801Y890682D01*
G01X-18435Y893806D02*
X-20801Y893832D01*
G01X-18435Y896955D02*
X-20801Y896981D01*
G01X-18435Y900105D02*
X-20801Y900131D01*
G01X-18435Y903254D02*
X-20801Y903281D01*
G01X-18435Y906404D02*
X-20801Y906430D01*
G01X-18435Y909554D02*
X-20801Y909580D01*
G01X-18435Y912703D02*
X-20801Y912730D01*
G01X-18435Y915853D02*
X-20801Y915879D01*
G01X-18435Y919002D02*
X-20801Y919029D01*
G01X-19469Y887521D02*
X-16213Y887485D01*
G01X-18174Y887506D02*
X-14677Y887469D01*
G01X-19469Y890670D02*
X-16213Y890634D01*
G01X-18174Y890656D02*
X-14677Y890618D01*
G01X-19469Y893820D02*
X-16213Y893784D01*
G01X-18174Y893806D02*
X-14677Y893768D01*
G01X-19469Y896970D02*
X-16213Y896933D01*
G01X-18174Y896955D02*
X-14677Y896917D01*
G01X-19469Y900119D02*
X-16213Y900083D01*
G01X-18174Y900105D02*
X-14677Y900067D01*
G01X-19469Y903269D02*
X-16213Y903233D01*
G01X-18174Y903254D02*
X-14677Y903217D01*
G01X-19469Y906419D02*
X-16213Y906382D01*
G01X-18174Y906404D02*
X-14677Y906366D01*
G01X-19469Y909568D02*
X-16213Y909532D01*
G01X-18174Y909554D02*
X-14677Y909516D01*
G01X-19469Y912718D02*
X-16213Y912681D01*
G01X-18174Y912703D02*
X-14677Y912665D01*
G01X-19469Y915867D02*
X-16213Y915831D01*
G01X-18174Y915853D02*
X-14677Y915815D01*
G01X-19469Y919017D02*
X-16213Y918981D01*
G01X-18174Y919002D02*
X-14677Y918965D01*
G01X-18931Y889142D02*
X-19434Y888978D01*
G01X-19099Y895867D02*
X-19937Y895703D01*
G01X-17424Y897344D02*
X-18429Y897180D01*
G01X-16921Y909975D02*
X-18094Y909647D01*
G01X-19099Y889962D02*
X-19769Y889798D01*
G01X-19099Y895047D02*
X-19769Y894883D01*
G01X-19099Y902429D02*
X-19769Y902265D01*
G01X-17424Y910631D02*
X-18094Y910467D01*
G01X-18764Y914076D02*
X-19434Y913912D01*
G01X-18764Y914896D02*
X-19434Y914732D01*
G01X-18931Y907514D02*
X-19769Y907350D01*
G01X-18931Y908335D02*
X-19769Y908170D01*
G01X-23622Y873394D02*
Y872081D01*
G01X-21109Y882252D02*
Y881596D01*
G01Y885533D02*
Y884713D01*
G01Y879627D02*
Y878971D01*
G01Y878151D02*
Y877331D01*
G01X-20801Y882089D02*
Y881233D01*
G01Y885239D02*
Y884383D01*
G01Y878940D02*
Y878084D01*
G01Y872641D02*
Y871785D01*
G01Y875790D02*
Y874934D01*
G01Y869491D02*
Y868635D01*
G01Y866341D02*
Y865485D01*
G01X-20439Y881924D02*
Y881431D01*
G01Y879299D02*
Y878971D01*
G01X-19469Y882095D02*
Y881228D01*
G01Y885245D02*
Y884377D01*
G01Y878946D02*
Y878078D01*
G01Y872646D02*
Y871779D01*
G01Y875796D02*
Y874928D01*
G01Y869497D02*
Y868629D01*
G01Y866347D02*
Y865480D01*
G01X-18435Y882115D02*
Y881207D01*
G01Y885265D02*
Y884357D01*
G01Y878966D02*
Y878057D01*
G01Y872667D02*
Y871758D01*
G01Y875816D02*
Y874908D01*
G01Y869517D02*
Y868609D01*
G01Y866367D02*
Y865459D01*
G01X-18429Y874214D02*
Y871261D01*
G01X-18174Y882115D02*
Y881207D01*
G01Y885265D02*
Y884357D01*
G01Y878966D02*
Y878057D01*
G01Y872667D02*
Y871758D01*
G01Y875816D02*
Y874908D01*
G01Y869517D02*
Y868609D01*
G01Y866367D02*
Y865459D01*
G01X-17759Y874378D02*
Y871097D01*
G01X-16213Y882137D02*
Y881185D01*
G01Y885287D02*
Y884335D01*
G01Y878987D02*
Y878036D01*
G01Y872688D02*
Y871737D01*
G01Y875838D02*
Y874886D01*
G01Y869539D02*
Y868587D01*
G01Y866389D02*
Y865437D01*
G01X-15985Y882137D02*
Y881185D01*
G01Y885287D02*
Y884335D01*
G01Y878987D02*
Y878036D01*
G01Y872688D02*
Y871737D01*
G01Y875838D02*
Y874886D01*
G01Y869539D02*
Y868587D01*
G01Y866389D02*
Y865437D01*
G01X-15748Y883400D02*
Y882580D01*
G01Y878151D02*
Y877331D01*
G01Y880776D02*
Y879955D01*
G01Y876018D02*
Y875034D01*
G01Y870441D02*
Y869457D01*
G01X-21109Y878971D02*
X-20942Y878479D01*
G01X-20439Y878971D02*
X-20272Y878479D01*
G01X-21109Y881596D02*
X-20942Y881104D01*
G01X-14537Y882241D02*
Y881081D01*
G01Y885391D02*
Y884231D01*
G01Y879092D02*
Y877932D01*
G01Y872793D02*
Y871633D01*
G01Y875942D02*
Y874782D01*
G01Y869643D02*
Y868483D01*
G01Y866493D02*
Y865333D01*
G01X-13068Y885533D02*
Y884713D01*
G01X-13009Y882449D02*
Y880874D01*
G01Y885598D02*
Y884024D01*
G01Y879299D02*
Y877724D01*
G01Y873000D02*
Y871425D01*
G01Y876150D02*
Y874575D01*
G01Y869850D02*
Y868276D01*
G01X315Y882843D02*
Y882252D01*
G01Y884220D02*
Y883630D01*
G01Y876543D02*
Y875953D01*
G01Y879693D02*
Y879102D01*
G01Y877921D02*
Y877331D01*
G01Y881071D02*
Y880480D01*
G01Y873394D02*
Y872803D01*
G01Y874772D02*
Y874181D01*
G01Y867094D02*
Y866504D01*
G01Y870244D02*
Y869654D01*
G01Y868472D02*
Y867882D01*
G01Y871622D02*
Y871031D01*
G01X512Y882843D02*
Y882252D01*
G01Y884220D02*
Y883630D01*
G01Y876543D02*
Y875953D01*
G01Y879693D02*
Y879102D01*
G01Y877921D02*
Y877331D01*
G01Y881071D02*
Y880480D01*
G01Y873394D02*
Y872803D01*
G01Y874772D02*
Y874181D01*
G01Y867094D02*
Y866504D01*
G01Y870244D02*
Y869654D01*
G01Y868472D02*
Y867882D01*
G01Y871622D02*
Y871031D01*
G01X709Y882252D02*
Y881071D01*
G01Y885402D02*
Y884220D01*
G01Y879102D02*
Y877921D01*
G01Y872803D02*
Y871622D01*
G01Y875953D02*
Y874772D01*
G01Y869654D02*
Y868472D01*
G01Y866504D02*
Y865323D01*
G01X1074Y882252D02*
Y881071D01*
G01Y885402D02*
Y884220D01*
G01Y879102D02*
Y877921D01*
G01Y872803D02*
Y871622D01*
G01Y875953D02*
Y874772D01*
G01Y869654D02*
Y868472D01*
G01Y866504D02*
Y865323D01*
G01X1184Y882252D02*
Y881071D01*
G01Y885402D02*
Y884220D01*
G01Y879102D02*
Y877921D01*
G01Y872803D02*
Y871622D01*
G01Y875953D02*
Y874772D01*
G01Y869654D02*
Y868472D01*
G01Y866504D02*
Y865323D01*
G01X9965Y882252D02*
Y881071D01*
G01Y885402D02*
Y884220D01*
G01Y879102D02*
Y877921D01*
G01Y872803D02*
Y871622D01*
G01Y875953D02*
Y874772D01*
G01Y869654D02*
Y868472D01*
G01Y866504D02*
Y865323D01*
G01X10075Y882252D02*
Y881071D01*
G01Y885402D02*
Y884220D01*
G01Y879102D02*
Y877921D01*
G01Y872803D02*
Y871622D01*
G01Y875953D02*
Y874772D01*
G01Y869654D02*
Y868472D01*
G01Y866504D02*
Y865323D01*
G01X-20942Y882744D02*
X-21109Y882252D01*
G01X-20942Y880119D02*
X-21109Y879627D01*
G01X-20942Y878479D02*
X-20607Y878151D01*
G01X-20272Y878479D02*
X-19937Y878151D01*
G01X-20942Y881104D02*
X-20439Y880611D01*
G01X-20272Y881104D02*
X-20104Y880939D01*
G01X-20439Y881431D02*
X-20272Y881104D01*
G01Y882252D02*
X-20439Y881924D01*
G01X-20272Y879627D02*
X-20439Y879299D01*
G01X-14677Y865421D02*
X-14537Y865333D01*
G01X-14677Y868571D02*
X-14537Y868483D01*
G01X-14449Y868571D02*
X-13977Y868276D01*
G01X-14677Y871720D02*
X-14537Y871633D01*
G01X-14449Y871720D02*
X-13977Y871425D01*
G01X-14677Y874870D02*
X-14537Y874782D01*
G01X-14449Y874870D02*
X-13977Y874575D01*
G01X-14677Y878020D02*
X-14537Y877932D01*
G01X-14449Y878020D02*
X-13977Y877724D01*
G01X-14677Y881169D02*
X-14537Y881081D01*
G01X-14449Y881169D02*
X-13977Y880874D01*
G01X-14677Y884319D02*
X-14537Y884231D01*
G01X-14449Y884319D02*
X-13977Y884024D01*
G01X-20104Y880939D02*
X-19769Y880776D01*
G01X-14537Y868483D02*
X-14147Y868276D01*
G01X-14537Y871633D02*
X-14147Y871425D01*
G01X-14537Y874782D02*
X-14147Y874575D01*
G01X-14537Y877932D02*
X-14147Y877724D01*
G01X-14537Y881081D02*
X-14147Y880874D01*
G01X-14537Y884231D02*
X-14147Y884024D01*
G01X-20607Y883072D02*
X-20942Y882744D01*
G01X-20104Y882416D02*
X-20272Y882252D01*
G01X-20439Y880611D02*
X-20942Y880119D01*
G01X-20104Y879791D02*
X-20272Y879627D01*
G01X-18429Y871261D02*
X-22952Y872737D01*
G01X-15748Y870441D02*
X-17759Y871097D01*
G01X-15748Y869457D02*
X-23622Y872081D01*
G01X-14537Y882241D02*
X-14677Y882154D01*
G01X-13977Y882449D02*
X-14449Y882154D01*
G01X-14537Y879092D02*
X-14677Y879004D01*
G01X-13977Y879299D02*
X-14449Y879004D01*
G01X-14537Y875942D02*
X-14677Y875854D01*
G01X-13977Y876150D02*
X-14449Y875854D01*
G01X-14537Y872793D02*
X-14677Y872705D01*
G01X-13977Y873000D02*
X-14449Y872705D01*
G01X-14537Y869643D02*
X-14677Y869555D01*
G01X-13977Y869850D02*
X-14449Y869555D01*
G01X-14537Y866493D02*
X-14677Y866406D01*
G01X-13977Y866701D02*
X-14449Y866406D01*
G01X-14147Y882449D02*
X-14537Y882241D01*
G01X-14147Y879299D02*
X-14537Y879092D01*
G01X-14147Y876150D02*
X-14537Y875942D01*
G01X-14147Y873000D02*
X-14537Y872793D01*
G01X-14147Y869850D02*
X-14537Y869643D01*
G01X-14147Y866701D02*
X-14537Y866493D01*
G01X-19769Y882580D02*
X-20104Y882416D01*
G01X-19769Y879955D02*
X-20104Y879791D01*
G01X-19769Y883400D02*
X-20607Y883072D01*
G01X-19469Y866353D02*
X-18174Y866367D01*
G01X-18435D02*
X-20801Y866341D01*
G01X-18174Y866367D02*
X-17126Y866379D01*
G01X-19469Y869503D02*
X-18174Y869517D01*
G01X-18435D02*
X-20801Y869491D01*
G01X-18174Y869517D02*
X-17126Y869528D01*
G01X-19469Y872652D02*
X-18174Y872667D01*
G01X-18435D02*
X-20801Y872641D01*
G01X-18174Y872667D02*
X-17126Y872678D01*
G01X-19469Y875802D02*
X-18174Y875816D01*
G01X-18435D02*
X-20801Y875790D01*
G01X-18174Y875816D02*
X-17126Y875828D01*
G01X-19469Y878952D02*
X-18174Y878966D01*
G01X-18435D02*
X-20801Y878940D01*
G01X-18174Y878966D02*
X-17126Y878977D01*
G01X-19469Y882101D02*
X-18174Y882115D01*
G01X-18435D02*
X-20801Y882089D01*
G01X-18174Y882115D02*
X-17126Y882127D01*
G01X-19469Y885251D02*
X-18174Y885265D01*
G01X-18435D02*
X-20801Y885239D01*
G01X-18174Y885265D02*
X-17126Y885276D01*
G01X-15985Y866389D02*
X-14449Y866406D01*
G01X-14677D02*
X-18174Y866367D01*
G01X-14677Y866406D02*
X-16213Y866389D01*
G01X-15985Y869539D02*
X-14449Y869555D01*
G01X-14677D02*
X-18174Y869517D01*
G01X-14677Y869555D02*
X-16213Y869539D01*
G01X-15985Y872688D02*
X-14449Y872705D01*
G01X-14677D02*
X-18174Y872667D01*
G01X-14677Y872705D02*
X-16213Y872688D01*
G01X-15985Y875838D02*
X-14449Y875854D01*
G01X-14677D02*
X-18174Y875816D01*
G01X-14677Y875854D02*
X-16213Y875838D01*
G01X-15985Y878987D02*
X-14449Y879004D01*
G01X-14677D02*
X-18174Y878966D01*
G01X-14677Y879004D02*
X-16213Y878987D01*
G01X-15985Y882137D02*
X-14449Y882154D01*
G01X-14677D02*
X-18174Y882115D01*
G01X-14677Y882154D02*
X-16213Y882137D01*
G01X-14677Y885303D02*
X-18174Y885265D01*
G01X-19469Y866353D02*
X-20801Y866341D01*
G01X-19469Y869503D02*
X-20801Y869491D01*
G01X-19469Y872652D02*
X-20801Y872641D01*
G01X-19469Y875802D02*
X-20801Y875790D01*
G01X-19469Y878952D02*
X-20801Y878940D01*
G01X-19469Y882101D02*
X-20801Y882089D01*
G01X-19469Y885251D02*
X-20801Y885239D01*
G01X-15985Y866389D02*
X-17126Y866379D01*
G01X-18435Y866367D02*
X-17126Y866379D01*
G01X-15985Y869539D02*
X-17126Y869528D01*
G01D02*
X-18435Y869517D01*
G01X-15985Y872688D02*
X-17126Y872678D01*
G01D02*
X-18435Y872667D01*
G01X-15985Y875838D02*
X-17126Y875828D01*
G01D02*
X-18435Y875816D01*
G01X-15985Y878987D02*
X-17126Y878977D01*
G01D02*
X-18435Y878966D01*
G01X-15985Y882137D02*
X-17126Y882127D01*
G01D02*
X-18435Y882115D01*
G01X-17126Y885276D02*
X-18435Y885265D01*
G01X12410Y865323D02*
X315D01*
G01X-14449Y865421D02*
X-14677D01*
G01X-15985Y865437D02*
X-16213D01*
G01X-18174Y865459D02*
X-18435D01*
G01X-18174Y866367D02*
X-18435D01*
G01X-15985Y866389D02*
X-16213D01*
G01X-14449Y866406D02*
X-14677D01*
G01X12410Y866504D02*
X315D01*
G01X-13009Y866701D02*
X-14147D01*
G01X512Y867094D02*
X0D01*
G01X512Y867882D02*
X0D01*
G01X-13009Y868276D02*
X-14147D01*
G01X12410Y868472D02*
X315D01*
G01X-14449Y868571D02*
X-14677D01*
G01X-15985Y868587D02*
X-16213D01*
G01X-18174Y868609D02*
X-18435D01*
G01X-18174Y869517D02*
X-18435D01*
G01X-15985Y869539D02*
X-16213D01*
G01X-14449Y869555D02*
X-14677D01*
G01X12410Y869654D02*
X315D01*
G01X-13009Y869850D02*
X-14147D01*
G01X512Y870244D02*
X0D01*
G01X512Y871031D02*
X0D01*
G01X-13009Y871425D02*
X-14147D01*
G01X12410Y871622D02*
X315D01*
G01X-14449Y871720D02*
X-14677D01*
G01X-15985Y871737D02*
X-16213D01*
G01X-18174Y871758D02*
X-18435D01*
G01X-18174Y872667D02*
X-18435D01*
G01X-15985Y872688D02*
X-16213D01*
G01X-14449Y872705D02*
X-14677D01*
G01X12410Y872803D02*
X315D01*
G01X-13009Y873000D02*
X-14147D01*
G01X512Y873394D02*
X0D01*
G01X512Y874181D02*
X0D01*
G01X-13009Y874575D02*
X-14147D01*
G01X12410Y874772D02*
X315D01*
G01X-14449Y874870D02*
X-14677D01*
G01X-15985Y874886D02*
X-16213D01*
G01X-18174Y874908D02*
X-18435D01*
G01X-18174Y875816D02*
X-18435D01*
G01X-15985Y875838D02*
X-16213D01*
G01X-14449Y875854D02*
X-14677D01*
G01X12410Y875953D02*
X315D01*
G01X-13009Y876150D02*
X-14147D01*
G01X512Y876543D02*
X0D01*
G01X512Y877331D02*
X0D01*
G01X-15748D02*
X-21109D01*
G01X-13009Y877724D02*
X-14147D01*
G01X12410Y877921D02*
X315D01*
G01X-14449Y878020D02*
X-14677D01*
G01X-15985Y878036D02*
X-16213D01*
G01X-18174Y878057D02*
X-18435D01*
G01X-15748Y878151D02*
X-19937D01*
G01X-20607D02*
X-21109D01*
G01X-18174Y878966D02*
X-18435D01*
G01X-15985Y878987D02*
X-16213D01*
G01X-14449Y879004D02*
X-14677D01*
G01X12410Y879102D02*
X315D01*
G01X-13009Y879299D02*
X-14147D01*
G01X512Y879693D02*
X0D01*
G01X-15748Y879955D02*
X-19769D01*
G01X512Y880480D02*
X0D01*
G01X-15748Y880776D02*
X-19769D01*
G01X-13009Y880874D02*
X-14147D01*
G01X12410Y881071D02*
X315D01*
G01X-14449Y881169D02*
X-14677D01*
G01X-15985Y881185D02*
X-16213D01*
G01X-18174Y881207D02*
X-18435D01*
G01X-18174Y882115D02*
X-18435D01*
G01X-15985Y882137D02*
X-16213D01*
G01X-14449Y882154D02*
X-14677D01*
G01X12410Y882252D02*
X315D01*
G01X-13009Y882449D02*
X-14147D01*
G01X-15748Y882580D02*
X-19769D01*
G01X512Y882843D02*
X0D01*
G01X-15748Y883400D02*
X-19769D01*
G01X512Y883630D02*
X0D01*
G01X-13009Y884024D02*
X-14147D01*
G01X12410Y884220D02*
X315D01*
G01X-14449Y884319D02*
X-14677D01*
G01X-15985Y884335D02*
X-16213D01*
G01X-18174Y884357D02*
X-18435D01*
G01X-13068Y884713D02*
X-21109D01*
G01X-18174Y885265D02*
X-18435D01*
G01X-19469Y865474D02*
X-20801Y865485D01*
G01X-15985Y865437D02*
X-18435Y865459D01*
G01X-19469Y868623D02*
X-20801Y868635D01*
G01X-15985Y868587D02*
X-18435Y868609D01*
G01X-19469Y871773D02*
X-20801Y871785D01*
G01X-15985Y871737D02*
X-18435Y871758D01*
G01X-19469Y874922D02*
X-20801Y874934D01*
G01X-15985Y874886D02*
X-18435Y874908D01*
G01X-19469Y878072D02*
X-20801Y878084D01*
G01X-15985Y878036D02*
X-18435Y878057D01*
G01X-19469Y881222D02*
X-20801Y881233D01*
G01X-15985Y881185D02*
X-18435Y881207D01*
G01X-19469Y884371D02*
X-20801Y884383D01*
G01X-15985Y884335D02*
X-18435Y884357D01*
G01X-15985Y865437D02*
X-14449Y865421D01*
G01X-15985Y868587D02*
X-14449Y868571D01*
G01X-15985Y871737D02*
X-14449Y871720D01*
G01X-15985Y874886D02*
X-14449Y874870D01*
G01X-15985Y878036D02*
X-14449Y878020D01*
G01X-15985Y881185D02*
X-14449Y881169D01*
G01X-15985Y884335D02*
X-14449Y884319D01*
G01X-18435Y865459D02*
X-20801Y865485D01*
G01X-18435Y868609D02*
X-20801Y868635D01*
G01X-18435Y871758D02*
X-20801Y871785D01*
G01X-18435Y874908D02*
X-20801Y874934D01*
G01X-18435Y878057D02*
X-20801Y878084D01*
G01X-18435Y881207D02*
X-20801Y881233D01*
G01X-18435Y884357D02*
X-20801Y884383D01*
G01X-19469Y865474D02*
X-16213Y865437D01*
G01X-18174Y865459D02*
X-14677Y865421D01*
G01X-19469Y868623D02*
X-16213Y868587D01*
G01X-18174Y868609D02*
X-14677Y868571D01*
G01X-19469Y871773D02*
X-16213Y871737D01*
G01X-18174Y871758D02*
X-14677Y871720D01*
G01X-19469Y874922D02*
X-16213Y874886D01*
G01X-18174Y874908D02*
X-14677Y874870D01*
G01X-19469Y878072D02*
X-16213Y878036D01*
G01X-18174Y878057D02*
X-14677Y878020D01*
G01X-19469Y881222D02*
X-16213Y881185D01*
G01X-18174Y881207D02*
X-14677Y881169D01*
G01X-19469Y884371D02*
X-16213Y884335D01*
G01X-18174Y884357D02*
X-14677Y884319D01*
G01X-15748Y876018D02*
X-23622Y873394D01*
G01X-18429Y874214D02*
X-22952Y872737D01*
G01X-15748Y875034D02*
X-17759Y874378D01*
G01X22441Y953709D02*
X11811D01*
G01X35827Y987894D02*
Y989626D01*
G01D02*
X40551Y994272D01*
G01X40547Y993164D02*
X35827Y988522D01*
G01X39236Y985925D02*
X35827Y987894D01*
G01X12057Y923197D02*
Y922016D01*
G01X12410Y923197D02*
Y922016D01*
G01X13353Y922941D02*
Y922272D01*
G01X13701Y922941D02*
Y922272D01*
G01X22441Y963157D02*
Y933630D01*
G01X12057Y923197D02*
X12287Y922941D01*
G01X12416Y923211D02*
X12634Y922941D01*
G01Y922272D02*
X12416Y922002D01*
G01X12287Y922272D02*
X12057Y922016D01*
G01X13701Y922272D02*
X12287D01*
G01X13701Y922941D02*
X12287D01*
G01X22441Y945047D02*
X11811D01*
G01X11861D02*
G03Y953708I-50J4331D01*
G01X22441Y963157D02*
X-9055D01*
G01Y954102D02*
X11813Y953709D01*
G01X11893Y953708D02*
X-9055Y954102D01*
G01X-30709Y933630D02*
Y928512D01*
G01X-20801Y923034D02*
Y922178D01*
G01X-19469Y923040D02*
Y922172D01*
G01X-18435Y923060D02*
Y922152D01*
G01X-18174Y923060D02*
Y922152D01*
G01X-16213Y923082D02*
Y922130D01*
G01X-15985Y923082D02*
Y922130D01*
G01X-14537Y923186D02*
Y922026D01*
G01X-13009Y923394D02*
Y921819D01*
G01X-9055Y963157D02*
Y942291D01*
G01X315Y923787D02*
Y923197D01*
G01Y922016D02*
Y921425D01*
G01X512Y923787D02*
Y923197D01*
G01Y922016D02*
Y921425D01*
G01X709Y923197D02*
Y922016D01*
G01X1074Y923197D02*
Y922016D01*
G01X1184Y923197D02*
Y922016D01*
G01X9965Y923197D02*
Y922016D01*
G01X10075Y923197D02*
Y922016D01*
G01X3937Y933630D02*
X0Y929693D01*
G01X-30709Y928512D02*
X-26772Y926543D01*
G01X-14537Y922026D02*
X-14147Y921819D01*
G01X-14677Y922114D02*
X-14537Y922026D01*
G01X-14449Y922114D02*
X-13977Y921819D01*
G01X-14537Y923186D02*
X-14677Y923098D01*
G01X-13977Y923394D02*
X-14449Y923098D01*
G01X-14147Y923394D02*
X-14537Y923186D01*
G01X-19469Y923046D02*
X-18174Y923060D01*
G01X-18435D02*
X-20801Y923034D01*
G01X-18174Y923060D02*
X-17126Y923072D01*
G01X-15985Y923082D02*
X-14449Y923098D01*
G01X-14677D02*
X-18174Y923060D01*
G01X-14677Y923098D02*
X-16213Y923082D01*
G01X-19469Y923046D02*
X-20801Y923034D01*
G01X-15985Y923082D02*
X-17126Y923072D01*
G01D02*
X-18435Y923060D01*
G01X512Y921425D02*
X0D01*
G01X-13009Y921819D02*
X-14147D01*
G01X12410Y922016D02*
X315D01*
G01X-14449Y922114D02*
X-14677D01*
G01X-15985Y922130D02*
X-16213D01*
G01X-18174Y922152D02*
X-18435D01*
G01X-18174Y923060D02*
X-18435D01*
G01X-15985Y923082D02*
X-16213D01*
G01X-14449Y923098D02*
X-14677D01*
G01X12410Y923197D02*
X315D01*
G01X-13009Y923394D02*
X-14147D01*
G01X512Y923787D02*
X0D01*
G01X-7283Y926543D02*
X-26772D01*
G01X-19469Y922167D02*
X-20801Y922178D01*
G01X-15985Y922130D02*
X-18435Y922152D01*
G01X-15985Y922130D02*
X-14449Y922114D01*
G01X-18435Y922152D02*
X-20801Y922178D01*
G01X-19469Y922167D02*
X-16213Y922130D01*
G01X-18174Y922152D02*
X-14677Y922114D01*
G01X11893Y945048D02*
X-9055Y944654D01*
G01X11817Y945047D02*
X-9055Y944654D01*
G01X22441Y933630D02*
X3937D01*
G01X16142Y949378D02*
G03I-4331J0D01*
G01X11827Y953709D02*
G03Y945047I-16J-4331D01*
G01X0Y993079D02*
G03X-7874I-3937J0D01*
G01Y986780D02*
Y993079D01*
G01X22441Y1083236D02*
Y1053709D01*
G01Y1063157D02*
X11811D01*
G01X49213Y1029527D02*
G03I-15749J0D01*
G01X40453D02*
G03I-6989J0D01*
G01X11861Y1063157D02*
G03Y1071819I-50J4331D01*
G01X-9055Y1077331D02*
Y1053709D01*
G01X11893Y1063158D02*
X-9055Y1062764D01*
G01D02*
X11813Y1063157D01*
G01X22441Y1053709D02*
X-9055D01*
G01X16142Y1067488D02*
G03I-4331J0D01*
G01X11827Y1071819D02*
G03Y1063157I-16J-4331D01*
G01X-7874Y1023787D02*
Y1030087D01*
G01Y1023787D02*
G03X0I3937J0D01*
G01X12057Y1101150D02*
Y1099969D01*
G01Y1104299D02*
Y1103118D01*
G01Y1098000D02*
Y1096819D01*
G01Y1094850D02*
Y1093669D01*
G01X12410Y1101150D02*
Y1099969D01*
G01Y1104299D02*
Y1103118D01*
G01Y1098000D02*
Y1096819D01*
G01Y1094850D02*
Y1093669D01*
G01X13353Y1104043D02*
Y1103374D01*
G01Y1097744D02*
Y1097075D01*
G01Y1100894D02*
Y1100224D01*
G01Y1094594D02*
Y1093925D01*
G01X13701Y1104043D02*
Y1103374D01*
G01Y1097744D02*
Y1097075D01*
G01Y1100894D02*
Y1100224D01*
G01Y1094594D02*
Y1093925D01*
G01X13780Y1095244D02*
Y1093276D01*
G01X15945Y1095215D02*
Y1095480D01*
G01Y1093709D02*
Y1093974D01*
G01Y1092823D02*
Y1093089D01*
G01X16487Y1094152D02*
Y1095037D01*
G01X16669Y1094196D02*
Y1094993D01*
G01X18071Y1094772D02*
Y1094417D01*
G01Y1093089D02*
Y1092823D01*
G01X12634Y1103374D02*
X12416Y1103104D01*
G01X12634Y1100224D02*
X12416Y1099954D01*
G01X12634Y1097075D02*
X12416Y1096805D01*
G01X12634Y1093925D02*
X12416Y1093655D01*
G01X12287Y1103374D02*
X12057Y1103118D01*
G01X12287Y1100224D02*
X12057Y1099969D01*
G01X12287Y1097075D02*
X12057Y1096819D01*
G01X12287Y1093925D02*
X12057Y1093669D01*
G01Y1094850D02*
X12287Y1094594D01*
G01X12057Y1098000D02*
X12287Y1097744D01*
G01X12057Y1101150D02*
X12287Y1100894D01*
G01X12057Y1104299D02*
X12287Y1104043D01*
G01X12416Y1094865D02*
X12634Y1094594D01*
G01X12416Y1098014D02*
X12634Y1097744D01*
G01X12416Y1101164D02*
X12634Y1100894D01*
G01X12416Y1104313D02*
X12634Y1104043D01*
G01X18071Y1094417D02*
X15945Y1093709D01*
G01Y1093974D02*
X16487Y1094152D01*
G01X17890Y1094594D02*
X16669Y1094196D01*
G01X17709Y1093089D02*
X17392Y1093354D01*
G01X17754D02*
X18071Y1093089D01*
G01X16487Y1095037D02*
X15945Y1095215D01*
G01X16669Y1094993D02*
X17890Y1094594D01*
G01X15945Y1095480D02*
X18071Y1094772D01*
G01X22441Y1071819D02*
X11811D01*
G01X18071Y1092823D02*
X15945D01*
G01Y1093089D02*
X17709D01*
G01X17392Y1093354D02*
X17754D01*
G01X13701Y1093925D02*
X12287D01*
G01X13701Y1094594D02*
X12287D01*
G01X13701Y1097075D02*
X12287D01*
G01X13701Y1097744D02*
X12287D01*
G01X13701Y1100224D02*
X12287D01*
G01X13701Y1100894D02*
X12287D01*
G01X13701Y1103374D02*
X12287D01*
G01X13701Y1104043D02*
X12287D01*
G01X12057Y1138945D02*
Y1137764D01*
G01Y1135795D02*
Y1134614D01*
G01Y1129496D02*
Y1128315D01*
G01Y1132646D02*
Y1131465D01*
G01X12410Y1138945D02*
Y1137764D01*
G01Y1135795D02*
Y1134614D01*
G01Y1129496D02*
Y1128315D01*
G01Y1132646D02*
Y1131465D01*
G01X13353Y1138689D02*
Y1138020D01*
G01Y1135539D02*
Y1134870D01*
G01Y1129240D02*
Y1128571D01*
G01Y1132390D02*
Y1131720D01*
G01Y1126091D02*
Y1125421D01*
G01X13701Y1138689D02*
Y1138020D01*
G01Y1135539D02*
Y1134870D01*
G01Y1129240D02*
Y1128571D01*
G01Y1132390D02*
Y1131720D01*
G01Y1126091D02*
Y1125421D01*
G01X12634Y1138020D02*
X12416Y1137750D01*
G01X12634Y1134870D02*
X12416Y1134600D01*
G01X12634Y1131720D02*
X12416Y1131450D01*
G01X12634Y1128571D02*
X12416Y1128301D01*
G01X12287Y1138020D02*
X12057Y1137764D01*
G01X12287Y1134870D02*
X12057Y1134614D01*
G01X12287Y1131720D02*
X12057Y1131465D01*
G01X12287Y1128571D02*
X12057Y1128315D01*
G01X12416Y1126361D02*
X12634Y1126091D01*
G01X12416Y1129510D02*
X12634Y1129240D01*
G01X12416Y1132660D02*
X12634Y1132390D01*
G01X12416Y1135809D02*
X12634Y1135539D01*
G01X12416Y1138959D02*
X12634Y1138689D01*
G01X12057Y1126346D02*
X12287Y1126091D01*
G01X12057Y1129496D02*
X12287Y1129240D01*
G01X12057Y1132646D02*
X12287Y1132390D01*
G01X12057Y1135795D02*
X12287Y1135539D01*
G01X12057Y1138945D02*
X12287Y1138689D01*
G01X13701Y1125421D02*
X12287D01*
G01X13701Y1126091D02*
X12287D01*
G01X13701Y1128571D02*
X12287D01*
G01X13701Y1129240D02*
X12287D01*
G01X13701Y1131720D02*
X12287D01*
G01X13701Y1132390D02*
X12287D01*
G01X13701Y1134870D02*
X12287D01*
G01X13701Y1135539D02*
X12287D01*
G01X13701Y1138020D02*
X12287D01*
G01X13701Y1138689D02*
X12287D01*
G01X12057Y1126346D02*
Y1125165D01*
G01Y1120047D02*
Y1118866D01*
G01Y1123197D02*
Y1122016D01*
G01Y1116898D02*
Y1115717D01*
G01Y1110598D02*
Y1109417D01*
G01Y1113748D02*
Y1112567D01*
G01Y1107449D02*
Y1106268D01*
G01X12410Y1126346D02*
Y1125165D01*
G01Y1120047D02*
Y1118866D01*
G01Y1123197D02*
Y1122016D01*
G01Y1116898D02*
Y1115717D01*
G01Y1110598D02*
Y1109417D01*
G01Y1113748D02*
Y1112567D01*
G01Y1107449D02*
Y1106268D01*
G01X13353Y1122941D02*
Y1122272D01*
G01Y1116642D02*
Y1115972D01*
G01Y1119791D02*
Y1119122D01*
G01Y1113492D02*
Y1112823D01*
G01Y1107193D02*
Y1106524D01*
G01Y1110343D02*
Y1109673D01*
G01X13701Y1122941D02*
Y1122272D01*
G01Y1116642D02*
Y1115972D01*
G01Y1119791D02*
Y1119122D01*
G01Y1113492D02*
Y1112823D01*
G01Y1107193D02*
Y1106524D01*
G01Y1110343D02*
Y1109673D01*
G01X12634Y1125421D02*
X12416Y1125151D01*
G01X12634Y1122272D02*
X12416Y1122002D01*
G01X12634Y1119122D02*
X12416Y1118852D01*
G01X12634Y1115972D02*
X12416Y1115702D01*
G01X12634Y1112823D02*
X12416Y1112553D01*
G01X12634Y1109673D02*
X12416Y1109403D01*
G01X12634Y1106524D02*
X12416Y1106254D01*
G01X12287Y1125421D02*
X12057Y1125165D01*
G01X12287Y1122272D02*
X12057Y1122016D01*
G01X12287Y1119122D02*
X12057Y1118866D01*
G01X12287Y1115972D02*
X12057Y1115717D01*
G01X12287Y1112823D02*
X12057Y1112567D01*
G01X12287Y1109673D02*
X12057Y1109417D01*
G01X12287Y1106524D02*
X12057Y1106268D01*
G01Y1107449D02*
X12287Y1107193D01*
G01X12416Y1107463D02*
X12634Y1107193D01*
G01X12416Y1110613D02*
X12634Y1110343D01*
G01X12416Y1113762D02*
X12634Y1113492D01*
G01X12416Y1116912D02*
X12634Y1116642D01*
G01X12416Y1120061D02*
X12634Y1119791D01*
G01X12416Y1123211D02*
X12634Y1122941D01*
G01X12057Y1110598D02*
X12287Y1110343D01*
G01X12057Y1113748D02*
X12287Y1113492D01*
G01X12057Y1116898D02*
X12287Y1116642D01*
G01X12057Y1120047D02*
X12287Y1119791D01*
G01X12057Y1123197D02*
X12287Y1122941D01*
G01X13701Y1106524D02*
X12287D01*
G01X13701Y1107193D02*
X12287D01*
G01X13701Y1109673D02*
X12287D01*
G01X13701Y1110343D02*
X12287D01*
G01X13701Y1112823D02*
X12287D01*
G01X13701Y1113492D02*
X12287D01*
G01X13701Y1115972D02*
X12287D01*
G01X13701Y1116642D02*
X12287D01*
G01X13701Y1119122D02*
X12287D01*
G01X13701Y1119791D02*
X12287D01*
G01X13701Y1122272D02*
X12287D01*
G01X13701Y1122941D02*
X12287D01*
G01X-30709Y1420638D02*
Y1092291D01*
G01Y1088354D02*
Y1083236D01*
G01X-26772Y1233630D02*
Y1092291D01*
G01X-20801Y1104137D02*
Y1103281D01*
G01Y1097837D02*
Y1096981D01*
G01Y1100987D02*
Y1100131D01*
G01Y1094688D02*
Y1093832D01*
G01X-19469Y1104143D02*
Y1103275D01*
G01Y1097843D02*
Y1096976D01*
G01Y1100993D02*
Y1100125D01*
G01Y1094694D02*
Y1093826D01*
G01X-18435Y1104163D02*
Y1103254D01*
G01Y1097863D02*
Y1096955D01*
G01Y1101013D02*
Y1100105D01*
G01Y1094714D02*
Y1093806D01*
G01X-18174Y1104163D02*
Y1103254D01*
G01Y1097863D02*
Y1096955D01*
G01Y1101013D02*
Y1100105D01*
G01Y1094714D02*
Y1093806D01*
G01X-16213Y1104184D02*
Y1103233D01*
G01Y1097885D02*
Y1096933D01*
G01Y1101035D02*
Y1100083D01*
G01Y1094735D02*
Y1093784D01*
G01X-15985Y1104184D02*
Y1103233D01*
G01Y1097885D02*
Y1096933D01*
G01Y1101035D02*
Y1100083D01*
G01Y1094735D02*
Y1093784D01*
G01X-14537Y1101139D02*
Y1099979D01*
G01Y1104289D02*
Y1103129D01*
G01Y1097989D02*
Y1096830D01*
G01Y1094840D02*
Y1093680D01*
G01X-13009Y1101346D02*
Y1099772D01*
G01Y1104496D02*
Y1102921D01*
G01Y1098197D02*
Y1096622D01*
G01Y1095047D02*
Y1093472D01*
G01X-7283Y1233630D02*
Y1090323D01*
G01X315Y1101740D02*
Y1101150D01*
G01Y1104890D02*
Y1104299D01*
G01Y1103118D02*
Y1102528D01*
G01Y1098591D02*
Y1098000D01*
G01Y1096819D02*
Y1096228D01*
G01Y1099969D02*
Y1099378D01*
G01Y1095441D02*
Y1094850D01*
G01Y1093669D02*
Y1093079D01*
G01X512Y1101740D02*
Y1101150D01*
G01Y1104890D02*
Y1104299D01*
G01Y1103118D02*
Y1102528D01*
G01Y1098591D02*
Y1098000D01*
G01Y1096819D02*
Y1096228D01*
G01Y1099969D02*
Y1099378D01*
G01Y1095441D02*
Y1094850D01*
G01Y1093669D02*
Y1093079D01*
G01X709Y1101150D02*
Y1099969D01*
G01Y1104299D02*
Y1103118D01*
G01Y1098000D02*
Y1096819D01*
G01Y1094850D02*
Y1093669D01*
G01X1074Y1101150D02*
Y1099969D01*
G01Y1104299D02*
Y1103118D01*
G01Y1098000D02*
Y1096819D01*
G01Y1094850D02*
Y1093669D01*
G01X1184Y1101150D02*
Y1099969D01*
G01Y1104299D02*
Y1103118D01*
G01Y1098000D02*
Y1096819D01*
G01Y1094850D02*
Y1093669D01*
G01X3937Y1093276D02*
Y1095244D01*
G01X9965Y1101150D02*
Y1099969D01*
G01Y1104299D02*
Y1103118D01*
G01Y1098000D02*
Y1096819D01*
G01Y1094850D02*
Y1093669D01*
G01X10075Y1101150D02*
Y1099969D01*
G01Y1104299D02*
Y1103118D01*
G01Y1098000D02*
Y1096819D01*
G01Y1094850D02*
Y1093669D01*
G01X-14537Y1104289D02*
X-14677Y1104201D01*
G01X-13977Y1104496D02*
X-14449Y1104201D01*
G01X-14537Y1101139D02*
X-14677Y1101051D01*
G01X-13977Y1101346D02*
X-14449Y1101051D01*
G01X-14537Y1097989D02*
X-14677Y1097902D01*
G01X-13977Y1098197D02*
X-14449Y1097902D01*
G01X-14537Y1094840D02*
X-14677Y1094752D01*
G01X-13977Y1095047D02*
X-14449Y1094752D01*
G01X-27981Y1094260D02*
X-30709Y1092685D01*
G01X-14147Y1104496D02*
X-14537Y1104289D01*
G01X-14147Y1101346D02*
X-14537Y1101139D01*
G01X-14147Y1098197D02*
X-14537Y1097989D01*
G01X-14147Y1095047D02*
X-14537Y1094840D01*
G01X-26772Y1090323D02*
X-30709Y1088354D01*
G01X0Y1087173D02*
X3937Y1083236D01*
G01X-14537Y1093680D02*
X-14147Y1093472D01*
G01X-14537Y1096830D02*
X-14147Y1096622D01*
G01X-14537Y1099979D02*
X-14147Y1099772D01*
G01X-14537Y1103129D02*
X-14147Y1102921D01*
G01X-30709Y1095835D02*
X-27981Y1094260D01*
G01X-14677Y1093768D02*
X-14537Y1093680D01*
G01X-14449Y1093768D02*
X-13977Y1093472D01*
G01X-14677Y1096917D02*
X-14537Y1096830D01*
G01X-14449Y1096917D02*
X-13977Y1096622D01*
G01X-14677Y1100067D02*
X-14537Y1099979D01*
G01X-14449Y1100067D02*
X-13977Y1099772D01*
G01X-14677Y1103217D02*
X-14537Y1103129D01*
G01X-14449Y1103217D02*
X-13977Y1102921D01*
G01X11817Y1071819D02*
X-9055Y1072213D01*
G01X11893Y1071818D02*
X-9055Y1072213D01*
G01X-19469Y1094700D02*
X-18174Y1094714D01*
G01X-18435D02*
X-20801Y1094688D01*
G01X-18174Y1094714D02*
X-17126Y1094725D01*
G01X-19469Y1097849D02*
X-18174Y1097863D01*
G01X-18435D02*
X-20801Y1097837D01*
G01X-18174Y1097863D02*
X-17126Y1097875D01*
G01X-19469Y1100999D02*
X-18174Y1101013D01*
G01X-18435D02*
X-20801Y1100987D01*
G01X-18174Y1101013D02*
X-17126Y1101024D01*
G01X-19469Y1104148D02*
X-18174Y1104163D01*
G01X-18435D02*
X-20801Y1104137D01*
G01X-18174Y1104163D02*
X-17126Y1104174D01*
G01X-15985Y1094735D02*
X-14449Y1094752D01*
G01X-14677D02*
X-18174Y1094714D01*
G01X-14677Y1094752D02*
X-16213Y1094735D01*
G01X-15985Y1097885D02*
X-14449Y1097902D01*
G01X-14677D02*
X-18174Y1097863D01*
G01X-14677Y1097902D02*
X-16213Y1097885D01*
G01X-15985Y1101035D02*
X-14449Y1101051D01*
G01X-14677D02*
X-18174Y1101013D01*
G01X-14677Y1101051D02*
X-16213Y1101035D01*
G01X-15985Y1104184D02*
X-14449Y1104201D01*
G01X-14677D02*
X-18174Y1104163D01*
G01X-14677Y1104201D02*
X-16213Y1104184D01*
G01X-19469Y1094700D02*
X-20801Y1094688D01*
G01X-19469Y1097849D02*
X-20801Y1097837D01*
G01X-19469Y1100999D02*
X-20801Y1100987D01*
G01X-19469Y1104148D02*
X-20801Y1104137D01*
G01X-15985Y1094735D02*
X-17126Y1094725D01*
G01X-18435Y1094714D02*
X-17126Y1094725D01*
G01X-15985Y1097885D02*
X-17126Y1097875D01*
G01D02*
X-18435Y1097863D01*
G01X-15985Y1101035D02*
X-17126Y1101024D01*
G01D02*
X-18435Y1101013D01*
G01X-15985Y1104184D02*
X-17126Y1104174D01*
G01D02*
X-18435Y1104163D01*
G01X22441Y1083236D02*
X3937D01*
G01X-7283Y1090323D02*
X-26772D01*
G01X512Y1093079D02*
X0D01*
G01X13780Y1093276D02*
X3937D01*
G01X-13009Y1093472D02*
X-14147D01*
G01X12410Y1093669D02*
X315D01*
G01X-14449Y1093768D02*
X-14677D01*
G01X-15985Y1093784D02*
X-16213D01*
G01X-18174Y1093806D02*
X-18435D01*
G01X-18174Y1094714D02*
X-18435D01*
G01X-15985Y1094735D02*
X-16213D01*
G01X-14449Y1094752D02*
X-14677D01*
G01X12410Y1094850D02*
X315D01*
G01X-13009Y1095047D02*
X-14147D01*
G01X3937Y1095244D02*
X13780D01*
G01X512Y1095441D02*
X0D01*
G01X512Y1096228D02*
X0D01*
G01X-13009Y1096622D02*
X-14147D01*
G01X12410Y1096819D02*
X315D01*
G01X-14449Y1096917D02*
X-14677D01*
G01X-15985Y1096933D02*
X-16213D01*
G01X-18174Y1096955D02*
X-18435D01*
G01X-18174Y1097863D02*
X-18435D01*
G01X-15985Y1097885D02*
X-16213D01*
G01X-14449Y1097902D02*
X-14677D01*
G01X12410Y1098000D02*
X315D01*
G01X-13009Y1098197D02*
X-14147D01*
G01X512Y1098591D02*
X0D01*
G01X512Y1099378D02*
X0D01*
G01X-13009Y1099772D02*
X-14147D01*
G01X12410Y1099969D02*
X315D01*
G01X-14449Y1100067D02*
X-14677D01*
G01X-15985Y1100083D02*
X-16213D01*
G01X-18174Y1100105D02*
X-18435D01*
G01X-18174Y1101013D02*
X-18435D01*
G01X-15985Y1101035D02*
X-16213D01*
G01X-14449Y1101051D02*
X-14677D01*
G01X12410Y1101150D02*
X315D01*
G01X-13009Y1101346D02*
X-14147D01*
G01X512Y1101740D02*
X0D01*
G01X512Y1102528D02*
X0D01*
G01X-13009Y1102921D02*
X-14147D01*
G01X12410Y1103118D02*
X315D01*
G01X-14449Y1103217D02*
X-14677D01*
G01X-15985Y1103233D02*
X-16213D01*
G01X-18174Y1103254D02*
X-18435D01*
G01Y1104163D02*
X-18174D01*
G01X-15985Y1104184D02*
X-16213D01*
G01X-14449Y1104201D02*
X-14677D01*
G01X12410Y1104299D02*
X315D01*
G01X-13009Y1104496D02*
X-14147D01*
G01X512Y1104890D02*
X0D01*
G01X-19469Y1093820D02*
X-20801Y1093832D01*
G01X-15985Y1093784D02*
X-18435Y1093806D01*
G01X-19469Y1096970D02*
X-20801Y1096981D01*
G01X-15985Y1096933D02*
X-18435Y1096955D01*
G01X-19469Y1100119D02*
X-20801Y1100131D01*
G01X-15985Y1100083D02*
X-18435Y1100105D01*
G01X-19469Y1103269D02*
X-20801Y1103281D01*
G01X-15985Y1103233D02*
X-18435Y1103254D01*
G01X-15985Y1093784D02*
X-14449Y1093768D01*
G01X-15985Y1096933D02*
X-14449Y1096917D01*
G01X-15985Y1100083D02*
X-14449Y1100067D01*
G01X-15985Y1103233D02*
X-14449Y1103217D01*
G01X-18435Y1093806D02*
X-20801Y1093832D01*
G01X-18435Y1096955D02*
X-20801Y1096981D01*
G01X-18435Y1100105D02*
X-20801Y1100131D01*
G01X-18435Y1103254D02*
X-20801Y1103281D01*
G01X-19469Y1093820D02*
X-16213Y1093784D01*
G01X-18174Y1093806D02*
X-14677Y1093768D01*
G01X-19469Y1096970D02*
X-16213Y1096933D01*
G01X-18174Y1096955D02*
X-14677Y1096917D01*
G01X-19469Y1100119D02*
X-16213Y1100083D01*
G01X-18174Y1100105D02*
X-14677Y1100067D01*
G01X-19469Y1103269D02*
X-16213Y1103233D01*
G01X-18174Y1103254D02*
X-14677Y1103217D01*
G01X-20801Y1138782D02*
Y1137926D01*
G01Y1135633D02*
Y1134777D01*
G01Y1129333D02*
Y1128478D01*
G01Y1132483D02*
Y1131627D01*
G01Y1126184D02*
Y1125328D01*
G01X-19469Y1138788D02*
Y1137920D01*
G01Y1135639D02*
Y1134771D01*
G01Y1129339D02*
Y1128472D01*
G01Y1132489D02*
Y1131621D01*
G01Y1126190D02*
Y1125322D01*
G01X-18435Y1138808D02*
Y1137900D01*
G01Y1135659D02*
Y1134750D01*
G01Y1129359D02*
Y1128451D01*
G01Y1132509D02*
Y1131601D01*
G01Y1126210D02*
Y1125302D01*
G01X-18174Y1138808D02*
Y1137900D01*
G01Y1135659D02*
Y1134750D01*
G01Y1129359D02*
Y1128451D01*
G01Y1132509D02*
Y1131601D01*
G01Y1126210D02*
Y1125302D01*
G01X-16213Y1138830D02*
Y1137878D01*
G01Y1135680D02*
Y1134729D01*
G01Y1129381D02*
Y1128430D01*
G01Y1132531D02*
Y1131579D01*
G01Y1126231D02*
Y1125280D01*
G01X-15985Y1138830D02*
Y1137878D01*
G01Y1135680D02*
Y1134729D01*
G01Y1129381D02*
Y1128430D01*
G01Y1132531D02*
Y1131579D01*
G01Y1126231D02*
Y1125280D01*
G01X-14537Y1138934D02*
Y1137774D01*
G01Y1135785D02*
Y1134625D01*
G01Y1129485D02*
Y1128326D01*
G01Y1132635D02*
Y1131475D01*
G01X-13009Y1139142D02*
Y1137567D01*
G01Y1135992D02*
Y1134417D01*
G01Y1129693D02*
Y1128118D01*
G01Y1132843D02*
Y1131268D01*
G01X315Y1136386D02*
Y1135795D01*
G01Y1134614D02*
Y1134024D01*
G01Y1137764D02*
Y1137173D01*
G01Y1130087D02*
Y1129496D01*
G01Y1133236D02*
Y1132646D01*
G01Y1131465D02*
Y1130874D01*
G01Y1126937D02*
Y1126346D01*
G01Y1128315D02*
Y1127724D01*
G01X512Y1136386D02*
Y1135795D01*
G01Y1134614D02*
Y1134024D01*
G01Y1137764D02*
Y1137173D01*
G01Y1130087D02*
Y1129496D01*
G01Y1133236D02*
Y1132646D01*
G01Y1131465D02*
Y1130874D01*
G01Y1126937D02*
Y1126346D01*
G01Y1128315D02*
Y1127724D01*
G01X709Y1138945D02*
Y1137764D01*
G01Y1135795D02*
Y1134614D01*
G01Y1129496D02*
Y1128315D01*
G01Y1132646D02*
Y1131465D01*
G01X1074Y1138945D02*
Y1137764D01*
G01Y1135795D02*
Y1134614D01*
G01Y1129496D02*
Y1128315D01*
G01Y1132646D02*
Y1131465D01*
G01X1184Y1138945D02*
Y1137764D01*
G01Y1135795D02*
Y1134614D01*
G01Y1129496D02*
Y1128315D01*
G01Y1132646D02*
Y1131465D01*
G01X9965Y1138945D02*
Y1137764D01*
G01Y1135795D02*
Y1134614D01*
G01Y1129496D02*
Y1128315D01*
G01Y1132646D02*
Y1131465D01*
G01X10075Y1138945D02*
Y1137764D01*
G01Y1135795D02*
Y1134614D01*
G01Y1129496D02*
Y1128315D01*
G01Y1132646D02*
Y1131465D01*
G01X-14537Y1138934D02*
X-14677Y1138846D01*
G01X-13977Y1139142D02*
X-14449Y1138846D01*
G01X-14537Y1135785D02*
X-14677Y1135697D01*
G01X-13977Y1135992D02*
X-14449Y1135697D01*
G01X-14537Y1132635D02*
X-14677Y1132547D01*
G01X-13977Y1132843D02*
X-14449Y1132547D01*
G01X-14537Y1129485D02*
X-14677Y1129398D01*
G01X-13977Y1129693D02*
X-14449Y1129398D01*
G01X-14537Y1126336D02*
X-14677Y1126248D01*
G01X-13977Y1126543D02*
X-14449Y1126248D01*
G01X-14147Y1139142D02*
X-14537Y1138934D01*
G01X-14147Y1135992D02*
X-14537Y1135785D01*
G01X-14147Y1132843D02*
X-14537Y1132635D01*
G01X-14147Y1129693D02*
X-14537Y1129485D01*
G01X-14147Y1126543D02*
X-14537Y1126336D01*
G01X-14677Y1128413D02*
X-14537Y1128326D01*
G01X-14449Y1128413D02*
X-13977Y1128118D01*
G01X-14677Y1131563D02*
X-14537Y1131475D01*
G01X-14449Y1131563D02*
X-13977Y1131268D01*
G01X-14677Y1134713D02*
X-14537Y1134625D01*
G01X-14449Y1134713D02*
X-13977Y1134417D01*
G01X-14677Y1137862D02*
X-14537Y1137774D01*
G01X-14449Y1137862D02*
X-13977Y1137567D01*
G01X-14537Y1128326D02*
X-14147Y1128118D01*
G01X-14537Y1131475D02*
X-14147Y1131268D01*
G01X-14537Y1134625D02*
X-14147Y1134417D01*
G01X-14537Y1137774D02*
X-14147Y1137567D01*
G01X-19469Y1126196D02*
X-18174Y1126210D01*
G01X-18435D02*
X-20801Y1126184D01*
G01X-18174Y1126210D02*
X-17126Y1126221D01*
G01X-19469Y1129345D02*
X-18174Y1129359D01*
G01X-18435D02*
X-20801Y1129333D01*
G01X-18174Y1129359D02*
X-17126Y1129371D01*
G01X-19469Y1132495D02*
X-18174Y1132509D01*
G01X-18435D02*
X-20801Y1132483D01*
G01X-18174Y1132509D02*
X-17126Y1132520D01*
G01X-19469Y1135644D02*
X-18174Y1135659D01*
G01X-18435D02*
X-20801Y1135633D01*
G01X-18174Y1135659D02*
X-17126Y1135670D01*
G01X-19469Y1138794D02*
X-18174Y1138808D01*
G01X-18435D02*
X-20801Y1138782D01*
G01X-18174Y1138808D02*
X-17126Y1138820D01*
G01X-15985Y1126231D02*
X-14449Y1126248D01*
G01X-14677D02*
X-18174Y1126210D01*
G01X-14677Y1126248D02*
X-16213Y1126231D01*
G01X-15985Y1129381D02*
X-14449Y1129398D01*
G01X-14677D02*
X-18174Y1129359D01*
G01X-14677Y1129398D02*
X-16213Y1129381D01*
G01X-15985Y1132531D02*
X-14449Y1132547D01*
G01X-14677D02*
X-18174Y1132509D01*
G01X-14677Y1132547D02*
X-16213Y1132531D01*
G01X-15985Y1135680D02*
X-14449Y1135697D01*
G01X-14677D02*
X-18174Y1135659D01*
G01X-14677Y1135697D02*
X-16213Y1135680D01*
G01X-15985Y1138830D02*
X-14449Y1138846D01*
G01X-14677D02*
X-18174Y1138808D01*
G01X-14677Y1138846D02*
X-16213Y1138830D01*
G01X-19469Y1126196D02*
X-20801Y1126184D01*
G01X-19469Y1129345D02*
X-20801Y1129333D01*
G01X-19469Y1132495D02*
X-20801Y1132483D01*
G01X-19469Y1135644D02*
X-20801Y1135633D01*
G01X-19469Y1138794D02*
X-20801Y1138782D01*
G01X-15985Y1126231D02*
X-17126Y1126221D01*
G01D02*
X-18435Y1126210D01*
G01X-15985Y1129381D02*
X-17126Y1129371D01*
G01D02*
X-18435Y1129359D01*
G01X-15985Y1132531D02*
X-17126Y1132520D01*
G01D02*
X-18435Y1132509D01*
G01X-15985Y1135680D02*
X-17126Y1135670D01*
G01D02*
X-18435Y1135659D01*
G01X-15985Y1138830D02*
X-17126Y1138820D01*
G01D02*
X-18435Y1138808D01*
G01X-15985Y1125280D02*
X-16213D01*
G01X-18174Y1125302D02*
X-18435D01*
G01X-18174Y1126210D02*
X-18435D01*
G01X-15985Y1126231D02*
X-16213D01*
G01X-14449Y1126248D02*
X-14677D01*
G01X12410Y1126346D02*
X315D01*
G01X-13009Y1126543D02*
X-14147D01*
G01X512Y1126937D02*
X0D01*
G01X512Y1127724D02*
X0D01*
G01X-13009Y1128118D02*
X-14147D01*
G01X12410Y1128315D02*
X315D01*
G01X-14449Y1128413D02*
X-14677D01*
G01X-15985Y1128430D02*
X-16213D01*
G01X-18174Y1128451D02*
X-18435D01*
G01X-18174Y1129359D02*
X-18435D01*
G01X-15985Y1129381D02*
X-16213D01*
G01X-14449Y1129398D02*
X-14677D01*
G01X12410Y1129496D02*
X315D01*
G01X-13009Y1129693D02*
X-14147D01*
G01X512Y1130087D02*
X0D01*
G01X512Y1130874D02*
X0D01*
G01X-13009Y1131268D02*
X-14147D01*
G01X12410Y1131465D02*
X315D01*
G01X-14449Y1131563D02*
X-14677D01*
G01X-15985Y1131579D02*
X-16213D01*
G01X-18174Y1131601D02*
X-18435D01*
G01X-18174Y1132509D02*
X-18435D01*
G01X-15985Y1132531D02*
X-16213D01*
G01X-14449Y1132547D02*
X-14677D01*
G01X12410Y1132646D02*
X315D01*
G01X-13009Y1132843D02*
X-14147D01*
G01X512Y1133236D02*
X0D01*
G01X512Y1134024D02*
X0D01*
G01X-13009Y1134417D02*
X-14147D01*
G01X12410Y1134614D02*
X315D01*
G01X-14449Y1134713D02*
X-14677D01*
G01X-15985Y1134729D02*
X-16213D01*
G01X-18174Y1134750D02*
X-18435D01*
G01X-18174Y1135659D02*
X-18435D01*
G01X-15985Y1135680D02*
X-16213D01*
G01X-14449Y1135697D02*
X-14677D01*
G01X12410Y1135795D02*
X315D01*
G01X-13009Y1135992D02*
X-14147D01*
G01X512Y1136386D02*
X0D01*
G01X512Y1137173D02*
X0D01*
G01X-13009Y1137567D02*
X-14147D01*
G01X12410Y1137764D02*
X315D01*
G01X-14449Y1137862D02*
X-14677D01*
G01X-15985Y1137878D02*
X-16213D01*
G01X-18174Y1137900D02*
X-18435D01*
G01X-18174Y1138808D02*
X-18435D01*
G01X-15985Y1138830D02*
X-16213D01*
G01X-14449Y1138846D02*
X-14677D01*
G01X-19469Y1125316D02*
X-20801Y1125328D01*
G01X-15985Y1125280D02*
X-18435Y1125302D01*
G01X-19469Y1128466D02*
X-20801Y1128478D01*
G01X-15985Y1128430D02*
X-18435Y1128451D01*
G01X-19469Y1131615D02*
X-20801Y1131627D01*
G01X-15985Y1131579D02*
X-18435Y1131601D01*
G01X-19469Y1134765D02*
X-20801Y1134777D01*
G01X-15985Y1134729D02*
X-18435Y1134750D01*
G01X-19469Y1137915D02*
X-20801Y1137926D01*
G01X-15985Y1137878D02*
X-18435Y1137900D01*
G01X-15985Y1128430D02*
X-14449Y1128413D01*
G01X-15985Y1131579D02*
X-14449Y1131563D01*
G01X-15985Y1134729D02*
X-14449Y1134713D01*
G01X-15985Y1137878D02*
X-14449Y1137862D01*
G01X-18435Y1125302D02*
X-20801Y1125328D01*
G01X-18435Y1128451D02*
X-20801Y1128478D01*
G01X-18435Y1131601D02*
X-20801Y1131627D01*
G01X-18435Y1134750D02*
X-20801Y1134777D01*
G01X-18435Y1137900D02*
X-20801Y1137926D01*
G01X-19469Y1125316D02*
X-16213Y1125280D01*
G01X-19469Y1128466D02*
X-16213Y1128430D01*
G01X-18174Y1128451D02*
X-14677Y1128413D01*
G01X-19469Y1131615D02*
X-16213Y1131579D01*
G01X-18174Y1131601D02*
X-14677Y1131563D01*
G01X-19469Y1134765D02*
X-16213Y1134729D01*
G01X-18174Y1134750D02*
X-14677Y1134713D01*
G01X-19469Y1137915D02*
X-16213Y1137878D01*
G01X-18174Y1137900D02*
X-14677Y1137862D01*
G01X-20801Y1119885D02*
Y1119029D01*
G01Y1123034D02*
Y1122178D01*
G01Y1116735D02*
Y1115879D01*
G01Y1113585D02*
Y1112730D01*
G01Y1107286D02*
Y1106430D01*
G01Y1110436D02*
Y1109580D01*
G01X-19469Y1119891D02*
Y1119023D01*
G01Y1123040D02*
Y1122172D01*
G01Y1116741D02*
Y1115873D01*
G01Y1113591D02*
Y1112724D01*
G01Y1107292D02*
Y1106424D01*
G01Y1110442D02*
Y1109574D01*
G01X-18435Y1119911D02*
Y1119002D01*
G01Y1123060D02*
Y1122152D01*
G01Y1116761D02*
Y1115853D01*
G01Y1113611D02*
Y1112703D01*
G01Y1107312D02*
Y1106404D01*
G01Y1110462D02*
Y1109554D01*
G01X-18174Y1119911D02*
Y1119002D01*
G01Y1123060D02*
Y1122152D01*
G01Y1116761D02*
Y1115853D01*
G01Y1113611D02*
Y1112703D01*
G01Y1107312D02*
Y1106404D01*
G01Y1110462D02*
Y1109554D01*
G01X-16213Y1119932D02*
Y1118981D01*
G01Y1123082D02*
Y1122130D01*
G01Y1116783D02*
Y1115831D01*
G01Y1110483D02*
Y1109532D01*
G01Y1113633D02*
Y1112681D01*
G01Y1107334D02*
Y1106382D01*
G01X-15985Y1119932D02*
Y1118981D01*
G01Y1123082D02*
Y1122130D01*
G01Y1116783D02*
Y1115831D01*
G01Y1110483D02*
Y1109532D01*
G01Y1113633D02*
Y1112681D01*
G01Y1107334D02*
Y1106382D01*
G01X-14537Y1126336D02*
Y1125176D01*
G01Y1120037D02*
Y1118877D01*
G01Y1123186D02*
Y1122026D01*
G01Y1116887D02*
Y1115727D01*
G01Y1110588D02*
Y1109428D01*
G01Y1113737D02*
Y1112578D01*
G01Y1107438D02*
Y1106278D01*
G01X-13009Y1126543D02*
Y1124969D01*
G01Y1120244D02*
Y1118669D01*
G01Y1123394D02*
Y1121819D01*
G01Y1117094D02*
Y1115520D01*
G01Y1110795D02*
Y1109220D01*
G01Y1113945D02*
Y1112370D01*
G01Y1107646D02*
Y1106071D01*
G01X315Y1125165D02*
Y1124575D01*
G01Y1120638D02*
Y1120047D01*
G01Y1123787D02*
Y1123197D01*
G01Y1122016D02*
Y1121425D01*
G01Y1117488D02*
Y1116898D01*
G01Y1115717D02*
Y1115126D01*
G01Y1118866D02*
Y1118276D01*
G01Y1111189D02*
Y1110598D01*
G01Y1114339D02*
Y1113748D01*
G01Y1112567D02*
Y1111976D01*
G01Y1108039D02*
Y1107449D01*
G01Y1106268D02*
Y1105677D01*
G01Y1109417D02*
Y1108827D01*
G01X512Y1125165D02*
Y1124575D01*
G01Y1120638D02*
Y1120047D01*
G01Y1123787D02*
Y1123197D01*
G01Y1122016D02*
Y1121425D01*
G01Y1117488D02*
Y1116898D01*
G01Y1115717D02*
Y1115126D01*
G01Y1118866D02*
Y1118276D01*
G01Y1111189D02*
Y1110598D01*
G01Y1114339D02*
Y1113748D01*
G01Y1112567D02*
Y1111976D01*
G01Y1108039D02*
Y1107449D01*
G01Y1106268D02*
Y1105677D01*
G01Y1109417D02*
Y1108827D01*
G01X709Y1126346D02*
Y1125165D01*
G01Y1120047D02*
Y1118866D01*
G01Y1123197D02*
Y1122016D01*
G01Y1116898D02*
Y1115717D01*
G01Y1110598D02*
Y1109417D01*
G01Y1113748D02*
Y1112567D01*
G01Y1107449D02*
Y1106268D01*
G01X1074Y1126346D02*
Y1125165D01*
G01Y1120047D02*
Y1118866D01*
G01Y1123197D02*
Y1122016D01*
G01Y1116898D02*
Y1115717D01*
G01Y1110598D02*
Y1109417D01*
G01Y1113748D02*
Y1112567D01*
G01Y1107449D02*
Y1106268D01*
G01X1184Y1126346D02*
Y1125165D01*
G01Y1120047D02*
Y1118866D01*
G01Y1123197D02*
Y1122016D01*
G01Y1116898D02*
Y1115717D01*
G01Y1110598D02*
Y1109417D01*
G01Y1113748D02*
Y1112567D01*
G01Y1107449D02*
Y1106268D01*
G01X9965Y1126346D02*
Y1125165D01*
G01Y1120047D02*
Y1118866D01*
G01Y1123197D02*
Y1122016D01*
G01Y1116898D02*
Y1115717D01*
G01Y1110598D02*
Y1109417D01*
G01Y1113748D02*
Y1112567D01*
G01Y1107449D02*
Y1106268D01*
G01X10075Y1126346D02*
Y1125165D01*
G01Y1120047D02*
Y1118866D01*
G01Y1123197D02*
Y1122016D01*
G01Y1116898D02*
Y1115717D01*
G01Y1110598D02*
Y1109417D01*
G01Y1113748D02*
Y1112567D01*
G01Y1107449D02*
Y1106268D01*
G01X-14537Y1123186D02*
X-14677Y1123098D01*
G01X-13977Y1123394D02*
X-14449Y1123098D01*
G01X-14537Y1120037D02*
X-14677Y1119949D01*
G01X-13977Y1120244D02*
X-14449Y1119949D01*
G01X-14537Y1116887D02*
X-14677Y1116799D01*
G01X-13977Y1117094D02*
X-14449Y1116799D01*
G01X-14537Y1113737D02*
X-14677Y1113650D01*
G01X-13977Y1113945D02*
X-14449Y1113650D01*
G01X-14537Y1110588D02*
X-14677Y1110500D01*
G01X-13977Y1110795D02*
X-14449Y1110500D01*
G01X-14537Y1107438D02*
X-14677Y1107350D01*
G01X-13977Y1107646D02*
X-14449Y1107350D01*
G01X-14147Y1123394D02*
X-14537Y1123186D01*
G01X-14147Y1120244D02*
X-14537Y1120037D01*
G01X-14147Y1117094D02*
X-14537Y1116887D01*
G01X-14147Y1113945D02*
X-14537Y1113737D01*
G01X-14147Y1110795D02*
X-14537Y1110588D01*
G01X-14147Y1107646D02*
X-14537Y1107438D01*
G01Y1106278D02*
X-14147Y1106071D01*
G01X-14537Y1109428D02*
X-14147Y1109220D01*
G01X-14537Y1112578D02*
X-14147Y1112370D01*
G01X-14677Y1106366D02*
X-14537Y1106278D01*
G01X-14449Y1106366D02*
X-13977Y1106071D01*
G01X-14677Y1109516D02*
X-14537Y1109428D01*
G01X-14449Y1109516D02*
X-13977Y1109220D01*
G01X-14677Y1112665D02*
X-14537Y1112578D01*
G01X-14449Y1112665D02*
X-13977Y1112370D01*
G01X-14677Y1115815D02*
X-14537Y1115727D01*
G01X-14449Y1115815D02*
X-13977Y1115520D01*
G01X-14677Y1118965D02*
X-14537Y1118877D01*
G01X-14449Y1118965D02*
X-13977Y1118669D01*
G01X-14677Y1122114D02*
X-14537Y1122026D01*
G01X-14449Y1122114D02*
X-13977Y1121819D01*
G01X-14677Y1125264D02*
X-14537Y1125176D01*
G01X-14449Y1125264D02*
X-13977Y1124969D01*
G01X-14537Y1115727D02*
X-14147Y1115520D01*
G01X-14537Y1118877D02*
X-14147Y1118669D01*
G01X-14537Y1122026D02*
X-14147Y1121819D01*
G01X-14537Y1125176D02*
X-14147Y1124969D01*
G01X-19469Y1107298D02*
X-18174Y1107312D01*
G01X-18435D02*
X-20801Y1107286D01*
G01X-18174Y1107312D02*
X-17126Y1107324D01*
G01X-19469Y1110448D02*
X-18174Y1110462D01*
G01X-18435D02*
X-20801Y1110436D01*
G01X-18174Y1110462D02*
X-17126Y1110473D01*
G01X-19469Y1113597D02*
X-18174Y1113611D01*
G01X-18435D02*
X-20801Y1113585D01*
G01X-18174Y1113611D02*
X-17126Y1113623D01*
G01X-19469Y1116747D02*
X-18174Y1116761D01*
G01X-18435D02*
X-20801Y1116735D01*
G01X-18174Y1116761D02*
X-17126Y1116772D01*
G01X-19469Y1119896D02*
X-18174Y1119911D01*
G01X-18435D02*
X-20801Y1119885D01*
G01X-18174Y1119911D02*
X-17126Y1119922D01*
G01X-19469Y1123046D02*
X-18174Y1123060D01*
G01X-18435D02*
X-20801Y1123034D01*
G01X-18174Y1123060D02*
X-17126Y1123072D01*
G01X-15985Y1107334D02*
X-14449Y1107350D01*
G01X-14677D02*
X-18174Y1107312D01*
G01X-14677Y1107350D02*
X-16213Y1107334D01*
G01X-15985Y1110483D02*
X-14449Y1110500D01*
G01X-14677D02*
X-18174Y1110462D01*
G01X-14677Y1110500D02*
X-16213Y1110483D01*
G01X-15985Y1113633D02*
X-14449Y1113650D01*
G01X-14677D02*
X-18174Y1113611D01*
G01X-14677Y1113650D02*
X-16213Y1113633D01*
G01X-15985Y1116783D02*
X-14449Y1116799D01*
G01X-14677D02*
X-18174Y1116761D01*
G01X-14677Y1116799D02*
X-16213Y1116783D01*
G01X-15985Y1119932D02*
X-14449Y1119949D01*
G01X-14677D02*
X-18174Y1119911D01*
G01X-14677Y1119949D02*
X-16213Y1119932D01*
G01X-15985Y1123082D02*
X-14449Y1123098D01*
G01X-14677D02*
X-18174Y1123060D01*
G01X-14677Y1123098D02*
X-16213Y1123082D01*
G01X-19469Y1107298D02*
X-20801Y1107286D01*
G01X-19469Y1110448D02*
X-20801Y1110436D01*
G01X-19469Y1113597D02*
X-20801Y1113585D01*
G01X-19469Y1116747D02*
X-20801Y1116735D01*
G01X-19469Y1119896D02*
X-20801Y1119885D01*
G01X-19469Y1123046D02*
X-20801Y1123034D01*
G01X-15985Y1107334D02*
X-17126Y1107324D01*
G01D02*
X-18435Y1107312D01*
G01X-15985Y1110483D02*
X-17126Y1110473D01*
G01D02*
X-18435Y1110462D01*
G01X-15985Y1113633D02*
X-17126Y1113623D01*
G01D02*
X-18435Y1113611D01*
G01X-15985Y1116783D02*
X-17126Y1116772D01*
G01D02*
X-18435Y1116761D01*
G01X-15985Y1119932D02*
X-17126Y1119922D01*
G01D02*
X-18435Y1119911D01*
G01X-15985Y1123082D02*
X-17126Y1123072D01*
G01D02*
X-18435Y1123060D01*
G01X512Y1105677D02*
X0D01*
G01X-13009Y1106071D02*
X-14147D01*
G01X12410Y1106268D02*
X315D01*
G01X-14449Y1106366D02*
X-14677D01*
G01X-15985Y1106382D02*
X-16213D01*
G01X-18174Y1106404D02*
X-18435D01*
G01X-18174Y1107312D02*
X-18435D01*
G01X-15985Y1107334D02*
X-16213D01*
G01X-14449Y1107350D02*
X-14677D01*
G01X12410Y1107449D02*
X315D01*
G01X-13009Y1107646D02*
X-14147D01*
G01X512Y1108039D02*
X0D01*
G01X512Y1108827D02*
X0D01*
G01X-13009Y1109220D02*
X-14147D01*
G01X12410Y1109417D02*
X315D01*
G01X-14449Y1109516D02*
X-14677D01*
G01X-15985Y1109532D02*
X-16213D01*
G01X-18174Y1109554D02*
X-18435D01*
G01X-18174Y1110462D02*
X-18435D01*
G01X-15985Y1110483D02*
X-16213D01*
G01X-14449Y1110500D02*
X-14677D01*
G01X12410Y1110598D02*
X315D01*
G01X-13009Y1110795D02*
X-14147D01*
G01X512Y1111189D02*
X0D01*
G01X512Y1111976D02*
X0D01*
G01X-13009Y1112370D02*
X-14147D01*
G01X12410Y1112567D02*
X315D01*
G01X-14449Y1112665D02*
X-14677D01*
G01X-15985Y1112681D02*
X-16213D01*
G01X-18174Y1112703D02*
X-18435D01*
G01X-18174Y1113611D02*
X-18435D01*
G01X-16213Y1113633D02*
X-15985D01*
G01X-14449Y1113650D02*
X-14677D01*
G01X12410Y1113748D02*
X315D01*
G01X-13009Y1113945D02*
X-14147D01*
G01X512Y1114339D02*
X0D01*
G01X512Y1115126D02*
X0D01*
G01X-13009Y1115520D02*
X-14147D01*
G01X12410Y1115717D02*
X315D01*
G01X-14449Y1115815D02*
X-14677D01*
G01X-15985Y1115831D02*
X-16213D01*
G01X-18174Y1115853D02*
X-18435D01*
G01X-18174Y1116761D02*
X-18435D01*
G01X-15985Y1116783D02*
X-16213D01*
G01X-14449Y1116799D02*
X-14677D01*
G01X12410Y1116898D02*
X315D01*
G01X-13009Y1117094D02*
X-14147D01*
G01X512Y1117488D02*
X0D01*
G01X512Y1118276D02*
X0D01*
G01X-13009Y1118669D02*
X-14147D01*
G01X12410Y1118866D02*
X315D01*
G01X-14449Y1118965D02*
X-14677D01*
G01X-15985Y1118981D02*
X-16213D01*
G01X-18174Y1119002D02*
X-18435D01*
G01X-18174Y1119911D02*
X-18435D01*
G01X-15985Y1119932D02*
X-16213D01*
G01X-14449Y1119949D02*
X-14677D01*
G01X12410Y1120047D02*
X315D01*
G01X-13009Y1120244D02*
X-14147D01*
G01X512Y1120638D02*
X0D01*
G01X512Y1121425D02*
X0D01*
G01X-13009Y1121819D02*
X-14147D01*
G01X12410Y1122016D02*
X315D01*
G01X-14449Y1122114D02*
X-14677D01*
G01X-15985Y1122130D02*
X-16213D01*
G01X-18174Y1122152D02*
X-18435D01*
G01X-18174Y1123060D02*
X-18435D01*
G01X-15985Y1123082D02*
X-16213D01*
G01X-14449Y1123098D02*
X-14677D01*
G01X12410Y1123197D02*
X315D01*
G01X-13009Y1123394D02*
X-14147D01*
G01X512Y1123787D02*
X0D01*
G01X512Y1124575D02*
X0D01*
G01X-13009Y1124969D02*
X-14147D01*
G01X12410Y1125165D02*
X315D01*
G01X-14449Y1125264D02*
X-14677D01*
G01X-19469Y1106419D02*
X-20801Y1106430D01*
G01X-15985Y1106382D02*
X-18435Y1106404D01*
G01X-19469Y1109568D02*
X-20801Y1109580D01*
G01X-15985Y1109532D02*
X-18435Y1109554D01*
G01X-19469Y1112718D02*
X-20801Y1112730D01*
G01X-15985Y1112681D02*
X-18435Y1112703D01*
G01X-19469Y1115867D02*
X-20801Y1115879D01*
G01X-15985Y1115831D02*
X-18435Y1115853D01*
G01X-19469Y1119017D02*
X-20801Y1119029D01*
G01X-15985Y1118981D02*
X-18435Y1119002D01*
G01X-19469Y1122167D02*
X-20801Y1122178D01*
G01X-15985Y1122130D02*
X-18435Y1122152D01*
G01X-15985Y1106382D02*
X-14449Y1106366D01*
G01X-15985Y1109532D02*
X-14449Y1109516D01*
G01X-15985Y1112681D02*
X-14449Y1112665D01*
G01X-15985Y1115831D02*
X-14449Y1115815D01*
G01X-15985Y1118981D02*
X-14449Y1118965D01*
G01X-15985Y1122130D02*
X-14449Y1122114D01*
G01X-15985Y1125280D02*
X-14449Y1125264D01*
G01X-18435Y1106404D02*
X-20801Y1106430D01*
G01X-18435Y1109554D02*
X-20801Y1109580D01*
G01X-18435Y1112703D02*
X-20801Y1112730D01*
G01X-18435Y1115853D02*
X-20801Y1115879D01*
G01X-18435Y1119002D02*
X-20801Y1119029D01*
G01X-18435Y1122152D02*
X-20801Y1122178D01*
G01X-19469Y1106419D02*
X-16213Y1106382D01*
G01X-18174Y1106404D02*
X-14677Y1106366D01*
G01X-19469Y1109568D02*
X-16213Y1109532D01*
G01X-18174Y1109554D02*
X-14677Y1109516D01*
G01X-19469Y1112718D02*
X-16213Y1112681D01*
G01X-18174Y1112703D02*
X-14677Y1112665D01*
G01X-19469Y1115867D02*
X-16213Y1115831D01*
G01X-18174Y1115853D02*
X-14677Y1115815D01*
G01X-19469Y1119017D02*
X-16213Y1118981D01*
G01X-18174Y1119002D02*
X-14677Y1118965D01*
G01X-19469Y1122167D02*
X-16213Y1122130D01*
G01X-18174Y1122152D02*
X-14677Y1122114D01*
G01X-18174Y1125302D02*
X-14677Y1125264D01*
G01X12057Y1211386D02*
Y1210205D01*
G01Y1205087D02*
Y1203906D01*
G01Y1208236D02*
Y1207055D01*
G01Y1201937D02*
Y1200756D01*
G01Y1195638D02*
Y1194457D01*
G01Y1198787D02*
Y1197606D01*
G01Y1192488D02*
Y1191307D01*
G01Y1189339D02*
Y1188157D01*
G01X12410Y1211386D02*
Y1210205D01*
G01Y1205087D02*
Y1203906D01*
G01Y1208236D02*
Y1207055D01*
G01Y1201937D02*
Y1200756D01*
G01Y1195638D02*
Y1194457D01*
G01Y1198787D02*
Y1197606D01*
G01Y1192488D02*
Y1191307D01*
G01Y1189339D02*
Y1188157D01*
G01X13353Y1211130D02*
Y1210461D01*
G01Y1204831D02*
Y1204161D01*
G01Y1207980D02*
Y1207311D01*
G01Y1201681D02*
Y1201012D01*
G01Y1195382D02*
Y1194713D01*
G01Y1198531D02*
Y1197862D01*
G01Y1192232D02*
Y1191563D01*
G01Y1189083D02*
Y1188413D01*
G01X13701Y1211130D02*
Y1210461D01*
G01Y1204831D02*
Y1204161D01*
G01Y1207980D02*
Y1207311D01*
G01Y1201681D02*
Y1201012D01*
G01Y1195382D02*
Y1194713D01*
G01Y1198531D02*
Y1197862D01*
G01Y1192232D02*
Y1191563D01*
G01Y1189083D02*
Y1188413D01*
G01X12634Y1210461D02*
X12416Y1210191D01*
G01X12634Y1207311D02*
X12416Y1207041D01*
G01X12634Y1204161D02*
X12416Y1203891D01*
G01X12634Y1201012D02*
X12416Y1200742D01*
G01X12634Y1197862D02*
X12416Y1197592D01*
G01X12634Y1194713D02*
X12416Y1194443D01*
G01X12634Y1191563D02*
X12416Y1191293D01*
G01X12634Y1188413D02*
X12416Y1188143D01*
G01X12287Y1210461D02*
X12057Y1210205D01*
G01X12287Y1207311D02*
X12057Y1207055D01*
G01X12287Y1204161D02*
X12057Y1203906D01*
G01X12287Y1201012D02*
X12057Y1200756D01*
G01X12287Y1197862D02*
X12057Y1197606D01*
G01X12287Y1194713D02*
X12057Y1194457D01*
G01X12287Y1191563D02*
X12057Y1191307D01*
G01X12287Y1188413D02*
X12057Y1188157D01*
G01Y1186189D02*
X12287Y1185933D01*
G01X12057Y1189339D02*
X12287Y1189083D01*
G01X12057Y1192488D02*
X12287Y1192232D01*
G01X12057Y1195638D02*
X12287Y1195382D01*
G01X12057Y1198787D02*
X12287Y1198531D01*
G01X12057Y1201937D02*
X12287Y1201681D01*
G01X12057Y1205087D02*
X12287Y1204831D01*
G01X12057Y1208236D02*
X12287Y1207980D01*
G01X12057Y1211386D02*
X12287Y1211130D01*
G01X12416Y1186203D02*
X12634Y1185933D01*
G01X12416Y1189353D02*
X12634Y1189083D01*
G01X12416Y1192502D02*
X12634Y1192232D01*
G01X12416Y1195652D02*
X12634Y1195382D01*
G01X12416Y1198802D02*
X12634Y1198531D01*
G01X12416Y1201951D02*
X12634Y1201681D01*
G01X12416Y1205101D02*
X12634Y1204831D01*
G01X12416Y1208250D02*
X12634Y1207980D01*
G01X12416Y1211400D02*
X12634Y1211130D01*
G01X13701Y1185933D02*
X12287D01*
G01X13701Y1188413D02*
X12287D01*
G01X13701Y1189083D02*
X12287D01*
G01X13701Y1191563D02*
X12287D01*
G01X13701Y1192232D02*
X12287D01*
G01X13701Y1194713D02*
X12287D01*
G01X13701Y1195382D02*
X12287D01*
G01X13701Y1197862D02*
X12287D01*
G01X13701Y1198531D02*
X12287D01*
G01X13701Y1201012D02*
X12287D01*
G01X13701Y1201681D02*
X12287D01*
G01X13701Y1204161D02*
X12287D01*
G01X13701Y1204831D02*
X12287D01*
G01X13701Y1207311D02*
X12287D01*
G01X13701Y1207980D02*
X12287D01*
G01X13701Y1210461D02*
X12287D01*
G01X13701Y1211130D02*
X12287D01*
G01X12057Y1186189D02*
Y1185008D01*
G01Y1183039D02*
Y1181858D01*
G01Y1176740D02*
Y1175559D01*
G01Y1179890D02*
Y1178709D01*
G01Y1173591D02*
Y1172409D01*
G01Y1167291D02*
Y1166110D01*
G01Y1170441D02*
Y1169260D01*
G01Y1164142D02*
Y1162961D01*
G01Y1157843D02*
Y1156661D01*
G01Y1160992D02*
Y1159811D01*
G01Y1154693D02*
Y1153512D01*
G01Y1148394D02*
Y1147213D01*
G01Y1151543D02*
Y1150362D01*
G01Y1145244D02*
Y1144063D01*
G01Y1142094D02*
Y1140913D01*
G01X12410Y1186189D02*
Y1185008D01*
G01Y1183039D02*
Y1181858D01*
G01Y1176740D02*
Y1175559D01*
G01Y1179890D02*
Y1178709D01*
G01Y1173591D02*
Y1172409D01*
G01Y1167291D02*
Y1166110D01*
G01Y1170441D02*
Y1169260D01*
G01Y1164142D02*
Y1162961D01*
G01Y1157843D02*
Y1156661D01*
G01Y1160992D02*
Y1159811D01*
G01Y1154693D02*
Y1153512D01*
G01Y1148394D02*
Y1147213D01*
G01Y1151543D02*
Y1150362D01*
G01Y1145244D02*
Y1144063D01*
G01Y1142094D02*
Y1140913D01*
G01X13353Y1185933D02*
Y1185264D01*
G01Y1182783D02*
Y1182114D01*
G01Y1176484D02*
Y1175815D01*
G01Y1179634D02*
Y1178965D01*
G01Y1173335D02*
Y1172665D01*
G01Y1167035D02*
Y1166366D01*
G01Y1170185D02*
Y1169516D01*
G01Y1163886D02*
Y1163217D01*
G01Y1157587D02*
Y1156917D01*
G01Y1160736D02*
Y1160067D01*
G01Y1154437D02*
Y1153768D01*
G01Y1148138D02*
Y1147469D01*
G01Y1151287D02*
Y1150618D01*
G01Y1144988D02*
Y1144319D01*
G01Y1141839D02*
Y1141169D01*
G01X13701Y1185933D02*
Y1185264D01*
G01Y1182783D02*
Y1182114D01*
G01Y1176484D02*
Y1175815D01*
G01Y1179634D02*
Y1178965D01*
G01Y1173335D02*
Y1172665D01*
G01Y1167035D02*
Y1166366D01*
G01Y1170185D02*
Y1169516D01*
G01Y1163886D02*
Y1163217D01*
G01Y1157587D02*
Y1156917D01*
G01Y1160736D02*
Y1160067D01*
G01Y1154437D02*
Y1153768D01*
G01Y1148138D02*
Y1147469D01*
G01Y1151287D02*
Y1150618D01*
G01Y1144988D02*
Y1144319D01*
G01Y1141839D02*
Y1141169D01*
G01X12634Y1185264D02*
X12416Y1184994D01*
G01X12634Y1182114D02*
X12416Y1181844D01*
G01X12634Y1178965D02*
X12416Y1178694D01*
G01X12634Y1175815D02*
X12416Y1175545D01*
G01X12634Y1172665D02*
X12416Y1172395D01*
G01X12634Y1169516D02*
X12416Y1169246D01*
G01X12634Y1166366D02*
X12416Y1166096D01*
G01X12634Y1163217D02*
X12416Y1162946D01*
G01X12634Y1160067D02*
X12416Y1159797D01*
G01X12634Y1156917D02*
X12416Y1156647D01*
G01X12634Y1153768D02*
X12416Y1153498D01*
G01X12634Y1150618D02*
X12416Y1150348D01*
G01X12634Y1147469D02*
X12416Y1147198D01*
G01X12634Y1144319D02*
X12416Y1144049D01*
G01X12634Y1141169D02*
X12416Y1140899D01*
G01X12287Y1185264D02*
X12057Y1185008D01*
G01X12287Y1182114D02*
X12057Y1181858D01*
G01X12287Y1178965D02*
X12057Y1178709D01*
G01X12287Y1175815D02*
X12057Y1175559D01*
G01X12287Y1172665D02*
X12057Y1172409D01*
G01X12287Y1169516D02*
X12057Y1169260D01*
G01X12287Y1166366D02*
X12057Y1166110D01*
G01X12287Y1163217D02*
X12057Y1162961D01*
G01X12287Y1160067D02*
X12057Y1159811D01*
G01X12287Y1156917D02*
X12057Y1156661D01*
G01X12287Y1153768D02*
X12057Y1153512D01*
G01X12287Y1150618D02*
X12057Y1150362D01*
G01X12287Y1147469D02*
X12057Y1147213D01*
G01X12287Y1144319D02*
X12057Y1144063D01*
G01X12287Y1141169D02*
X12057Y1140913D01*
G01Y1142094D02*
X12287Y1141839D01*
G01X12057Y1145244D02*
X12287Y1144988D01*
G01X12057Y1148394D02*
X12287Y1148138D01*
G01X12057Y1151543D02*
X12287Y1151287D01*
G01X12057Y1154693D02*
X12287Y1154437D01*
G01X12057Y1157843D02*
X12287Y1157587D01*
G01X12057Y1160992D02*
X12287Y1160736D01*
G01X12057Y1164142D02*
X12287Y1163886D01*
G01X12057Y1167291D02*
X12287Y1167035D01*
G01X12057Y1170441D02*
X12287Y1170185D01*
G01X12057Y1173591D02*
X12287Y1173335D01*
G01X12057Y1176740D02*
X12287Y1176484D01*
G01X12057Y1179890D02*
X12287Y1179634D01*
G01X12057Y1183039D02*
X12287Y1182783D01*
G01X12416Y1142109D02*
X12634Y1141839D01*
G01X12416Y1145258D02*
X12634Y1144988D01*
G01X12416Y1148408D02*
X12634Y1148138D01*
G01X12416Y1151557D02*
X12634Y1151287D01*
G01X12416Y1154707D02*
X12634Y1154437D01*
G01X12416Y1157857D02*
X12634Y1157587D01*
G01X12416Y1161006D02*
X12634Y1160736D01*
G01X12416Y1164156D02*
X12634Y1163886D01*
G01X12416Y1167306D02*
X12634Y1167035D01*
G01X12416Y1170455D02*
X12634Y1170185D01*
G01X12416Y1173605D02*
X12634Y1173335D01*
G01X12416Y1176754D02*
X12634Y1176484D01*
G01X12416Y1179904D02*
X12634Y1179634D01*
G01X12416Y1183054D02*
X12634Y1182783D01*
G01X13701Y1141169D02*
X12287D01*
G01X13701Y1141839D02*
X12287D01*
G01X13701Y1144319D02*
X12287D01*
G01X13701Y1144988D02*
X12287D01*
G01X13701Y1147469D02*
X12287D01*
G01X13701Y1148138D02*
X12287D01*
G01X13701Y1150618D02*
X12287D01*
G01X13701Y1151287D02*
X12287D01*
G01X13701Y1153768D02*
X12287D01*
G01X13701Y1154437D02*
X12287D01*
G01X13701Y1156917D02*
X12287D01*
G01X13701Y1157587D02*
X12287D01*
G01X13701Y1160067D02*
X12287D01*
G01X13701Y1160736D02*
X12287D01*
G01X13701Y1163217D02*
X12287D01*
G01X13701Y1163886D02*
X12287D01*
G01X13701Y1166366D02*
X12287D01*
G01X13701Y1167035D02*
X12287D01*
G01X13701Y1169516D02*
X12287D01*
G01X13701Y1170185D02*
X12287D01*
G01X13701Y1172665D02*
X12287D01*
G01X13701Y1173335D02*
X12287D01*
G01X13701Y1175815D02*
X12287D01*
G01X13701Y1176484D02*
X12287D01*
G01X13701Y1178965D02*
X12287D01*
G01X13701Y1179634D02*
X12287D01*
G01X13701Y1182114D02*
X12287D01*
G01X13701Y1182783D02*
X12287D01*
G01X13701Y1185264D02*
X12287D01*
G01X-20801Y1211223D02*
Y1210367D01*
G01Y1204924D02*
Y1204068D01*
G01Y1208074D02*
Y1207218D01*
G01Y1201774D02*
Y1200919D01*
G01Y1195475D02*
Y1194619D01*
G01Y1198625D02*
Y1197769D01*
G01Y1192326D02*
Y1191470D01*
G01Y1189176D02*
Y1188320D01*
G01X-19469Y1211229D02*
Y1210361D01*
G01Y1204930D02*
Y1204062D01*
G01Y1208080D02*
Y1207212D01*
G01Y1201780D02*
Y1200913D01*
G01Y1195481D02*
Y1194613D01*
G01Y1198631D02*
Y1197763D01*
G01Y1192331D02*
Y1191464D01*
G01Y1189182D02*
Y1188314D01*
G01X-18435Y1211249D02*
Y1210341D01*
G01Y1204950D02*
Y1204042D01*
G01Y1208100D02*
Y1207191D01*
G01Y1201800D02*
Y1200892D01*
G01Y1195501D02*
Y1194593D01*
G01Y1198651D02*
Y1197743D01*
G01Y1192352D02*
Y1191443D01*
G01Y1189202D02*
Y1188294D01*
G01X-18174Y1211249D02*
Y1210341D01*
G01Y1204950D02*
Y1204042D01*
G01Y1208100D02*
Y1207191D01*
G01Y1201800D02*
Y1200892D01*
G01Y1195501D02*
Y1194593D01*
G01Y1198651D02*
Y1197743D01*
G01Y1192352D02*
Y1191443D01*
G01Y1189202D02*
Y1188294D01*
G01X-16213Y1211271D02*
Y1210319D01*
G01Y1204972D02*
Y1204020D01*
G01Y1208121D02*
Y1207170D01*
G01Y1201822D02*
Y1200870D01*
G01Y1195523D02*
Y1194571D01*
G01Y1198672D02*
Y1197721D01*
G01Y1192373D02*
Y1191422D01*
G01Y1189224D02*
Y1188272D01*
G01X-15985Y1211271D02*
Y1210319D01*
G01Y1204972D02*
Y1204020D01*
G01Y1208121D02*
Y1207170D01*
G01Y1201822D02*
Y1200870D01*
G01Y1195523D02*
Y1194571D01*
G01Y1198672D02*
Y1197721D01*
G01Y1192373D02*
Y1191422D01*
G01Y1189224D02*
Y1188272D01*
G01X-14537Y1211375D02*
Y1210215D01*
G01Y1205076D02*
Y1203916D01*
G01Y1208226D02*
Y1207066D01*
G01Y1201926D02*
Y1200767D01*
G01Y1195627D02*
Y1194467D01*
G01Y1198777D02*
Y1197617D01*
G01Y1192478D02*
Y1191318D01*
G01Y1189328D02*
Y1188168D01*
G01X-13009Y1211583D02*
Y1210008D01*
G01Y1205283D02*
Y1203709D01*
G01Y1208433D02*
Y1206858D01*
G01Y1202134D02*
Y1200559D01*
G01Y1195835D02*
Y1194260D01*
G01Y1198984D02*
Y1197409D01*
G01Y1192685D02*
Y1191110D01*
G01Y1189535D02*
Y1187961D01*
G01X315Y1208827D02*
Y1208236D01*
G01Y1211976D02*
Y1211386D01*
G01Y1210205D02*
Y1209614D01*
G01Y1205677D02*
Y1205087D01*
G01Y1207055D02*
Y1206465D01*
G01Y1202528D02*
Y1201937D01*
G01Y1200756D02*
Y1200165D01*
G01Y1203906D02*
Y1203315D01*
G01Y1196228D02*
Y1195638D01*
G01Y1199378D02*
Y1198787D01*
G01Y1197606D02*
Y1197016D01*
G01Y1193079D02*
Y1192488D01*
G01Y1191307D02*
Y1190717D01*
G01Y1194457D02*
Y1193866D01*
G01Y1186780D02*
Y1186189D01*
G01Y1189929D02*
Y1189339D01*
G01Y1188157D02*
Y1187567D01*
G01X512Y1208827D02*
Y1208236D01*
G01Y1211976D02*
Y1211386D01*
G01Y1210205D02*
Y1209614D01*
G01Y1205677D02*
Y1205087D01*
G01Y1207055D02*
Y1206465D01*
G01Y1202528D02*
Y1201937D01*
G01Y1200756D02*
Y1200165D01*
G01Y1203906D02*
Y1203315D01*
G01Y1196228D02*
Y1195638D01*
G01Y1199378D02*
Y1198787D01*
G01Y1197606D02*
Y1197016D01*
G01Y1193079D02*
Y1192488D01*
G01Y1191307D02*
Y1190717D01*
G01Y1194457D02*
Y1193866D01*
G01Y1186780D02*
Y1186189D01*
G01Y1189929D02*
Y1189339D01*
G01Y1188157D02*
Y1187567D01*
G01X709Y1211386D02*
Y1210205D01*
G01Y1205087D02*
Y1203906D01*
G01Y1208236D02*
Y1207055D01*
G01Y1201937D02*
Y1200756D01*
G01Y1195638D02*
Y1194457D01*
G01Y1198787D02*
Y1197606D01*
G01Y1192488D02*
Y1191307D01*
G01Y1189339D02*
Y1188157D01*
G01X1074Y1211386D02*
Y1210205D01*
G01Y1205087D02*
Y1203906D01*
G01Y1208236D02*
Y1207055D01*
G01Y1201937D02*
Y1200756D01*
G01Y1195638D02*
Y1194457D01*
G01Y1198787D02*
Y1197606D01*
G01Y1192488D02*
Y1191307D01*
G01Y1189339D02*
Y1188157D01*
G01X1184Y1211386D02*
Y1210205D01*
G01Y1205087D02*
Y1203906D01*
G01Y1208236D02*
Y1207055D01*
G01Y1201937D02*
Y1200756D01*
G01Y1195638D02*
Y1194457D01*
G01Y1198787D02*
Y1197606D01*
G01Y1192488D02*
Y1191307D01*
G01Y1189339D02*
Y1188157D01*
G01X9965Y1211386D02*
Y1210205D01*
G01Y1205087D02*
Y1203906D01*
G01Y1208236D02*
Y1207055D01*
G01Y1201937D02*
Y1200756D01*
G01Y1195638D02*
Y1194457D01*
G01Y1198787D02*
Y1197606D01*
G01Y1192488D02*
Y1191307D01*
G01Y1189339D02*
Y1188157D01*
G01X10075Y1211386D02*
Y1210205D01*
G01Y1205087D02*
Y1203906D01*
G01Y1208236D02*
Y1207055D01*
G01Y1201937D02*
Y1200756D01*
G01Y1195638D02*
Y1194457D01*
G01Y1198787D02*
Y1197606D01*
G01Y1192488D02*
Y1191307D01*
G01Y1189339D02*
Y1188157D01*
G01X-14537Y1211375D02*
X-14677Y1211287D01*
G01X-13977Y1211583D02*
X-14449Y1211287D01*
G01X-14537Y1208226D02*
X-14677Y1208138D01*
G01X-13977Y1208433D02*
X-14449Y1208138D01*
G01X-14537Y1205076D02*
X-14677Y1204988D01*
G01X-13977Y1205283D02*
X-14449Y1204988D01*
G01X-14537Y1201926D02*
X-14677Y1201839D01*
G01X-13977Y1202134D02*
X-14449Y1201839D01*
G01X-14537Y1198777D02*
X-14677Y1198689D01*
G01X-13977Y1198984D02*
X-14449Y1198689D01*
G01X-14537Y1195627D02*
X-14677Y1195539D01*
G01X-13977Y1195835D02*
X-14449Y1195539D01*
G01X-14537Y1192478D02*
X-14677Y1192390D01*
G01X-13977Y1192685D02*
X-14449Y1192390D01*
G01X-14537Y1189328D02*
X-14677Y1189240D01*
G01X-13977Y1189535D02*
X-14449Y1189240D01*
G01X-14537Y1186178D02*
X-14677Y1186091D01*
G01X-13977Y1186386D02*
X-14449Y1186091D01*
G01X-14147Y1211583D02*
X-14537Y1211375D01*
G01X-14147Y1208433D02*
X-14537Y1208226D01*
G01X-14147Y1205283D02*
X-14537Y1205076D01*
G01X-14147Y1202134D02*
X-14537Y1201926D01*
G01X-14147Y1198984D02*
X-14537Y1198777D01*
G01X-14147Y1195835D02*
X-14537Y1195627D01*
G01X-14147Y1192685D02*
X-14537Y1192478D01*
G01X-14147Y1189535D02*
X-14537Y1189328D01*
G01X-14147Y1186386D02*
X-14537Y1186178D01*
G01Y1188168D02*
X-14147Y1187961D01*
G01X-14537Y1191318D02*
X-14147Y1191110D01*
G01X-14537Y1194467D02*
X-14147Y1194260D01*
G01X-14537Y1197617D02*
X-14147Y1197409D01*
G01X-14677Y1188256D02*
X-14537Y1188168D01*
G01X-14449Y1188256D02*
X-13977Y1187961D01*
G01X-14677Y1191406D02*
X-14537Y1191318D01*
G01X-14449Y1191406D02*
X-13977Y1191110D01*
G01X-14677Y1194555D02*
X-14537Y1194467D01*
G01X-14449Y1194555D02*
X-13977Y1194260D01*
G01X-14677Y1197705D02*
X-14537Y1197617D01*
G01X-14449Y1197705D02*
X-13977Y1197409D01*
G01X-14677Y1200854D02*
X-14537Y1200767D01*
G01X-14449Y1200854D02*
X-13977Y1200559D01*
G01X-14677Y1204004D02*
X-14537Y1203916D01*
G01X-14449Y1204004D02*
X-13977Y1203709D01*
G01X-14677Y1207154D02*
X-14537Y1207066D01*
G01X-14449Y1207154D02*
X-13977Y1206858D01*
G01X-14677Y1210303D02*
X-14537Y1210215D01*
G01X-14449Y1210303D02*
X-13977Y1210008D01*
G01X-14537Y1200767D02*
X-14147Y1200559D01*
G01X-14537Y1203916D02*
X-14147Y1203709D01*
G01X-14537Y1207066D02*
X-14147Y1206858D01*
G01X-14537Y1210215D02*
X-14147Y1210008D01*
G01X-19469Y1186038D02*
X-18174Y1186052D01*
G01X-18435D02*
X-20801Y1186026D01*
G01X-18174Y1186052D02*
X-17126Y1186064D01*
G01X-19469Y1189188D02*
X-18174Y1189202D01*
G01X-18435D02*
X-20801Y1189176D01*
G01X-18174Y1189202D02*
X-17126Y1189213D01*
G01X-19469Y1192337D02*
X-18174Y1192352D01*
G01X-18435D02*
X-20801Y1192326D01*
G01X-18174Y1192352D02*
X-17126Y1192363D01*
G01X-19469Y1195487D02*
X-18174Y1195501D01*
G01X-18435D02*
X-20801Y1195475D01*
G01X-18174Y1195501D02*
X-17126Y1195513D01*
G01X-19469Y1198637D02*
X-18174Y1198651D01*
G01X-18435D02*
X-20801Y1198625D01*
G01X-18174Y1198651D02*
X-17126Y1198662D01*
G01X-19469Y1201786D02*
X-18174Y1201800D01*
G01X-18435D02*
X-20801Y1201774D01*
G01X-18174Y1201800D02*
X-17126Y1201812D01*
G01X-19469Y1204936D02*
X-18174Y1204950D01*
G01X-18435D02*
X-20801Y1204924D01*
G01X-18174Y1204950D02*
X-17126Y1204961D01*
G01X-19469Y1208085D02*
X-18174Y1208100D01*
G01X-18435D02*
X-20801Y1208074D01*
G01X-18174Y1208100D02*
X-17126Y1208111D01*
G01X-19469Y1211235D02*
X-18174Y1211249D01*
G01X-18435D02*
X-20801Y1211223D01*
G01X-18174Y1211249D02*
X-17126Y1211261D01*
G01X-15985Y1186074D02*
X-14449Y1186091D01*
G01X-14677D02*
X-18174Y1186052D01*
G01X-14677Y1186091D02*
X-16213Y1186074D01*
G01X-15985Y1189224D02*
X-14449Y1189240D01*
G01X-14677D02*
X-18174Y1189202D01*
G01X-14677Y1189240D02*
X-16213Y1189224D01*
G01X-15985Y1192373D02*
X-14449Y1192390D01*
G01X-14677D02*
X-18174Y1192352D01*
G01X-14677Y1192390D02*
X-16213Y1192373D01*
G01X-15985Y1195523D02*
X-14449Y1195539D01*
G01X-14677D02*
X-18174Y1195501D01*
G01X-14677Y1195539D02*
X-16213Y1195523D01*
G01X-15985Y1198672D02*
X-14449Y1198689D01*
G01X-14677D02*
X-18174Y1198651D01*
G01X-14677Y1198689D02*
X-16213Y1198672D01*
G01X-15985Y1201822D02*
X-14449Y1201839D01*
G01X-14677D02*
X-18174Y1201800D01*
G01X-14677Y1201839D02*
X-16213Y1201822D01*
G01X-15985Y1204972D02*
X-14449Y1204988D01*
G01X-14677D02*
X-18174Y1204950D01*
G01X-14677Y1204988D02*
X-16213Y1204972D01*
G01X-15985Y1208121D02*
X-14449Y1208138D01*
G01X-14677D02*
X-18174Y1208100D01*
G01X-14677Y1208138D02*
X-16213Y1208121D01*
G01X-15985Y1211271D02*
X-14449Y1211287D01*
G01X-14677D02*
X-18174Y1211249D01*
G01X-14677Y1211287D02*
X-16213Y1211271D01*
G01X-19469Y1186038D02*
X-20801Y1186026D01*
G01X-19469Y1189188D02*
X-20801Y1189176D01*
G01X-19469Y1192337D02*
X-20801Y1192326D01*
G01X-19469Y1195487D02*
X-20801Y1195475D01*
G01X-19469Y1198637D02*
X-20801Y1198625D01*
G01X-19469Y1201786D02*
X-20801Y1201774D01*
G01X-19469Y1204936D02*
X-20801Y1204924D01*
G01X-19469Y1208085D02*
X-20801Y1208074D01*
G01X-19469Y1211235D02*
X-20801Y1211223D01*
G01X-15985Y1186074D02*
X-17126Y1186064D01*
G01D02*
X-18435Y1186052D01*
G01X-15985Y1189224D02*
X-17126Y1189213D01*
G01D02*
X-18435Y1189202D01*
G01X-15985Y1192373D02*
X-17126Y1192363D01*
G01D02*
X-18435Y1192352D01*
G01X-15985Y1195523D02*
X-17126Y1195513D01*
G01D02*
X-18435Y1195501D01*
G01X-15985Y1198672D02*
X-17126Y1198662D01*
G01D02*
X-18435Y1198651D01*
G01X-15985Y1201822D02*
X-17126Y1201812D01*
G01D02*
X-18435Y1201800D01*
G01X-15985Y1204972D02*
X-17126Y1204961D01*
G01D02*
X-18435Y1204950D01*
G01X-15985Y1208121D02*
X-17126Y1208111D01*
G01D02*
X-18435Y1208100D01*
G01X-15985Y1211271D02*
X-17126Y1211261D01*
G01D02*
X-18435Y1211249D01*
G01X-18174Y1186052D02*
X-18435D01*
G01X-15985Y1186074D02*
X-16213D01*
G01X-14449Y1186091D02*
X-14677D01*
G01X12410Y1186189D02*
X315D01*
G01X-13009Y1186386D02*
X-14147D01*
G01X512Y1186780D02*
X0D01*
G01X512Y1187567D02*
X0D01*
G01X-13009Y1187961D02*
X-14147D01*
G01X12410Y1188157D02*
X315D01*
G01X-14449Y1188256D02*
X-14677D01*
G01X-15985Y1188272D02*
X-16213D01*
G01X-18174Y1188294D02*
X-18435D01*
G01X-18174Y1189202D02*
X-18435D01*
G01X-15985Y1189224D02*
X-16213D01*
G01X-14449Y1189240D02*
X-14677D01*
G01X12410Y1189339D02*
X315D01*
G01X-13009Y1189535D02*
X-14147D01*
G01X512Y1189929D02*
X0D01*
G01X512Y1190717D02*
X0D01*
G01X-13009Y1191110D02*
X-14147D01*
G01X12410Y1191307D02*
X315D01*
G01X-14449Y1191406D02*
X-14677D01*
G01X-15985Y1191422D02*
X-16213D01*
G01X-18174Y1191443D02*
X-18435D01*
G01X-18174Y1192352D02*
X-18435D01*
G01X-15985Y1192373D02*
X-16213D01*
G01X-14449Y1192390D02*
X-14677D01*
G01X12410Y1192488D02*
X315D01*
G01X-13009Y1192685D02*
X-14147D01*
G01X512Y1193079D02*
X0D01*
G01X512Y1193866D02*
X0D01*
G01X-13009Y1194260D02*
X-14147D01*
G01X12410Y1194457D02*
X315D01*
G01X-14449Y1194555D02*
X-14677D01*
G01X-15985Y1194571D02*
X-16213D01*
G01X-18174Y1194593D02*
X-18435D01*
G01X-18174Y1195501D02*
X-18435D01*
G01X-15985Y1195523D02*
X-16213D01*
G01X-14449Y1195539D02*
X-14677D01*
G01X12410Y1195638D02*
X315D01*
G01X-13009Y1195835D02*
X-14147D01*
G01X512Y1196228D02*
X0D01*
G01X512Y1197016D02*
X0D01*
G01X-13009Y1197409D02*
X-14147D01*
G01X12410Y1197606D02*
X315D01*
G01X-14449Y1197705D02*
X-14677D01*
G01X-15985Y1197721D02*
X-16213D01*
G01X-18174Y1197743D02*
X-18435D01*
G01X-18174Y1198651D02*
X-18435D01*
G01X-15985Y1198672D02*
X-16213D01*
G01X-14449Y1198689D02*
X-14677D01*
G01X12410Y1198787D02*
X315D01*
G01X-13009Y1198984D02*
X-14147D01*
G01X512Y1199378D02*
X0D01*
G01X512Y1200165D02*
X0D01*
G01X-13009Y1200559D02*
X-14147D01*
G01X12410Y1200756D02*
X315D01*
G01X-14449Y1200854D02*
X-14677D01*
G01X-15985Y1200870D02*
X-16213D01*
G01X-18174Y1200892D02*
X-18435D01*
G01X-18174Y1201800D02*
X-18435D01*
G01X-15985Y1201822D02*
X-16213D01*
G01X-14449Y1201839D02*
X-14677D01*
G01X12410Y1201937D02*
X315D01*
G01X-13009Y1202134D02*
X-14147D01*
G01X512Y1202528D02*
X0D01*
G01X512Y1203315D02*
X0D01*
G01X-13009Y1203709D02*
X-14147D01*
G01X12410Y1203906D02*
X315D01*
G01X-14449Y1204004D02*
X-14677D01*
G01X-15985Y1204020D02*
X-16213D01*
G01X-18174Y1204042D02*
X-18435D01*
G01X-18174Y1204950D02*
X-18435D01*
G01X-15985Y1204972D02*
X-16213D01*
G01X-14449Y1204988D02*
X-14677D01*
G01X12410Y1205087D02*
X315D01*
G01X-13009Y1205283D02*
X-14147D01*
G01X512Y1205677D02*
X0D01*
G01X512Y1206465D02*
X0D01*
G01X-13009Y1206858D02*
X-14147D01*
G01X12410Y1207055D02*
X315D01*
G01X-14449Y1207154D02*
X-14677D01*
G01X-15985Y1207170D02*
X-16213D01*
G01X-18174Y1207191D02*
X-18435D01*
G01X-18174Y1208100D02*
X-18435D01*
G01X-15985Y1208121D02*
X-16213D01*
G01X-14449Y1208138D02*
X-14677D01*
G01X12410Y1208236D02*
X315D01*
G01X-13009Y1208433D02*
X-14147D01*
G01X512Y1208827D02*
X0D01*
G01X512Y1209614D02*
X0D01*
G01X-13009Y1210008D02*
X-14147D01*
G01X12410Y1210205D02*
X315D01*
G01X-14449Y1210303D02*
X-14677D01*
G01X-15985Y1210319D02*
X-16213D01*
G01X-18174Y1210341D02*
X-18435D01*
G01X-18174Y1211249D02*
X-18435D01*
G01X-15985Y1211271D02*
X-16213D01*
G01X-14449Y1211287D02*
X-14677D01*
G01X12410Y1211386D02*
X315D01*
G01X-13009Y1211583D02*
X-14147D01*
G01X-19469Y1188308D02*
X-20801Y1188320D01*
G01X-15985Y1188272D02*
X-18435Y1188294D01*
G01X-19469Y1191458D02*
X-20801Y1191470D01*
G01X-15985Y1191422D02*
X-18435Y1191443D01*
G01X-19469Y1194607D02*
X-20801Y1194619D01*
G01X-15985Y1194571D02*
X-18435Y1194593D01*
G01X-19469Y1197757D02*
X-20801Y1197769D01*
G01X-15985Y1197721D02*
X-18435Y1197743D01*
G01X-19469Y1200907D02*
X-20801Y1200919D01*
G01X-15985Y1200870D02*
X-18435Y1200892D01*
G01X-19469Y1204056D02*
X-20801Y1204068D01*
G01X-15985Y1204020D02*
X-18435Y1204042D01*
G01X-19469Y1207206D02*
X-20801Y1207218D01*
G01X-15985Y1207170D02*
X-18435Y1207191D01*
G01X-19469Y1210356D02*
X-20801Y1210367D01*
G01X-15985Y1210319D02*
X-18435Y1210341D01*
G01X-15985Y1188272D02*
X-14449Y1188256D01*
G01X-15985Y1191422D02*
X-14449Y1191406D01*
G01X-15985Y1194571D02*
X-14449Y1194555D01*
G01X-15985Y1197721D02*
X-14449Y1197705D01*
G01X-15985Y1200870D02*
X-14449Y1200854D01*
G01X-15985Y1204020D02*
X-14449Y1204004D01*
G01X-15985Y1207170D02*
X-14449Y1207154D01*
G01X-15985Y1210319D02*
X-14449Y1210303D01*
G01X-18435Y1188294D02*
X-20801Y1188320D01*
G01X-18435Y1191443D02*
X-20801Y1191470D01*
G01X-18435Y1194593D02*
X-20801Y1194619D01*
G01X-18435Y1197743D02*
X-20801Y1197769D01*
G01X-18435Y1200892D02*
X-20801Y1200919D01*
G01X-18435Y1204042D02*
X-20801Y1204068D01*
G01X-18435Y1207191D02*
X-20801Y1207218D01*
G01X-18435Y1210341D02*
X-20801Y1210367D01*
G01X-19469Y1188308D02*
X-16213Y1188272D01*
G01X-18174Y1188294D02*
X-14677Y1188256D01*
G01X-19469Y1191458D02*
X-16213Y1191422D01*
G01X-18174Y1191443D02*
X-14677Y1191406D01*
G01X-19469Y1194607D02*
X-16213Y1194571D01*
G01X-18174Y1194593D02*
X-14677Y1194555D01*
G01X-19469Y1197757D02*
X-16213Y1197721D01*
G01X-18174Y1197743D02*
X-14677Y1197705D01*
G01X-19469Y1200907D02*
X-16213Y1200870D01*
G01X-18174Y1200892D02*
X-14677Y1200854D01*
G01X-19469Y1204056D02*
X-16213Y1204020D01*
G01X-18174Y1204042D02*
X-14677Y1204004D01*
G01X-19469Y1207206D02*
X-16213Y1207170D01*
G01X-18174Y1207191D02*
X-14677Y1207154D01*
G01X-19469Y1210356D02*
X-16213Y1210319D01*
G01X-18174Y1210341D02*
X-14677Y1210303D01*
G01X-20801Y1186026D02*
Y1185170D01*
G01Y1182877D02*
Y1182021D01*
G01Y1176578D02*
Y1175722D01*
G01Y1179727D02*
Y1178871D01*
G01Y1173428D02*
Y1172572D01*
G01Y1167129D02*
Y1166273D01*
G01Y1170278D02*
Y1169422D01*
G01Y1163979D02*
Y1163123D01*
G01Y1157680D02*
Y1156824D01*
G01Y1160830D02*
Y1159974D01*
G01Y1154530D02*
Y1153674D01*
G01Y1148231D02*
Y1147375D01*
G01Y1151381D02*
Y1150525D01*
G01Y1145081D02*
Y1144226D01*
G01Y1141932D02*
Y1141076D01*
G01X-19469Y1186032D02*
Y1185165D01*
G01Y1182883D02*
Y1182015D01*
G01Y1176583D02*
Y1175716D01*
G01Y1179733D02*
Y1178865D01*
G01Y1173434D02*
Y1172566D01*
G01Y1167135D02*
Y1166267D01*
G01Y1170284D02*
Y1169417D01*
G01Y1163985D02*
Y1163117D01*
G01Y1157686D02*
Y1156818D01*
G01Y1160835D02*
Y1159968D01*
G01Y1154536D02*
Y1153669D01*
G01Y1148237D02*
Y1147369D01*
G01Y1151387D02*
Y1150519D01*
G01Y1145087D02*
Y1144220D01*
G01Y1141938D02*
Y1141070D01*
G01X-18435Y1186052D02*
Y1185144D01*
G01Y1182903D02*
Y1181994D01*
G01Y1176604D02*
Y1175695D01*
G01Y1179753D02*
Y1178845D01*
G01Y1173454D02*
Y1172546D01*
G01Y1167155D02*
Y1166246D01*
G01Y1170304D02*
Y1169396D01*
G01Y1164005D02*
Y1163097D01*
G01Y1157706D02*
Y1156798D01*
G01Y1160856D02*
Y1159947D01*
G01Y1154556D02*
Y1153648D01*
G01Y1148257D02*
Y1147349D01*
G01Y1151407D02*
Y1150498D01*
G01Y1145107D02*
Y1144199D01*
G01Y1141958D02*
Y1141050D01*
G01X-18174Y1186052D02*
Y1185144D01*
G01Y1182903D02*
Y1181994D01*
G01Y1176604D02*
Y1175695D01*
G01Y1179753D02*
Y1178845D01*
G01Y1173454D02*
Y1172546D01*
G01Y1167155D02*
Y1166246D01*
G01Y1170304D02*
Y1169396D01*
G01Y1164005D02*
Y1163097D01*
G01Y1157706D02*
Y1156798D01*
G01Y1160856D02*
Y1159947D01*
G01Y1154556D02*
Y1153648D01*
G01Y1148257D02*
Y1147349D01*
G01Y1151407D02*
Y1150498D01*
G01Y1145107D02*
Y1144199D01*
G01Y1141958D02*
Y1141050D01*
G01X-16213Y1186074D02*
Y1185122D01*
G01Y1182924D02*
Y1181973D01*
G01Y1176625D02*
Y1175674D01*
G01Y1179775D02*
Y1178823D01*
G01Y1173476D02*
Y1172524D01*
G01Y1167176D02*
Y1166225D01*
G01Y1170326D02*
Y1169374D01*
G01Y1164027D02*
Y1163075D01*
G01Y1157728D02*
Y1156776D01*
G01Y1160877D02*
Y1159926D01*
G01Y1154578D02*
Y1153626D01*
G01Y1148279D02*
Y1147327D01*
G01Y1151428D02*
Y1150477D01*
G01Y1145129D02*
Y1144178D01*
G01Y1141980D02*
Y1141028D01*
G01X-15985Y1186074D02*
Y1185122D01*
G01Y1182924D02*
Y1181973D01*
G01Y1176625D02*
Y1175674D01*
G01Y1179775D02*
Y1178823D01*
G01Y1173476D02*
Y1172524D01*
G01Y1167176D02*
Y1166225D01*
G01Y1170326D02*
Y1169374D01*
G01Y1164027D02*
Y1163075D01*
G01Y1157728D02*
Y1156776D01*
G01Y1160877D02*
Y1159926D01*
G01Y1154578D02*
Y1153626D01*
G01Y1148279D02*
Y1147327D01*
G01Y1151428D02*
Y1150477D01*
G01Y1145129D02*
Y1144178D01*
G01Y1141980D02*
Y1141028D01*
G01X-14537Y1186178D02*
Y1185019D01*
G01Y1183029D02*
Y1181869D01*
G01Y1176730D02*
Y1175570D01*
G01Y1179879D02*
Y1178719D01*
G01Y1173580D02*
Y1172420D01*
G01Y1167281D02*
Y1166121D01*
G01Y1170430D02*
Y1169270D01*
G01Y1164131D02*
Y1162971D01*
G01Y1157832D02*
Y1156672D01*
G01Y1160981D02*
Y1159822D01*
G01Y1154682D02*
Y1153522D01*
G01Y1148383D02*
Y1147223D01*
G01Y1151533D02*
Y1150373D01*
G01Y1145233D02*
Y1144074D01*
G01Y1142084D02*
Y1140924D01*
G01X-13009Y1186386D02*
Y1184811D01*
G01Y1183236D02*
Y1181661D01*
G01Y1176937D02*
Y1175362D01*
G01Y1180087D02*
Y1178512D01*
G01Y1173787D02*
Y1172213D01*
G01Y1167488D02*
Y1165913D01*
G01Y1170638D02*
Y1169063D01*
G01Y1164339D02*
Y1162764D01*
G01Y1158039D02*
Y1156465D01*
G01Y1161189D02*
Y1159614D01*
G01Y1154890D02*
Y1153315D01*
G01Y1148591D02*
Y1147016D01*
G01Y1151740D02*
Y1150165D01*
G01Y1145441D02*
Y1143866D01*
G01Y1142291D02*
Y1140717D01*
G01X315Y1183630D02*
Y1183039D01*
G01Y1181858D02*
Y1181268D01*
G01Y1185008D02*
Y1184417D01*
G01Y1177331D02*
Y1176740D01*
G01Y1180480D02*
Y1179890D01*
G01Y1178709D02*
Y1178118D01*
G01Y1174181D02*
Y1173591D01*
G01Y1172409D02*
Y1171819D01*
G01Y1175559D02*
Y1174969D01*
G01Y1167882D02*
Y1167291D01*
G01Y1171031D02*
Y1170441D01*
G01Y1169260D02*
Y1168669D01*
G01Y1164732D02*
Y1164142D01*
G01Y1162961D02*
Y1162370D01*
G01Y1166110D02*
Y1165520D01*
G01Y1158433D02*
Y1157843D01*
G01Y1161583D02*
Y1160992D01*
G01Y1159811D02*
Y1159220D01*
G01Y1155283D02*
Y1154693D01*
G01Y1153512D02*
Y1152921D01*
G01Y1156661D02*
Y1156071D01*
G01Y1148984D02*
Y1148394D01*
G01Y1152134D02*
Y1151543D01*
G01Y1150362D02*
Y1149772D01*
G01Y1145835D02*
Y1145244D01*
G01Y1144063D02*
Y1143472D01*
G01Y1147213D02*
Y1146622D01*
G01Y1139535D02*
Y1138945D01*
G01Y1142685D02*
Y1142094D01*
G01Y1140913D02*
Y1140323D01*
G01X512Y1183630D02*
Y1183039D01*
G01Y1181858D02*
Y1181268D01*
G01Y1185008D02*
Y1184417D01*
G01Y1177331D02*
Y1176740D01*
G01Y1180480D02*
Y1179890D01*
G01Y1178709D02*
Y1178118D01*
G01Y1174181D02*
Y1173591D01*
G01Y1172409D02*
Y1171819D01*
G01Y1175559D02*
Y1174969D01*
G01Y1167882D02*
Y1167291D01*
G01Y1171031D02*
Y1170441D01*
G01Y1169260D02*
Y1168669D01*
G01Y1164732D02*
Y1164142D01*
G01Y1162961D02*
Y1162370D01*
G01Y1166110D02*
Y1165520D01*
G01Y1158433D02*
Y1157843D01*
G01Y1161583D02*
Y1160992D01*
G01Y1159811D02*
Y1159220D01*
G01Y1155283D02*
Y1154693D01*
G01Y1153512D02*
Y1152921D01*
G01Y1156661D02*
Y1156071D01*
G01Y1148984D02*
Y1148394D01*
G01Y1152134D02*
Y1151543D01*
G01Y1150362D02*
Y1149772D01*
G01Y1145835D02*
Y1145244D01*
G01Y1144063D02*
Y1143472D01*
G01Y1147213D02*
Y1146622D01*
G01Y1139535D02*
Y1138945D01*
G01Y1142685D02*
Y1142094D01*
G01Y1140913D02*
Y1140323D01*
G01X709Y1186189D02*
Y1185008D01*
G01Y1183039D02*
Y1181858D01*
G01Y1176740D02*
Y1175559D01*
G01Y1179890D02*
Y1178709D01*
G01Y1173591D02*
Y1172409D01*
G01Y1167291D02*
Y1166110D01*
G01Y1170441D02*
Y1169260D01*
G01Y1164142D02*
Y1162961D01*
G01Y1157843D02*
Y1156661D01*
G01Y1160992D02*
Y1159811D01*
G01Y1154693D02*
Y1153512D01*
G01Y1148394D02*
Y1147213D01*
G01Y1151543D02*
Y1150362D01*
G01Y1145244D02*
Y1144063D01*
G01Y1142094D02*
Y1140913D01*
G01X1074Y1186189D02*
Y1185008D01*
G01Y1183039D02*
Y1181858D01*
G01Y1176740D02*
Y1175559D01*
G01Y1179890D02*
Y1178709D01*
G01Y1173591D02*
Y1172409D01*
G01Y1167291D02*
Y1166110D01*
G01Y1170441D02*
Y1169260D01*
G01Y1164142D02*
Y1162961D01*
G01Y1157843D02*
Y1156661D01*
G01Y1160992D02*
Y1159811D01*
G01Y1154693D02*
Y1153512D01*
G01Y1148394D02*
Y1147213D01*
G01Y1151543D02*
Y1150362D01*
G01Y1145244D02*
Y1144063D01*
G01Y1142094D02*
Y1140913D01*
G01X1184Y1186189D02*
Y1185008D01*
G01Y1183039D02*
Y1181858D01*
G01Y1176740D02*
Y1175559D01*
G01Y1179890D02*
Y1178709D01*
G01Y1173591D02*
Y1172409D01*
G01Y1167291D02*
Y1166110D01*
G01Y1170441D02*
Y1169260D01*
G01Y1164142D02*
Y1162961D01*
G01Y1157843D02*
Y1156661D01*
G01Y1160992D02*
Y1159811D01*
G01Y1154693D02*
Y1153512D01*
G01Y1148394D02*
Y1147213D01*
G01Y1151543D02*
Y1150362D01*
G01Y1145244D02*
Y1144063D01*
G01Y1142094D02*
Y1140913D01*
G01X9965Y1186189D02*
Y1185008D01*
G01Y1183039D02*
Y1181858D01*
G01Y1176740D02*
Y1175559D01*
G01Y1179890D02*
Y1178709D01*
G01Y1173591D02*
Y1172409D01*
G01Y1167291D02*
Y1166110D01*
G01Y1170441D02*
Y1169260D01*
G01Y1164142D02*
Y1162961D01*
G01Y1157843D02*
Y1156661D01*
G01Y1160992D02*
Y1159811D01*
G01Y1154693D02*
Y1153512D01*
G01Y1148394D02*
Y1147213D01*
G01Y1151543D02*
Y1150362D01*
G01Y1145244D02*
Y1144063D01*
G01Y1142094D02*
Y1140913D01*
G01X10075Y1186189D02*
Y1185008D01*
G01Y1183039D02*
Y1181858D01*
G01Y1176740D02*
Y1175559D01*
G01Y1179890D02*
Y1178709D01*
G01Y1173591D02*
Y1172409D01*
G01Y1167291D02*
Y1166110D01*
G01Y1170441D02*
Y1169260D01*
G01Y1164142D02*
Y1162961D01*
G01Y1157843D02*
Y1156661D01*
G01Y1160992D02*
Y1159811D01*
G01Y1154693D02*
Y1153512D01*
G01Y1148394D02*
Y1147213D01*
G01Y1151543D02*
Y1150362D01*
G01Y1145244D02*
Y1144063D01*
G01Y1142094D02*
Y1140913D01*
G01X-14537Y1183029D02*
X-14677Y1182941D01*
G01X-13977Y1183236D02*
X-14449Y1182941D01*
G01X-14537Y1179879D02*
X-14677Y1179791D01*
G01X-13977Y1180087D02*
X-14449Y1179791D01*
G01X-14537Y1176730D02*
X-14677Y1176642D01*
G01X-13977Y1176937D02*
X-14449Y1176642D01*
G01X-14537Y1173580D02*
X-14677Y1173492D01*
G01X-13977Y1173787D02*
X-14449Y1173492D01*
G01X-14537Y1170430D02*
X-14677Y1170343D01*
G01X-13977Y1170638D02*
X-14449Y1170343D01*
G01X-14537Y1167281D02*
X-14677Y1167193D01*
G01X-13977Y1167488D02*
X-14449Y1167193D01*
G01X-14537Y1164131D02*
X-14677Y1164043D01*
G01X-13977Y1164339D02*
X-14449Y1164043D01*
G01X-14537Y1160981D02*
X-14677Y1160894D01*
G01X-13977Y1161189D02*
X-14449Y1160894D01*
G01X-14537Y1157832D02*
X-14677Y1157744D01*
G01X-13977Y1158039D02*
X-14449Y1157744D01*
G01X-14537Y1154682D02*
X-14677Y1154594D01*
G01X-13977Y1154890D02*
X-14449Y1154594D01*
G01X-14537Y1151533D02*
X-14677Y1151445D01*
G01X-13977Y1151740D02*
X-14449Y1151445D01*
G01X-14537Y1148383D02*
X-14677Y1148295D01*
G01X-13977Y1148591D02*
X-14449Y1148295D01*
G01X-14537Y1145233D02*
X-14677Y1145146D01*
G01X-13977Y1145441D02*
X-14449Y1145146D01*
G01X-14537Y1142084D02*
X-14677Y1141996D01*
G01X-13977Y1142291D02*
X-14449Y1141996D01*
G01X-14147Y1183236D02*
X-14537Y1183029D01*
G01X-14147Y1180087D02*
X-14537Y1179879D01*
G01X-14147Y1176937D02*
X-14537Y1176730D01*
G01X-14147Y1173787D02*
X-14537Y1173580D01*
G01X-14147Y1170638D02*
X-14537Y1170430D01*
G01X-14147Y1167488D02*
X-14537Y1167281D01*
G01X-14147Y1164339D02*
X-14537Y1164131D01*
G01X-14147Y1161189D02*
X-14537Y1160981D01*
G01X-14147Y1158039D02*
X-14537Y1157832D01*
G01X-14147Y1154890D02*
X-14537Y1154682D01*
G01X-14147Y1151740D02*
X-14537Y1151533D01*
G01X-14147Y1148591D02*
X-14537Y1148383D01*
G01X-14147Y1145441D02*
X-14537Y1145233D01*
G01X-14147Y1142291D02*
X-14537Y1142084D01*
G01X-14677Y1141012D02*
X-14537Y1140924D01*
G01X-14449Y1141012D02*
X-13977Y1140717D01*
G01X-14677Y1144161D02*
X-14537Y1144074D01*
G01X-14449Y1144161D02*
X-13977Y1143866D01*
G01X-14677Y1147311D02*
X-14537Y1147223D01*
G01X-14449Y1147311D02*
X-13977Y1147016D01*
G01X-14677Y1150461D02*
X-14537Y1150373D01*
G01X-14449Y1150461D02*
X-13977Y1150165D01*
G01X-14677Y1153610D02*
X-14537Y1153522D01*
G01X-14449Y1153610D02*
X-13977Y1153315D01*
G01X-14537Y1140924D02*
X-14147Y1140717D01*
G01X-14537Y1144074D02*
X-14147Y1143866D01*
G01X-14537Y1147223D02*
X-14147Y1147016D01*
G01X-14537Y1150373D02*
X-14147Y1150165D01*
G01X-14537Y1153522D02*
X-14147Y1153315D01*
G01X-14537Y1156672D02*
X-14147Y1156465D01*
G01X-14537Y1159822D02*
X-14147Y1159614D01*
G01X-14537Y1162971D02*
X-14147Y1162764D01*
G01X-14537Y1166121D02*
X-14147Y1165913D01*
G01X-14537Y1169270D02*
X-14147Y1169063D01*
G01X-14537Y1172420D02*
X-14147Y1172213D01*
G01X-14537Y1175570D02*
X-14147Y1175362D01*
G01X-14537Y1178719D02*
X-14147Y1178512D01*
G01X-14537Y1181869D02*
X-14147Y1181661D01*
G01X-14537Y1185019D02*
X-14147Y1184811D01*
G01X-14677Y1156760D02*
X-14537Y1156672D01*
G01X-14449Y1156760D02*
X-13977Y1156465D01*
G01X-14677Y1159909D02*
X-14537Y1159822D01*
G01X-14449Y1159909D02*
X-13977Y1159614D01*
G01X-14677Y1163059D02*
X-14537Y1162971D01*
G01X-14449Y1163059D02*
X-13977Y1162764D01*
G01X-14677Y1166209D02*
X-14537Y1166121D01*
G01X-14449Y1166209D02*
X-13977Y1165913D01*
G01X-14677Y1169358D02*
X-14537Y1169270D01*
G01X-14449Y1169358D02*
X-13977Y1169063D01*
G01X-14677Y1172508D02*
X-14537Y1172420D01*
G01X-14449Y1172508D02*
X-13977Y1172213D01*
G01X-14677Y1175657D02*
X-14537Y1175570D01*
G01X-14449Y1175657D02*
X-13977Y1175362D01*
G01X-14677Y1178807D02*
X-14537Y1178719D01*
G01X-14449Y1178807D02*
X-13977Y1178512D01*
G01X-14677Y1181957D02*
X-14537Y1181869D01*
G01X-14449Y1181957D02*
X-13977Y1181661D01*
G01X-14677Y1185106D02*
X-14537Y1185019D01*
G01X-14449Y1185106D02*
X-13977Y1184811D01*
G01X-19469Y1141944D02*
X-18174Y1141958D01*
G01X-18435D02*
X-20801Y1141932D01*
G01X-18174Y1141958D02*
X-17126Y1141969D01*
G01X-19469Y1145093D02*
X-18174Y1145107D01*
G01X-18435D02*
X-20801Y1145081D01*
G01X-18174Y1145107D02*
X-17126Y1145119D01*
G01X-19469Y1148243D02*
X-18174Y1148257D01*
G01X-18435D02*
X-20801Y1148231D01*
G01X-18174Y1148257D02*
X-17126Y1148269D01*
G01X-19469Y1151393D02*
X-18174Y1151407D01*
G01X-18435D02*
X-20801Y1151381D01*
G01X-18174Y1151407D02*
X-17126Y1151418D01*
G01X-15985Y1141980D02*
X-14449Y1141996D01*
G01X-14677D02*
X-18174Y1141958D01*
G01X-14677Y1141996D02*
X-16213Y1141980D01*
G01X-15985Y1145129D02*
X-14449Y1145146D01*
G01X-14677D02*
X-18174Y1145107D01*
G01X-14677Y1145146D02*
X-16213Y1145129D01*
G01X-15985Y1148279D02*
X-14449Y1148295D01*
G01X-14677D02*
X-18174Y1148257D01*
G01X-14677Y1148295D02*
X-16213Y1148279D01*
G01X-15985Y1151428D02*
X-14449Y1151445D01*
G01X-14677D02*
X-18174Y1151407D01*
G01X-14677Y1151445D02*
X-16213Y1151428D01*
G01X-19469Y1141944D02*
X-20801Y1141932D01*
G01X-19469Y1145093D02*
X-20801Y1145081D01*
G01X-19469Y1148243D02*
X-20801Y1148231D01*
G01X-19469Y1151393D02*
X-20801Y1151381D01*
G01X-19469Y1154542D02*
X-20801Y1154530D01*
G01X-15985Y1141980D02*
X-17126Y1141969D01*
G01D02*
X-18435Y1141958D01*
G01X-15985Y1145129D02*
X-17126Y1145119D01*
G01D02*
X-18435Y1145107D01*
G01X-15985Y1148279D02*
X-17126Y1148269D01*
G01D02*
X-18435Y1148257D01*
G01X-15985Y1151428D02*
X-17126Y1151418D01*
G01D02*
X-18435Y1151407D01*
G01X-15985Y1154578D02*
X-17126Y1154568D01*
G01D02*
X-18435Y1154556D01*
G01X12410Y1138945D02*
X315D01*
G01X-13009Y1139142D02*
X-14147D01*
G01X512Y1139535D02*
X0D01*
G01X512Y1140323D02*
X0D01*
G01X-13009Y1140717D02*
X-14147D01*
G01X12410Y1140913D02*
X315D01*
G01X-14449Y1141012D02*
X-14677D01*
G01X-15985Y1141028D02*
X-16213D01*
G01X-18174Y1141050D02*
X-18435D01*
G01X-18174Y1141958D02*
X-18435D01*
G01X-15985Y1141980D02*
X-16213D01*
G01X-14449Y1141996D02*
X-14677D01*
G01X12410Y1142094D02*
X315D01*
G01X-13009Y1142291D02*
X-14147D01*
G01X512Y1142685D02*
X0D01*
G01X512Y1143472D02*
X0D01*
G01X-13009Y1143866D02*
X-14147D01*
G01X12410Y1144063D02*
X315D01*
G01X-14449Y1144161D02*
X-14677D01*
G01X-15985Y1144178D02*
X-16213D01*
G01X-18174Y1144199D02*
X-18435D01*
G01X-18174Y1145107D02*
X-18435D01*
G01X-15985Y1145129D02*
X-16213D01*
G01X-14449Y1145146D02*
X-14677D01*
G01X12410Y1145244D02*
X315D01*
G01X-13009Y1145441D02*
X-14147D01*
G01X512Y1145835D02*
X0D01*
G01X512Y1146622D02*
X0D01*
G01X-13009Y1147016D02*
X-14147D01*
G01X12410Y1147213D02*
X315D01*
G01X-14449Y1147311D02*
X-14677D01*
G01X-15985Y1147327D02*
X-16213D01*
G01X-18174Y1147349D02*
X-18435D01*
G01X-18174Y1148257D02*
X-18435D01*
G01X-15985Y1148279D02*
X-16213D01*
G01X-14449Y1148295D02*
X-14677D01*
G01X12410Y1148394D02*
X315D01*
G01X-13009Y1148591D02*
X-14147D01*
G01X512Y1148984D02*
X0D01*
G01X512Y1149772D02*
X0D01*
G01X-13009Y1150165D02*
X-14147D01*
G01X12410Y1150362D02*
X315D01*
G01X-14449Y1150461D02*
X-14677D01*
G01X-15985Y1150477D02*
X-16213D01*
G01X-18174Y1150498D02*
X-18435D01*
G01X-18174Y1151407D02*
X-18435D01*
G01X-16213Y1151428D02*
X-15985D01*
G01X-14449Y1151445D02*
X-14677D01*
G01X12410Y1151543D02*
X315D01*
G01X-13009Y1151740D02*
X-14147D01*
G01X512Y1152134D02*
X0D01*
G01X512Y1152921D02*
X0D01*
G01X-13009Y1153315D02*
X-14147D01*
G01X12410Y1153512D02*
X315D01*
G01X-14449Y1153610D02*
X-14677D01*
G01X-15985Y1153626D02*
X-16213D01*
G01X-18174Y1153648D02*
X-18435D01*
G01X-18174Y1154556D02*
X-18435D01*
G01X-15985Y1154578D02*
X-16213D01*
G01X-14449Y1154594D02*
X-14677D01*
G01X12410Y1154693D02*
X315D01*
G01X-13009Y1154890D02*
X-14147D01*
G01X512Y1155283D02*
X0D01*
G01X512Y1156071D02*
X0D01*
G01X-13009Y1156465D02*
X-14147D01*
G01X12410Y1156661D02*
X315D01*
G01X-14449Y1156760D02*
X-14677D01*
G01X-15985Y1156776D02*
X-16213D01*
G01X-18174Y1156798D02*
X-18435D01*
G01X-18174Y1157706D02*
X-18435D01*
G01X-15985Y1157728D02*
X-16213D01*
G01X-14449Y1157744D02*
X-14677D01*
G01X12410Y1157843D02*
X315D01*
G01X-13009Y1158039D02*
X-14147D01*
G01X512Y1158433D02*
X0D01*
G01X512Y1159220D02*
X0D01*
G01X-19469Y1141064D02*
X-20801Y1141076D01*
G01X-15985Y1141028D02*
X-18435Y1141050D01*
G01X-19469Y1144214D02*
X-20801Y1144226D01*
G01X-15985Y1144178D02*
X-18435Y1144199D01*
G01X-19469Y1147363D02*
X-20801Y1147375D01*
G01X-15985Y1147327D02*
X-18435Y1147349D01*
G01X-19469Y1150513D02*
X-20801Y1150525D01*
G01X-15985Y1150477D02*
X-18435Y1150498D01*
G01X-19469Y1153663D02*
X-20801Y1153674D01*
G01X-15985Y1153626D02*
X-18435Y1153648D01*
G01X-19469Y1156812D02*
X-20801Y1156824D01*
G01X-15985Y1156776D02*
X-18435Y1156798D01*
G01X-19469Y1159962D02*
X-20801Y1159974D01*
G01X-15985Y1159926D02*
X-18435Y1159947D01*
G01X-19469Y1163111D02*
X-20801Y1163123D01*
G01X-15985Y1163075D02*
X-18435Y1163097D01*
G01X-15985Y1141028D02*
X-14449Y1141012D01*
G01X-15985Y1144178D02*
X-14449Y1144161D01*
G01X-15985Y1147327D02*
X-14449Y1147311D01*
G01X-15985Y1150477D02*
X-14449Y1150461D01*
G01X-15985Y1153626D02*
X-14449Y1153610D01*
G01X-15985Y1156776D02*
X-14449Y1156760D01*
G01X-15985Y1159926D02*
X-14449Y1159909D01*
G01X-15985Y1163075D02*
X-14449Y1163059D01*
G01X-18435Y1141050D02*
X-20801Y1141076D01*
G01X-18435Y1144199D02*
X-20801Y1144226D01*
G01X-18435Y1147349D02*
X-20801Y1147375D01*
G01X-18435Y1150498D02*
X-20801Y1150525D01*
G01X-18435Y1153648D02*
X-20801Y1153674D01*
G01X-18435Y1156798D02*
X-20801Y1156824D01*
G01X-18435Y1159947D02*
X-20801Y1159974D01*
G01X-18435Y1163097D02*
X-20801Y1163123D01*
G01X-19469Y1141064D02*
X-16213Y1141028D01*
G01X-18174Y1141050D02*
X-14677Y1141012D01*
G01X-19469Y1144214D02*
X-16213Y1144178D01*
G01X-18174Y1144199D02*
X-14677Y1144161D01*
G01X-19469Y1147363D02*
X-16213Y1147327D01*
G01X-18174Y1147349D02*
X-14677Y1147311D01*
G01X-19469Y1150513D02*
X-16213Y1150477D01*
G01X-18174Y1150498D02*
X-14677Y1150461D01*
G01X-19469Y1153663D02*
X-16213Y1153626D01*
G01X-18174Y1153648D02*
X-14677Y1153610D01*
G01X-19469Y1156812D02*
X-16213Y1156776D01*
G01X-18174Y1156798D02*
X-14677Y1156760D01*
G01X-19469Y1159962D02*
X-16213Y1159926D01*
G01X-18174Y1159947D02*
X-14677Y1159909D01*
G01X-19469Y1163111D02*
X-16213Y1163075D01*
G01X-18174Y1163097D02*
X-14677Y1163059D01*
G01X-19469Y1154542D02*
X-18174Y1154556D01*
G01X-18435D02*
X-20801Y1154530D01*
G01X-18174Y1154556D02*
X-17126Y1154568D01*
G01X-19469Y1157692D02*
X-18174Y1157706D01*
G01X-18435D02*
X-20801Y1157680D01*
G01X-18174Y1157706D02*
X-17126Y1157717D01*
G01X-19469Y1160841D02*
X-18174Y1160856D01*
G01X-18435D02*
X-20801Y1160830D01*
G01X-18174Y1160856D02*
X-17126Y1160867D01*
G01X-19469Y1163991D02*
X-18174Y1164005D01*
G01X-18435D02*
X-20801Y1163979D01*
G01X-18174Y1164005D02*
X-17126Y1164017D01*
G01X-19469Y1167141D02*
X-18174Y1167155D01*
G01X-18435D02*
X-20801Y1167129D01*
G01X-18174Y1167155D02*
X-17126Y1167166D01*
G01X-19469Y1170290D02*
X-18174Y1170304D01*
G01X-18435D02*
X-20801Y1170278D01*
G01X-18174Y1170304D02*
X-17126Y1170316D01*
G01X-19469Y1173440D02*
X-18174Y1173454D01*
G01X-18435D02*
X-20801Y1173428D01*
G01X-18174Y1173454D02*
X-17126Y1173465D01*
G01X-19469Y1176589D02*
X-18174Y1176604D01*
G01X-18435D02*
X-20801Y1176578D01*
G01X-18174Y1176604D02*
X-17126Y1176615D01*
G01X-19469Y1179739D02*
X-18174Y1179753D01*
G01X-18435D02*
X-20801Y1179727D01*
G01X-18174Y1179753D02*
X-17126Y1179765D01*
G01X-19469Y1182889D02*
X-18174Y1182903D01*
G01X-18435D02*
X-20801Y1182877D01*
G01X-18174Y1182903D02*
X-17126Y1182914D01*
G01X-15985Y1154578D02*
X-14449Y1154594D01*
G01X-14677D02*
X-18174Y1154556D01*
G01X-14677Y1154594D02*
X-16213Y1154578D01*
G01X-15985Y1157728D02*
X-14449Y1157744D01*
G01X-14677D02*
X-18174Y1157706D01*
G01X-14677Y1157744D02*
X-16213Y1157728D01*
G01X-15985Y1160877D02*
X-14449Y1160894D01*
G01X-14677D02*
X-18174Y1160856D01*
G01X-14677Y1160894D02*
X-16213Y1160877D01*
G01X-15985Y1164027D02*
X-14449Y1164043D01*
G01X-14677D02*
X-18174Y1164005D01*
G01X-14677Y1164043D02*
X-16213Y1164027D01*
G01X-15985Y1167176D02*
X-14449Y1167193D01*
G01X-14677D02*
X-18174Y1167155D01*
G01X-14677Y1167193D02*
X-16213Y1167176D01*
G01X-15985Y1170326D02*
X-14449Y1170343D01*
G01X-14677D02*
X-18174Y1170304D01*
G01X-14677Y1170343D02*
X-16213Y1170326D01*
G01X-15985Y1173476D02*
X-14449Y1173492D01*
G01X-14677D02*
X-18174Y1173454D01*
G01X-14677Y1173492D02*
X-16213Y1173476D01*
G01X-15985Y1176625D02*
X-14449Y1176642D01*
G01X-14677D02*
X-18174Y1176604D01*
G01X-14677Y1176642D02*
X-16213Y1176625D01*
G01X-15985Y1179775D02*
X-14449Y1179791D01*
G01X-14677D02*
X-18174Y1179753D01*
G01X-14677Y1179791D02*
X-16213Y1179775D01*
G01X-15985Y1182924D02*
X-14449Y1182941D01*
G01X-14677D02*
X-18174Y1182903D01*
G01X-14677Y1182941D02*
X-16213Y1182924D01*
G01X-19469Y1157692D02*
X-20801Y1157680D01*
G01X-19469Y1160841D02*
X-20801Y1160830D01*
G01X-19469Y1163991D02*
X-20801Y1163979D01*
G01X-19469Y1167141D02*
X-20801Y1167129D01*
G01X-19469Y1170290D02*
X-20801Y1170278D01*
G01X-19469Y1173440D02*
X-20801Y1173428D01*
G01X-19469Y1176589D02*
X-20801Y1176578D01*
G01X-19469Y1179739D02*
X-20801Y1179727D01*
G01X-19469Y1182889D02*
X-20801Y1182877D01*
G01X-15985Y1157728D02*
X-17126Y1157717D01*
G01D02*
X-18435Y1157706D01*
G01X-15985Y1160877D02*
X-17126Y1160867D01*
G01D02*
X-18435Y1160856D01*
G01X-15985Y1164027D02*
X-17126Y1164017D01*
G01D02*
X-18435Y1164005D01*
G01X-15985Y1167176D02*
X-17126Y1167166D01*
G01D02*
X-18435Y1167155D01*
G01X-15985Y1170326D02*
X-17126Y1170316D01*
G01D02*
X-18435Y1170304D01*
G01X-15985Y1173476D02*
X-17126Y1173465D01*
G01D02*
X-18435Y1173454D01*
G01X-15985Y1176625D02*
X-17126Y1176615D01*
G01X-18435Y1176604D02*
X-17126Y1176615D01*
G01X-15985Y1179775D02*
X-17126Y1179765D01*
G01D02*
X-18435Y1179753D01*
G01X-15985Y1182924D02*
X-17126Y1182914D01*
G01D02*
X-18435Y1182903D01*
G01X-13009Y1159614D02*
X-14147D01*
G01X12410Y1159811D02*
X315D01*
G01X-14449Y1159909D02*
X-14677D01*
G01X-15985Y1159926D02*
X-16213D01*
G01X-18174Y1159947D02*
X-18435D01*
G01X-18174Y1160856D02*
X-18435D01*
G01X-15985Y1160877D02*
X-16213D01*
G01X-14449Y1160894D02*
X-14677D01*
G01X12410Y1160992D02*
X315D01*
G01X-13009Y1161189D02*
X-14147D01*
G01X512Y1161583D02*
X0D01*
G01X512Y1162370D02*
X0D01*
G01X-13009Y1162764D02*
X-14147D01*
G01X12410Y1162961D02*
X315D01*
G01X-14449Y1163059D02*
X-14677D01*
G01X-15985Y1163075D02*
X-16213D01*
G01X-18174Y1163097D02*
X-18435D01*
G01X-18174Y1164005D02*
X-18435D01*
G01X-15985Y1164027D02*
X-16213D01*
G01X-14449Y1164043D02*
X-14677D01*
G01X12410Y1164142D02*
X315D01*
G01X-13009Y1164339D02*
X-14147D01*
G01X512Y1164732D02*
X0D01*
G01X512Y1165520D02*
X0D01*
G01X-13009Y1165913D02*
X-14147D01*
G01X12410Y1166110D02*
X315D01*
G01X-14449Y1166209D02*
X-14677D01*
G01X-15985Y1166225D02*
X-16213D01*
G01X-18174Y1166246D02*
X-18435D01*
G01X-18174Y1167155D02*
X-18435D01*
G01X-15985Y1167176D02*
X-16213D01*
G01X-14449Y1167193D02*
X-14677D01*
G01X12410Y1167291D02*
X315D01*
G01X-13009Y1167488D02*
X-14147D01*
G01X512Y1167882D02*
X0D01*
G01X512Y1168669D02*
X0D01*
G01X-13009Y1169063D02*
X-14147D01*
G01X12410Y1169260D02*
X315D01*
G01X-14449Y1169358D02*
X-14677D01*
G01X-15985Y1169374D02*
X-16213D01*
G01X-18174Y1169396D02*
X-18435D01*
G01X-18174Y1170304D02*
X-18435D01*
G01X-15985Y1170326D02*
X-16213D01*
G01X-14449Y1170343D02*
X-14677D01*
G01X12410Y1170441D02*
X315D01*
G01X-13009Y1170638D02*
X-14147D01*
G01X512Y1171031D02*
X0D01*
G01X512Y1171819D02*
X0D01*
G01X-13009Y1172213D02*
X-14147D01*
G01X12410Y1172409D02*
X315D01*
G01X-14449Y1172508D02*
X-14677D01*
G01X-15985Y1172524D02*
X-16213D01*
G01X-18174Y1172546D02*
X-18435D01*
G01X-18174Y1173454D02*
X-18435D01*
G01X-15985Y1173476D02*
X-16213D01*
G01X-14449Y1173492D02*
X-14677D01*
G01X12410Y1173591D02*
X315D01*
G01X-13009Y1173787D02*
X-14147D01*
G01X512Y1174181D02*
X0D01*
G01X512Y1174969D02*
X0D01*
G01X-13009Y1175362D02*
X-14147D01*
G01X12410Y1175559D02*
X315D01*
G01X-14449Y1175657D02*
X-14677D01*
G01X-15985Y1175674D02*
X-16213D01*
G01X-18174Y1175695D02*
X-18435D01*
G01X-18174Y1176604D02*
X-18435D01*
G01X-15985Y1176625D02*
X-16213D01*
G01X-14449Y1176642D02*
X-14677D01*
G01X12410Y1176740D02*
X315D01*
G01X-13009Y1176937D02*
X-14147D01*
G01X512Y1177331D02*
X0D01*
G01X512Y1178118D02*
X0D01*
G01X-13009Y1178512D02*
X-14147D01*
G01X12410Y1178709D02*
X315D01*
G01X-14449Y1178807D02*
X-14677D01*
G01X-15985Y1178823D02*
X-16213D01*
G01X-18174Y1178845D02*
X-18435D01*
G01X-18174Y1179753D02*
X-18435D01*
G01X-15985Y1179775D02*
X-16213D01*
G01X-14449Y1179791D02*
X-14677D01*
G01X12410Y1179890D02*
X315D01*
G01X-13009Y1180087D02*
X-14147D01*
G01X512Y1180480D02*
X0D01*
G01X512Y1181268D02*
X0D01*
G01X-13009Y1181661D02*
X-14147D01*
G01X12410Y1181858D02*
X315D01*
G01X-14449Y1181957D02*
X-14677D01*
G01X-15985Y1181973D02*
X-16213D01*
G01X-18174Y1181994D02*
X-18435D01*
G01X-18174Y1182903D02*
X-18435D01*
G01X-15985Y1182924D02*
X-16213D01*
G01X-14449Y1182941D02*
X-14677D01*
G01X12410Y1183039D02*
X315D01*
G01X-13009Y1183236D02*
X-14147D01*
G01X512Y1183630D02*
X0D01*
G01X512Y1184417D02*
X0D01*
G01X-13009Y1184811D02*
X-14147D01*
G01X12410Y1185008D02*
X315D01*
G01X-14449Y1185106D02*
X-14677D01*
G01X-15985Y1185122D02*
X-16213D01*
G01X-18174Y1185144D02*
X-18435D01*
G01X-19469Y1166261D02*
X-20801Y1166273D01*
G01X-15985Y1166225D02*
X-18435Y1166246D01*
G01X-19469Y1169411D02*
X-20801Y1169422D01*
G01X-15985Y1169374D02*
X-18435Y1169396D01*
G01X-19469Y1172560D02*
X-20801Y1172572D01*
G01X-15985Y1172524D02*
X-18435Y1172546D01*
G01X-19469Y1175710D02*
X-20801Y1175722D01*
G01X-15985Y1175674D02*
X-18435Y1175695D01*
G01X-19469Y1178859D02*
X-20801Y1178871D01*
G01X-15985Y1178823D02*
X-18435Y1178845D01*
G01X-19469Y1182009D02*
X-20801Y1182021D01*
G01X-15985Y1181973D02*
X-18435Y1181994D01*
G01X-19469Y1185159D02*
X-20801Y1185170D01*
G01X-15985Y1185122D02*
X-18435Y1185144D01*
G01X-15985Y1166225D02*
X-14449Y1166209D01*
G01X-15985Y1169374D02*
X-14449Y1169358D01*
G01X-15985Y1172524D02*
X-14449Y1172508D01*
G01X-15985Y1175674D02*
X-14449Y1175657D01*
G01X-15985Y1178823D02*
X-14449Y1178807D01*
G01X-15985Y1181973D02*
X-14449Y1181957D01*
G01X-15985Y1185122D02*
X-14449Y1185106D01*
G01X-18435Y1166246D02*
X-20801Y1166273D01*
G01X-18435Y1169396D02*
X-20801Y1169422D01*
G01X-18435Y1172546D02*
X-20801Y1172572D01*
G01X-18435Y1175695D02*
X-20801Y1175722D01*
G01X-18435Y1178845D02*
X-20801Y1178871D01*
G01X-18435Y1181994D02*
X-20801Y1182021D01*
G01X-18435Y1185144D02*
X-20801Y1185170D01*
G01X-19469Y1166261D02*
X-16213Y1166225D01*
G01X-18174Y1166246D02*
X-14677Y1166209D01*
G01X-19469Y1169411D02*
X-16213Y1169374D01*
G01X-18174Y1169396D02*
X-14677Y1169358D01*
G01X-19469Y1172560D02*
X-16213Y1172524D01*
G01X-18174Y1172546D02*
X-14677Y1172508D01*
G01X-19469Y1175710D02*
X-16213Y1175674D01*
G01X-18174Y1175695D02*
X-14677Y1175657D01*
G01X-19469Y1178859D02*
X-16213Y1178823D01*
G01X-18174Y1178845D02*
X-14677Y1178807D01*
G01X-19469Y1182009D02*
X-16213Y1181973D01*
G01X-18174Y1181994D02*
X-14677Y1181957D01*
G01X-19469Y1185159D02*
X-16213Y1185122D01*
G01X-18174Y1185144D02*
X-14677Y1185106D01*
G01X12634Y1223059D02*
X12416Y1222789D01*
G01X12634Y1219909D02*
X12416Y1219639D01*
G01X12057Y1223984D02*
Y1222803D01*
G01Y1220835D02*
Y1219654D01*
G01Y1214535D02*
Y1213354D01*
G01Y1217685D02*
Y1216504D01*
G01X12410Y1223984D02*
Y1222803D01*
G01Y1220835D02*
Y1219654D01*
G01Y1214535D02*
Y1213354D01*
G01Y1217685D02*
Y1216504D01*
G01X13353Y1223728D02*
Y1223059D01*
G01Y1220579D02*
Y1219909D01*
G01Y1214280D02*
Y1213610D01*
G01Y1217429D02*
Y1216760D01*
G01X13701Y1223728D02*
Y1223059D01*
G01Y1220579D02*
Y1219909D01*
G01Y1214280D02*
Y1213610D01*
G01Y1217429D02*
Y1216760D01*
G01X12634D02*
X12416Y1216490D01*
G01X12634Y1213610D02*
X12416Y1213340D01*
G01X12287Y1223059D02*
X12057Y1222803D01*
G01X12287Y1219909D02*
X12057Y1219654D01*
G01X12287Y1216760D02*
X12057Y1216504D01*
G01X12287Y1213610D02*
X12057Y1213354D01*
G01Y1214535D02*
X12287Y1214280D01*
G01X12057Y1217685D02*
X12287Y1217429D01*
G01X12057Y1220835D02*
X12287Y1220579D01*
G01X12416Y1214550D02*
X12634Y1214280D01*
G01X12416Y1217699D02*
X12634Y1217429D01*
G01X12416Y1220849D02*
X12634Y1220579D01*
G01X12416Y1223998D02*
X12634Y1223728D01*
G01X12057Y1223984D02*
X12287Y1223728D01*
G01X13701Y1213610D02*
X12287D01*
G01X13701Y1214280D02*
X12287D01*
G01X13701Y1216760D02*
X12287D01*
G01X13701Y1217429D02*
X12287D01*
G01X13701Y1219909D02*
X12287D01*
G01X13701Y1220579D02*
X12287D01*
G01X13701Y1223059D02*
X12287D01*
G01X13701Y1223728D02*
X12287D01*
G01X12634Y1282902D02*
X12416Y1282631D01*
G01X12634Y1279752D02*
X12416Y1279482D01*
G01X12634Y1276602D02*
X12416Y1276332D01*
G01X12634Y1273453D02*
X12416Y1273183D01*
G01X12634Y1270303D02*
X12416Y1270033D01*
G01X12634Y1267154D02*
X12416Y1266883D01*
G01X12634Y1264004D02*
X12416Y1263734D01*
G01X12634Y1260854D02*
X12416Y1260584D01*
G01X12634Y1257705D02*
X12416Y1257435D01*
G01X12634Y1254555D02*
X12416Y1254285D01*
G01X12634Y1251406D02*
X12416Y1251135D01*
G01X12634Y1248256D02*
X12416Y1247986D01*
G01X12287Y1282902D02*
X12057Y1282646D01*
G01X12287Y1279752D02*
X12057Y1279496D01*
G01X12287Y1276602D02*
X12057Y1276346D01*
G01X12287Y1273453D02*
X12057Y1273197D01*
G01X12287Y1270303D02*
X12057Y1270047D01*
G01X12287Y1267154D02*
X12057Y1266898D01*
G01X12287Y1264004D02*
X12057Y1263748D01*
G01X12287Y1260854D02*
X12057Y1260598D01*
G01X12287Y1257705D02*
X12057Y1257449D01*
G01X12287Y1254555D02*
X12057Y1254299D01*
G01X12287Y1251406D02*
X12057Y1251150D01*
G01X12287Y1248256D02*
X12057Y1248000D01*
G01Y1283827D02*
Y1282646D01*
G01Y1280677D02*
Y1279496D01*
G01Y1274378D02*
Y1273197D01*
G01Y1277528D02*
Y1276346D01*
G01Y1271228D02*
Y1270047D01*
G01Y1268079D02*
Y1266898D01*
G01Y1261780D02*
Y1260598D01*
G01Y1264929D02*
Y1263748D01*
G01Y1258630D02*
Y1257449D01*
G01Y1252331D02*
Y1251150D01*
G01Y1255480D02*
Y1254299D01*
G01Y1249181D02*
Y1248000D01*
G01X12410Y1283827D02*
Y1282646D01*
G01Y1280677D02*
Y1279496D01*
G01Y1274378D02*
Y1273197D01*
G01Y1277528D02*
Y1276346D01*
G01Y1271228D02*
Y1270047D01*
G01Y1268079D02*
Y1266898D01*
G01Y1261780D02*
Y1260598D01*
G01Y1264929D02*
Y1263748D01*
G01Y1258630D02*
Y1257449D01*
G01Y1252331D02*
Y1251150D01*
G01Y1255480D02*
Y1254299D01*
G01Y1249181D02*
Y1248000D01*
G01X13353Y1280421D02*
Y1279752D01*
G01Y1283571D02*
Y1282902D01*
G01Y1277272D02*
Y1276602D01*
G01Y1270972D02*
Y1270303D01*
G01Y1274122D02*
Y1273453D01*
G01Y1267823D02*
Y1267154D01*
G01Y1261524D02*
Y1260854D01*
G01Y1264673D02*
Y1264004D01*
G01Y1258374D02*
Y1257705D01*
G01Y1252075D02*
Y1251406D01*
G01Y1255224D02*
Y1254555D01*
G01Y1248925D02*
Y1248256D01*
G01X13701Y1280421D02*
Y1279752D01*
G01Y1283571D02*
Y1282902D01*
G01Y1277272D02*
Y1276602D01*
G01Y1270972D02*
Y1270303D01*
G01Y1274122D02*
Y1273453D01*
G01Y1267823D02*
Y1267154D01*
G01Y1261524D02*
Y1260854D01*
G01Y1264673D02*
Y1264004D01*
G01Y1258374D02*
Y1257705D01*
G01Y1252075D02*
Y1251406D01*
G01Y1255224D02*
Y1254555D01*
G01Y1248925D02*
Y1248256D01*
G01X12416Y1246046D02*
X12634Y1245776D01*
G01X12416Y1249195D02*
X12634Y1248925D01*
G01X12416Y1252345D02*
X12634Y1252075D01*
G01X12416Y1255494D02*
X12634Y1255224D01*
G01X12416Y1258644D02*
X12634Y1258374D01*
G01X12416Y1261794D02*
X12634Y1261524D01*
G01X12057Y1246031D02*
X12287Y1245776D01*
G01X12057Y1249181D02*
X12287Y1248925D01*
G01X12057Y1252331D02*
X12287Y1252075D01*
G01X12057Y1255480D02*
X12287Y1255224D01*
G01X12057Y1258630D02*
X12287Y1258374D01*
G01X12057Y1261780D02*
X12287Y1261524D01*
G01X12057Y1264929D02*
X12287Y1264673D01*
G01X12057Y1268079D02*
X12287Y1267823D01*
G01X12057Y1271228D02*
X12287Y1270972D01*
G01X12057Y1274378D02*
X12287Y1274122D01*
G01X12057Y1277528D02*
X12287Y1277272D01*
G01X12057Y1280677D02*
X12287Y1280421D01*
G01X12057Y1283827D02*
X12287Y1283571D01*
G01X12416Y1264943D02*
X12634Y1264673D01*
G01X12416Y1268093D02*
X12634Y1267823D01*
G01X12416Y1271243D02*
X12634Y1270972D01*
G01X12416Y1274392D02*
X12634Y1274122D01*
G01X12416Y1277542D02*
X12634Y1277272D01*
G01X12416Y1280691D02*
X12634Y1280421D01*
G01X12416Y1283841D02*
X12634Y1283571D01*
G01X13701Y1245776D02*
X12287D01*
G01X13701Y1248256D02*
X12287D01*
G01X13701Y1248925D02*
X12287D01*
G01X13701Y1251406D02*
X12287D01*
G01X13701Y1252075D02*
X12287D01*
G01X13701Y1254555D02*
X12287D01*
G01X13701Y1255224D02*
X12287D01*
G01X13701Y1257705D02*
X12287D01*
G01X13701Y1258374D02*
X12287D01*
G01X13701Y1260854D02*
X12287D01*
G01X13701Y1261524D02*
X12287D01*
G01X13701Y1264004D02*
X12287D01*
G01X13701Y1264673D02*
X12287D01*
G01X13701Y1267154D02*
X12287D01*
G01X13701Y1267823D02*
X12287D01*
G01X13701Y1270303D02*
X12287D01*
G01X13701Y1270972D02*
X12287D01*
G01X13701Y1273453D02*
X12287D01*
G01X13701Y1274122D02*
X12287D01*
G01X13701Y1276602D02*
X12287D01*
G01X13701Y1277272D02*
X12287D01*
G01X13701Y1279752D02*
X12287D01*
G01X13701Y1280421D02*
X12287D01*
G01X13701Y1282902D02*
X12287D01*
G01X13701Y1283571D02*
X12287D01*
G01X12634Y1245106D02*
X12416Y1244836D01*
G01X12634Y1229358D02*
X12416Y1229088D01*
G01X12634Y1226209D02*
X12416Y1225939D01*
G01X12287Y1245106D02*
X12057Y1244850D01*
G01X12287Y1229358D02*
X12057Y1229102D01*
G01Y1246031D02*
Y1244850D01*
G01Y1230283D02*
Y1229102D01*
G01Y1227134D02*
Y1225953D01*
G01X12410Y1246031D02*
Y1244850D01*
G01Y1230283D02*
Y1229102D01*
G01Y1227134D02*
Y1225953D01*
G01X13353Y1245776D02*
Y1245106D01*
G01Y1230028D02*
Y1229358D01*
G01Y1226878D02*
Y1226209D01*
G01X13701Y1245776D02*
Y1245106D01*
G01Y1230028D02*
Y1229358D01*
G01Y1226878D02*
Y1226209D01*
G01X19685Y1239535D02*
Y1235598D01*
G01X12287Y1226209D02*
X12057Y1225953D01*
G01X19685Y1235598D02*
X17717Y1233630D01*
G01X12416Y1227148D02*
X12634Y1226878D01*
G01X12416Y1230298D02*
X12634Y1230028D01*
G01X17717Y1241504D02*
X19685Y1239535D01*
G01X12057Y1227134D02*
X12287Y1226878D01*
G01X12057Y1230283D02*
X12287Y1230028D01*
G01X13701Y1226209D02*
X12287D01*
G01X13701Y1226878D02*
X12287D01*
G01X13701Y1229358D02*
X12287D01*
G01X13701Y1230028D02*
X12287D01*
G01X13701Y1245106D02*
X12287D01*
G01X17323Y1233236D02*
G03Y1241898I0J4331D01*
G01X39236Y1248957D02*
X35827Y1246988D01*
G01Y1245256D02*
Y1246988D01*
G01Y1245256D02*
X40551Y1240610D01*
G01X35827Y1246359D02*
X40547Y1241718D01*
G01X-20801Y1223822D02*
Y1222966D01*
G01Y1220672D02*
Y1219816D01*
G01Y1214373D02*
Y1213517D01*
G01Y1217522D02*
Y1216667D01*
G01X-19469Y1223828D02*
Y1222960D01*
G01Y1220678D02*
Y1219810D01*
G01Y1214379D02*
Y1213511D01*
G01Y1217528D02*
Y1216661D01*
G01X-18435Y1223848D02*
Y1222939D01*
G01Y1220698D02*
Y1219790D01*
G01Y1214399D02*
Y1213491D01*
G01Y1217548D02*
Y1216640D01*
G01X-18174Y1223848D02*
Y1222939D01*
G01Y1220698D02*
Y1219790D01*
G01Y1214399D02*
Y1213491D01*
G01Y1217548D02*
Y1216640D01*
G01X-16213Y1223869D02*
Y1222918D01*
G01Y1220720D02*
Y1219768D01*
G01Y1214420D02*
Y1213469D01*
G01Y1217570D02*
Y1216619D01*
G01X-15985Y1223869D02*
Y1222918D01*
G01Y1220720D02*
Y1219768D01*
G01Y1214420D02*
Y1213469D01*
G01Y1217570D02*
Y1216619D01*
G01X-14537Y1223974D02*
Y1222814D01*
G01Y1220824D02*
Y1219664D01*
G01Y1214525D02*
Y1213365D01*
G01Y1217674D02*
Y1216515D01*
G01X-13009Y1224181D02*
Y1222606D01*
G01Y1221031D02*
Y1219457D01*
G01Y1214732D02*
Y1213157D01*
G01Y1217882D02*
Y1216307D01*
G01X315Y1224575D02*
Y1223984D01*
G01Y1218276D02*
Y1217685D01*
G01Y1221425D02*
Y1220835D01*
G01Y1219654D02*
Y1219063D01*
G01Y1222803D02*
Y1222213D01*
G01Y1215126D02*
Y1214535D01*
G01Y1216504D02*
Y1215913D01*
G01Y1213354D02*
Y1212764D01*
G01X512Y1224575D02*
Y1223984D01*
G01Y1218276D02*
Y1217685D01*
G01Y1221425D02*
Y1220835D01*
G01Y1219654D02*
Y1219063D01*
G01Y1222803D02*
Y1222213D01*
G01Y1215126D02*
Y1214535D01*
G01Y1216504D02*
Y1215913D01*
G01Y1213354D02*
Y1212764D01*
G01X709Y1223984D02*
Y1222803D01*
G01Y1220835D02*
Y1219654D01*
G01Y1214535D02*
Y1213354D01*
G01Y1217685D02*
Y1216504D01*
G01X1074Y1223984D02*
Y1222803D01*
G01Y1220835D02*
Y1219654D01*
G01Y1214535D02*
Y1213354D01*
G01Y1217685D02*
Y1216504D01*
G01X1184Y1223984D02*
Y1222803D01*
G01Y1220835D02*
Y1219654D01*
G01Y1214535D02*
Y1213354D01*
G01Y1217685D02*
Y1216504D01*
G01X9965Y1223984D02*
Y1222803D01*
G01Y1220835D02*
Y1219654D01*
G01Y1214535D02*
Y1213354D01*
G01Y1217685D02*
Y1216504D01*
G01X10075Y1223984D02*
Y1222803D01*
G01Y1220835D02*
Y1219654D01*
G01Y1214535D02*
Y1213354D01*
G01Y1217685D02*
Y1216504D01*
G01X-14537Y1223974D02*
X-14677Y1223886D01*
G01X-13977Y1224181D02*
X-14449Y1223886D01*
G01X-14537Y1220824D02*
X-14677Y1220736D01*
G01X-13977Y1221031D02*
X-14449Y1220736D01*
G01X-14537Y1217674D02*
X-14677Y1217587D01*
G01X-13977Y1217882D02*
X-14449Y1217587D01*
G01X-14537Y1214525D02*
X-14677Y1214437D01*
G01X-13977Y1214732D02*
X-14449Y1214437D01*
G01X-14147Y1224181D02*
X-14537Y1223974D01*
G01X-14147Y1221031D02*
X-14537Y1220824D01*
G01X-14147Y1217882D02*
X-14537Y1217674D01*
G01X-14147Y1214732D02*
X-14537Y1214525D01*
G01X-14677Y1213453D02*
X-14537Y1213365D01*
G01X-14449Y1213453D02*
X-13977Y1213157D01*
G01X-14677Y1216602D02*
X-14537Y1216515D01*
G01X-14449Y1216602D02*
X-13977Y1216307D01*
G01X-14677Y1219752D02*
X-14537Y1219664D01*
G01X-14449Y1219752D02*
X-13977Y1219457D01*
G01X-14677Y1222902D02*
X-14537Y1222814D01*
G01X-14449Y1222902D02*
X-13977Y1222606D01*
G01X-14537Y1213365D02*
X-14147Y1213157D01*
G01X-14537Y1216515D02*
X-14147Y1216307D01*
G01X-14537Y1219664D02*
X-14147Y1219457D01*
G01X-14537Y1222814D02*
X-14147Y1222606D01*
G01X-19469Y1214385D02*
X-18174Y1214399D01*
G01X-18435D02*
X-20801Y1214373D01*
G01X-18174Y1214399D02*
X-17126Y1214410D01*
G01X-19469Y1217534D02*
X-18174Y1217548D01*
G01X-18435D02*
X-20801Y1217522D01*
G01X-18174Y1217548D02*
X-17126Y1217560D01*
G01X-19469Y1220684D02*
X-18174Y1220698D01*
G01X-18435D02*
X-20801Y1220672D01*
G01X-18174Y1220698D02*
X-17126Y1220709D01*
G01X-19469Y1223833D02*
X-18174Y1223848D01*
G01X-18435D02*
X-20801Y1223822D01*
G01X-18174Y1223848D02*
X-17126Y1223859D01*
G01X-15985Y1214420D02*
X-14449Y1214437D01*
G01X-14677D02*
X-18174Y1214399D01*
G01X-14677Y1214437D02*
X-16213Y1214420D01*
G01X-15985Y1217570D02*
X-14449Y1217587D01*
G01X-14677D02*
X-18174Y1217548D01*
G01X-14677Y1217587D02*
X-16213Y1217570D01*
G01X-15985Y1220720D02*
X-14449Y1220736D01*
G01X-14677D02*
X-18174Y1220698D01*
G01X-14677Y1220736D02*
X-16213Y1220720D01*
G01X-15985Y1223869D02*
X-14449Y1223886D01*
G01X-14677D02*
X-18174Y1223848D01*
G01X-14677Y1223886D02*
X-16213Y1223869D01*
G01X-19469Y1214385D02*
X-20801Y1214373D01*
G01X-19469Y1217534D02*
X-20801Y1217522D01*
G01X-19469Y1220684D02*
X-20801Y1220672D01*
G01X-19469Y1223833D02*
X-20801Y1223822D01*
G01X-15985Y1214420D02*
X-17126Y1214410D01*
G01D02*
X-18435Y1214399D01*
G01X-15985Y1217570D02*
X-17126Y1217560D01*
G01D02*
X-18435Y1217548D01*
G01X-15985Y1220720D02*
X-17126Y1220709D01*
G01D02*
X-18435Y1220698D01*
G01X-15985Y1223869D02*
X-17126Y1223859D01*
G01D02*
X-18435Y1223848D01*
G01X512Y1211976D02*
X0D01*
G01X512Y1212764D02*
X0D01*
G01X-13009Y1213157D02*
X-14147D01*
G01X12410Y1213354D02*
X315D01*
G01X-14449Y1213453D02*
X-14677D01*
G01X-15985Y1213469D02*
X-16213D01*
G01X-18174Y1213491D02*
X-18435D01*
G01X-18174Y1214399D02*
X-18435D01*
G01X-15985Y1214420D02*
X-16213D01*
G01X-14449Y1214437D02*
X-14677D01*
G01X12410Y1214535D02*
X315D01*
G01X-13009Y1214732D02*
X-14147D01*
G01X512Y1215126D02*
X0D01*
G01X512Y1215913D02*
X0D01*
G01X-13009Y1216307D02*
X-14147D01*
G01X12410Y1216504D02*
X315D01*
G01X-14449Y1216602D02*
X-14677D01*
G01X-15985Y1216619D02*
X-16213D01*
G01X-18174Y1216640D02*
X-18435D01*
G01X-18174Y1217548D02*
X-18435D01*
G01X-15985Y1217570D02*
X-16213D01*
G01X-14449Y1217587D02*
X-14677D01*
G01X12410Y1217685D02*
X315D01*
G01X-13009Y1217882D02*
X-14147D01*
G01X512Y1218276D02*
X0D01*
G01X512Y1219063D02*
X0D01*
G01X-13009Y1219457D02*
X-14147D01*
G01X12410Y1219654D02*
X315D01*
G01X-14449Y1219752D02*
X-14677D01*
G01X-15985Y1219768D02*
X-16213D01*
G01X-18174Y1219790D02*
X-18435D01*
G01X-18174Y1220698D02*
X-18435D01*
G01X-15985Y1220720D02*
X-16213D01*
G01X-14449Y1220736D02*
X-14677D01*
G01X12410Y1220835D02*
X315D01*
G01X-13009Y1221031D02*
X-14147D01*
G01X512Y1221425D02*
X0D01*
G01X512Y1222213D02*
X0D01*
G01X-13009Y1222606D02*
X-14147D01*
G01X12410Y1222803D02*
X315D01*
G01X-14449Y1222902D02*
X-14677D01*
G01X-15985Y1222918D02*
X-16213D01*
G01X-18174Y1222939D02*
X-18435D01*
G01X-18174Y1223848D02*
X-18435D01*
G01X-16213Y1223869D02*
X-15985D01*
G01X-14449Y1223886D02*
X-14677D01*
G01X12410Y1223984D02*
X315D01*
G01X-13009Y1224181D02*
X-14147D01*
G01X512Y1224575D02*
X0D01*
G01X-19469Y1213505D02*
X-20801Y1213517D01*
G01X-15985Y1213469D02*
X-18435Y1213491D01*
G01X-19469Y1216655D02*
X-20801Y1216667D01*
G01X-15985Y1216619D02*
X-18435Y1216640D01*
G01X-19469Y1219804D02*
X-20801Y1219816D01*
G01X-15985Y1219768D02*
X-18435Y1219790D01*
G01X-19469Y1222954D02*
X-20801Y1222966D01*
G01X-15985Y1222918D02*
X-18435Y1222939D01*
G01X-15985Y1213469D02*
X-14449Y1213453D01*
G01X-15985Y1216619D02*
X-14449Y1216602D01*
G01X-15985Y1219768D02*
X-14449Y1219752D01*
G01X-15985Y1222918D02*
X-14449Y1222902D01*
G01X-18435Y1213491D02*
X-20801Y1213517D01*
G01X-18435Y1216640D02*
X-20801Y1216667D01*
G01X-18435Y1219790D02*
X-20801Y1219816D01*
G01X-18435Y1222939D02*
X-20801Y1222966D01*
G01X-19469Y1213505D02*
X-16213Y1213469D01*
G01X-18174Y1213491D02*
X-14677Y1213453D01*
G01X-19469Y1216655D02*
X-16213Y1216619D01*
G01X-18174Y1216640D02*
X-14677Y1216602D01*
G01X-19469Y1219804D02*
X-16213Y1219768D01*
G01X-18174Y1219790D02*
X-14677Y1219752D01*
G01X-19469Y1222954D02*
X-16213Y1222918D01*
G01X-18174Y1222939D02*
X-14677Y1222902D01*
G01X-20801Y1283664D02*
Y1282808D01*
G01Y1280515D02*
Y1279659D01*
G01Y1277365D02*
Y1276509D01*
G01Y1271066D02*
Y1270210D01*
G01Y1274215D02*
Y1273359D01*
G01Y1267916D02*
Y1267060D01*
G01Y1261617D02*
Y1260761D01*
G01Y1264767D02*
Y1263911D01*
G01Y1258467D02*
Y1257611D01*
G01Y1252168D02*
Y1251312D01*
G01Y1255318D02*
Y1254462D01*
G01Y1249019D02*
Y1248163D01*
G01X-19469Y1283670D02*
Y1282802D01*
G01Y1280520D02*
Y1279653D01*
G01Y1277371D02*
Y1276503D01*
G01Y1271072D02*
Y1270204D01*
G01Y1274221D02*
Y1273354D01*
G01Y1267922D02*
Y1267054D01*
G01Y1261623D02*
Y1260755D01*
G01Y1264772D02*
Y1263905D01*
G01Y1258473D02*
Y1257606D01*
G01Y1252174D02*
Y1251306D01*
G01Y1255324D02*
Y1254456D01*
G01Y1249024D02*
Y1248157D01*
G01X-18435Y1283690D02*
Y1282782D01*
G01Y1280541D02*
Y1279632D01*
G01Y1277391D02*
Y1276483D01*
G01Y1271092D02*
Y1270183D01*
G01Y1274241D02*
Y1273333D01*
G01Y1267942D02*
Y1267034D01*
G01Y1261643D02*
Y1260735D01*
G01Y1264793D02*
Y1263884D01*
G01Y1258493D02*
Y1257585D01*
G01Y1252194D02*
Y1251286D01*
G01Y1255344D02*
Y1254435D01*
G01Y1249044D02*
Y1248136D01*
G01X-18174Y1283690D02*
Y1282782D01*
G01Y1280541D02*
Y1279632D01*
G01Y1277391D02*
Y1276483D01*
G01Y1271092D02*
Y1270183D01*
G01Y1274241D02*
Y1273333D01*
G01Y1267942D02*
Y1267034D01*
G01Y1261643D02*
Y1260735D01*
G01Y1264793D02*
Y1263884D01*
G01Y1258493D02*
Y1257585D01*
G01Y1252194D02*
Y1251286D01*
G01Y1255344D02*
Y1254435D01*
G01Y1249044D02*
Y1248136D01*
G01X-16213Y1283712D02*
Y1282760D01*
G01Y1280562D02*
Y1279611D01*
G01Y1277413D02*
Y1276461D01*
G01Y1271113D02*
Y1270162D01*
G01Y1274263D02*
Y1273311D01*
G01Y1267964D02*
Y1267012D01*
G01Y1261665D02*
Y1260713D01*
G01Y1264814D02*
Y1263863D01*
G01Y1258515D02*
Y1257563D01*
G01Y1252216D02*
Y1251264D01*
G01Y1255365D02*
Y1254414D01*
G01Y1249066D02*
Y1248115D01*
G01X-15985Y1283712D02*
Y1282760D01*
G01Y1280562D02*
Y1279611D01*
G01Y1277413D02*
Y1276461D01*
G01Y1271113D02*
Y1270162D01*
G01Y1274263D02*
Y1273311D01*
G01Y1267964D02*
Y1267012D01*
G01Y1261665D02*
Y1260713D01*
G01Y1264814D02*
Y1263863D01*
G01Y1258515D02*
Y1257563D01*
G01Y1252216D02*
Y1251264D01*
G01Y1255365D02*
Y1254414D01*
G01Y1249066D02*
Y1248115D01*
G01X-14537Y1283816D02*
Y1282656D01*
G01Y1280667D02*
Y1279507D01*
G01Y1274367D02*
Y1273207D01*
G01Y1277517D02*
Y1276357D01*
G01Y1271218D02*
Y1270058D01*
G01Y1268068D02*
Y1266908D01*
G01Y1261769D02*
Y1260609D01*
G01Y1264919D02*
Y1263759D01*
G01Y1258619D02*
Y1257459D01*
G01Y1252320D02*
Y1251160D01*
G01Y1255470D02*
Y1254310D01*
G01Y1249170D02*
Y1248011D01*
G01X-13009Y1284024D02*
Y1282449D01*
G01Y1280874D02*
Y1279299D01*
G01Y1274575D02*
Y1273000D01*
G01Y1277724D02*
Y1276150D01*
G01Y1271425D02*
Y1269850D01*
G01Y1265126D02*
Y1263551D01*
G01Y1268276D02*
Y1266701D01*
G01Y1261976D02*
Y1260402D01*
G01Y1255677D02*
Y1254102D01*
G01Y1258827D02*
Y1257252D01*
G01Y1252528D02*
Y1250953D01*
G01Y1249378D02*
Y1247803D01*
G01X315Y1284417D02*
Y1283827D01*
G01Y1281268D02*
Y1280677D01*
G01Y1279496D02*
Y1278906D01*
G01Y1282646D02*
Y1282055D01*
G01Y1274969D02*
Y1274378D01*
G01Y1278118D02*
Y1277528D01*
G01Y1276346D02*
Y1275756D01*
G01Y1271819D02*
Y1271228D01*
G01Y1270047D02*
Y1269457D01*
G01Y1273197D02*
Y1272606D01*
G01Y1265520D02*
Y1264929D01*
G01Y1268669D02*
Y1268079D01*
G01Y1266898D02*
Y1266307D01*
G01Y1262370D02*
Y1261780D01*
G01Y1260598D02*
Y1260008D01*
G01Y1263748D02*
Y1263157D01*
G01Y1256071D02*
Y1255480D01*
G01Y1259220D02*
Y1258630D01*
G01Y1257449D02*
Y1256858D01*
G01Y1252921D02*
Y1252331D01*
G01Y1251150D02*
Y1250559D01*
G01Y1254299D02*
Y1253709D01*
G01Y1246622D02*
Y1246031D01*
G01Y1249772D02*
Y1249181D01*
G01Y1248000D02*
Y1247409D01*
G01X512Y1284417D02*
Y1283827D01*
G01Y1281268D02*
Y1280677D01*
G01Y1279496D02*
Y1278906D01*
G01Y1282646D02*
Y1282055D01*
G01Y1274969D02*
Y1274378D01*
G01Y1278118D02*
Y1277528D01*
G01Y1276346D02*
Y1275756D01*
G01Y1271819D02*
Y1271228D01*
G01Y1270047D02*
Y1269457D01*
G01Y1273197D02*
Y1272606D01*
G01Y1265520D02*
Y1264929D01*
G01Y1268669D02*
Y1268079D01*
G01Y1266898D02*
Y1266307D01*
G01Y1262370D02*
Y1261780D01*
G01Y1260598D02*
Y1260008D01*
G01Y1263748D02*
Y1263157D01*
G01Y1256071D02*
Y1255480D01*
G01Y1259220D02*
Y1258630D01*
G01Y1257449D02*
Y1256858D01*
G01Y1252921D02*
Y1252331D01*
G01Y1251150D02*
Y1250559D01*
G01Y1254299D02*
Y1253709D01*
G01Y1246622D02*
Y1246031D01*
G01Y1249772D02*
Y1249181D01*
G01Y1248000D02*
Y1247409D01*
G01X709Y1283827D02*
Y1282646D01*
G01Y1280677D02*
Y1279496D01*
G01Y1274378D02*
Y1273197D01*
G01Y1277528D02*
Y1276346D01*
G01Y1271228D02*
Y1270047D01*
G01Y1268079D02*
Y1266898D01*
G01Y1261780D02*
Y1260598D01*
G01Y1264929D02*
Y1263748D01*
G01Y1258630D02*
Y1257449D01*
G01Y1252331D02*
Y1251150D01*
G01Y1255480D02*
Y1254299D01*
G01Y1249181D02*
Y1248000D01*
G01X1074Y1283827D02*
Y1282646D01*
G01Y1280677D02*
Y1279496D01*
G01Y1274378D02*
Y1273197D01*
G01Y1277528D02*
Y1276346D01*
G01Y1271228D02*
Y1270047D01*
G01Y1268079D02*
Y1266898D01*
G01Y1261780D02*
Y1260598D01*
G01Y1264929D02*
Y1263748D01*
G01Y1258630D02*
Y1257449D01*
G01Y1252331D02*
Y1251150D01*
G01Y1255480D02*
Y1254299D01*
G01Y1249181D02*
Y1248000D01*
G01X1184Y1283827D02*
Y1282646D01*
G01Y1280677D02*
Y1279496D01*
G01Y1274378D02*
Y1273197D01*
G01Y1277528D02*
Y1276346D01*
G01Y1271228D02*
Y1270047D01*
G01Y1268079D02*
Y1266898D01*
G01Y1261780D02*
Y1260598D01*
G01Y1264929D02*
Y1263748D01*
G01Y1258630D02*
Y1257449D01*
G01Y1252331D02*
Y1251150D01*
G01Y1255480D02*
Y1254299D01*
G01Y1249181D02*
Y1248000D01*
G01X9965Y1283827D02*
Y1282646D01*
G01Y1280677D02*
Y1279496D01*
G01Y1274378D02*
Y1273197D01*
G01Y1277528D02*
Y1276346D01*
G01Y1271228D02*
Y1270047D01*
G01Y1268079D02*
Y1266898D01*
G01Y1261780D02*
Y1260598D01*
G01Y1264929D02*
Y1263748D01*
G01Y1258630D02*
Y1257449D01*
G01Y1252331D02*
Y1251150D01*
G01Y1255480D02*
Y1254299D01*
G01Y1249181D02*
Y1248000D01*
G01X10075Y1283827D02*
Y1282646D01*
G01Y1280677D02*
Y1279496D01*
G01Y1274378D02*
Y1273197D01*
G01Y1277528D02*
Y1276346D01*
G01Y1271228D02*
Y1270047D01*
G01Y1268079D02*
Y1266898D01*
G01Y1261780D02*
Y1260598D01*
G01Y1264929D02*
Y1263748D01*
G01Y1258630D02*
Y1257449D01*
G01Y1252331D02*
Y1251150D01*
G01Y1255480D02*
Y1254299D01*
G01Y1249181D02*
Y1248000D01*
G01X-14537Y1283816D02*
X-14677Y1283728D01*
G01X-13977Y1284024D02*
X-14449Y1283728D01*
G01X-14537Y1280667D02*
X-14677Y1280579D01*
G01X-13977Y1280874D02*
X-14449Y1280579D01*
G01X-14537Y1277517D02*
X-14677Y1277429D01*
G01X-13977Y1277724D02*
X-14449Y1277429D01*
G01X-14537Y1274367D02*
X-14677Y1274280D01*
G01X-13977Y1274575D02*
X-14449Y1274280D01*
G01X-14537Y1271218D02*
X-14677Y1271130D01*
G01X-13977Y1271425D02*
X-14449Y1271130D01*
G01X-14537Y1268068D02*
X-14677Y1267980D01*
G01X-13977Y1268276D02*
X-14449Y1267980D01*
G01X-14537Y1264919D02*
X-14677Y1264831D01*
G01X-13977Y1265126D02*
X-14449Y1264831D01*
G01X-14537Y1261769D02*
X-14677Y1261681D01*
G01X-13977Y1261976D02*
X-14449Y1261681D01*
G01X-14537Y1258619D02*
X-14677Y1258531D01*
G01X-13977Y1258827D02*
X-14449Y1258531D01*
G01X-14537Y1255470D02*
X-14677Y1255382D01*
G01X-13977Y1255677D02*
X-14449Y1255382D01*
G01X-14537Y1252320D02*
X-14677Y1252232D01*
G01X-13977Y1252528D02*
X-14449Y1252232D01*
G01X-14537Y1249170D02*
X-14677Y1249083D01*
G01X-13977Y1249378D02*
X-14449Y1249083D01*
G01X-14537Y1246021D02*
X-14677Y1245933D01*
G01X-13977Y1246228D02*
X-14449Y1245933D01*
G01X-14147Y1284024D02*
X-14537Y1283816D01*
G01X-14147Y1280874D02*
X-14537Y1280667D01*
G01X-14147Y1277724D02*
X-14537Y1277517D01*
G01X-14147Y1274575D02*
X-14537Y1274367D01*
G01X-14147Y1271425D02*
X-14537Y1271218D01*
G01X-14147Y1268276D02*
X-14537Y1268068D01*
G01X-14147Y1265126D02*
X-14537Y1264919D01*
G01X-14147Y1261976D02*
X-14537Y1261769D01*
G01X-14147Y1258827D02*
X-14537Y1258619D01*
G01X-14147Y1255677D02*
X-14537Y1255470D01*
G01X-14147Y1252528D02*
X-14537Y1252320D01*
G01X-14147Y1249378D02*
X-14537Y1249170D01*
G01X-14147Y1246228D02*
X-14537Y1246021D01*
G01Y1248011D02*
X-14147Y1247803D01*
G01X-14537Y1251160D02*
X-14147Y1250953D01*
G01X-14537Y1254310D02*
X-14147Y1254102D01*
G01X-14537Y1257459D02*
X-14147Y1257252D01*
G01X-14537Y1260609D02*
X-14147Y1260402D01*
G01X-14537Y1263759D02*
X-14147Y1263551D01*
G01X-14537Y1266908D02*
X-14147Y1266701D01*
G01X-14537Y1270058D02*
X-14147Y1269850D01*
G01X-14537Y1273207D02*
X-14147Y1273000D01*
G01X-14537Y1276357D02*
X-14147Y1276150D01*
G01X-14537Y1279507D02*
X-14147Y1279299D01*
G01X-14537Y1282656D02*
X-14147Y1282449D01*
G01X-14677Y1248098D02*
X-14537Y1248011D01*
G01X-14449Y1248098D02*
X-13977Y1247803D01*
G01X-14677Y1251248D02*
X-14537Y1251160D01*
G01X-14449Y1251248D02*
X-13977Y1250953D01*
G01X-14677Y1254398D02*
X-14537Y1254310D01*
G01X-14449Y1254398D02*
X-13977Y1254102D01*
G01X-14677Y1257547D02*
X-14537Y1257459D01*
G01X-14449Y1257547D02*
X-13977Y1257252D01*
G01X-14677Y1260697D02*
X-14537Y1260609D01*
G01X-14449Y1260697D02*
X-13977Y1260402D01*
G01X-14677Y1263846D02*
X-14537Y1263759D01*
G01X-14449Y1263846D02*
X-13977Y1263551D01*
G01X-14677Y1266996D02*
X-14537Y1266908D01*
G01X-14449Y1266996D02*
X-13977Y1266701D01*
G01X-14677Y1270146D02*
X-14537Y1270058D01*
G01X-14449Y1270146D02*
X-13977Y1269850D01*
G01X-14677Y1273295D02*
X-14537Y1273207D01*
G01X-14449Y1273295D02*
X-13977Y1273000D01*
G01X-14677Y1276445D02*
X-14537Y1276357D01*
G01X-14449Y1276445D02*
X-13977Y1276150D01*
G01X-14677Y1279594D02*
X-14537Y1279507D01*
G01X-14449Y1279594D02*
X-13977Y1279299D01*
G01X-14677Y1282744D02*
X-14537Y1282656D01*
G01X-14449Y1282744D02*
X-13977Y1282449D01*
G01X-19469Y1245881D02*
X-18174Y1245895D01*
G01X-18435D02*
X-20801Y1245869D01*
G01X-18174Y1245895D02*
X-17126Y1245906D01*
G01X-19469Y1249030D02*
X-18174Y1249044D01*
G01X-18435D02*
X-20801Y1249019D01*
G01X-18174Y1249044D02*
X-17126Y1249056D01*
G01X-19469Y1252180D02*
X-18174Y1252194D01*
G01X-18435D02*
X-20801Y1252168D01*
G01X-18174Y1252194D02*
X-17126Y1252206D01*
G01X-19469Y1255330D02*
X-18174Y1255344D01*
G01X-18435D02*
X-20801Y1255318D01*
G01X-18174Y1255344D02*
X-17126Y1255355D01*
G01X-19469Y1258479D02*
X-18174Y1258493D01*
G01X-18435D02*
X-20801Y1258467D01*
G01X-18174Y1258493D02*
X-17126Y1258505D01*
G01X-19469Y1261629D02*
X-18174Y1261643D01*
G01X-18435D02*
X-20801Y1261617D01*
G01X-18174Y1261643D02*
X-17126Y1261654D01*
G01X-19469Y1264778D02*
X-18174Y1264793D01*
G01X-18435D02*
X-20801Y1264767D01*
G01X-18174Y1264793D02*
X-17126Y1264804D01*
G01X-19469Y1267928D02*
X-18174Y1267942D01*
G01X-18435D02*
X-20801Y1267916D01*
G01X-18174Y1267942D02*
X-17126Y1267954D01*
G01X-19469Y1271078D02*
X-18174Y1271092D01*
G01X-18435D02*
X-20801Y1271066D01*
G01X-18174Y1271092D02*
X-17126Y1271103D01*
G01X-19469Y1274227D02*
X-18174Y1274241D01*
G01X-18435D02*
X-20801Y1274215D01*
G01X-18174Y1274241D02*
X-17126Y1274253D01*
G01X-19469Y1277377D02*
X-18174Y1277391D01*
G01X-18435D02*
X-20801Y1277365D01*
G01X-18174Y1277391D02*
X-17126Y1277402D01*
G01X-19469Y1280526D02*
X-18174Y1280541D01*
G01X-18435D02*
X-20801Y1280515D01*
G01X-18174Y1280541D02*
X-17126Y1280552D01*
G01X-19469Y1283676D02*
X-18174Y1283690D01*
G01X-18435D02*
X-20801Y1283664D01*
G01X-18174Y1283690D02*
X-17126Y1283702D01*
G01X-15985Y1245917D02*
X-14449Y1245933D01*
G01X-14677D02*
X-18174Y1245895D01*
G01X-14677Y1245933D02*
X-16213Y1245917D01*
G01X-15985Y1249066D02*
X-14449Y1249083D01*
G01X-14677D02*
X-18174Y1249044D01*
G01X-14677Y1249083D02*
X-16213Y1249066D01*
G01X-15985Y1252216D02*
X-14449Y1252232D01*
G01X-14677D02*
X-18174Y1252194D01*
G01X-14677Y1252232D02*
X-16213Y1252216D01*
G01X-15985Y1255365D02*
X-14449Y1255382D01*
G01X-14677D02*
X-18174Y1255344D01*
G01X-14677Y1255382D02*
X-16213Y1255365D01*
G01X-15985Y1258515D02*
X-14449Y1258531D01*
G01X-14677D02*
X-18174Y1258493D01*
G01X-14677Y1258531D02*
X-16213Y1258515D01*
G01X-15985Y1261665D02*
X-14449Y1261681D01*
G01X-14677D02*
X-18174Y1261643D01*
G01X-14677Y1261681D02*
X-16213Y1261665D01*
G01X-15985Y1264814D02*
X-14449Y1264831D01*
G01X-14677D02*
X-18174Y1264793D01*
G01X-14677Y1264831D02*
X-16213Y1264814D01*
G01X-15985Y1267964D02*
X-14449Y1267980D01*
G01X-14677D02*
X-18174Y1267942D01*
G01X-14677Y1267980D02*
X-16213Y1267964D01*
G01X-15985Y1271113D02*
X-14449Y1271130D01*
G01X-14677D02*
X-18174Y1271092D01*
G01X-14677Y1271130D02*
X-16213Y1271113D01*
G01X-15985Y1274263D02*
X-14449Y1274280D01*
G01X-14677D02*
X-18174Y1274241D01*
G01X-14677Y1274280D02*
X-16213Y1274263D01*
G01X-15985Y1277413D02*
X-14449Y1277429D01*
G01X-14677D02*
X-18174Y1277391D01*
G01X-14677Y1277429D02*
X-16213Y1277413D01*
G01X-15985Y1280562D02*
X-14449Y1280579D01*
G01X-14677D02*
X-18174Y1280541D01*
G01X-14677Y1280579D02*
X-16213Y1280562D01*
G01X-15985Y1283712D02*
X-14449Y1283728D01*
G01X-14677D02*
X-18174Y1283690D01*
G01X-14677Y1283728D02*
X-16213Y1283712D01*
G01X-19469Y1245881D02*
X-20801Y1245869D01*
G01X-19469Y1249030D02*
X-20801Y1249019D01*
G01X-19469Y1252180D02*
X-20801Y1252168D01*
G01X-19469Y1255330D02*
X-20801Y1255318D01*
G01X-19469Y1258479D02*
X-20801Y1258467D01*
G01X-19469Y1261629D02*
X-20801Y1261617D01*
G01X-19469Y1264778D02*
X-20801Y1264767D01*
G01X-19469Y1267928D02*
X-20801Y1267916D01*
G01X-19469Y1271078D02*
X-20801Y1271066D01*
G01X-19469Y1274227D02*
X-20801Y1274215D01*
G01X-19469Y1277377D02*
X-20801Y1277365D01*
G01X-19469Y1280526D02*
X-20801Y1280515D01*
G01X-19469Y1283676D02*
X-20801Y1283664D01*
G01X-15985Y1245917D02*
X-17126Y1245906D01*
G01D02*
X-18435Y1245895D01*
G01X-15985Y1249066D02*
X-17126Y1249056D01*
G01D02*
X-18435Y1249044D01*
G01X-15985Y1252216D02*
X-17126Y1252206D01*
G01D02*
X-18435Y1252194D01*
G01X-15985Y1255365D02*
X-17126Y1255355D01*
G01D02*
X-18435Y1255344D01*
G01X-15985Y1258515D02*
X-17126Y1258505D01*
G01D02*
X-18435Y1258493D01*
G01X-15985Y1261665D02*
X-17126Y1261654D01*
G01D02*
X-18435Y1261643D01*
G01X-15985Y1264814D02*
X-17126Y1264804D01*
G01D02*
X-18435Y1264793D01*
G01X-15985Y1267964D02*
X-17126Y1267954D01*
G01X-18435Y1267942D02*
X-17126Y1267954D01*
G01X-15985Y1271113D02*
X-17126Y1271103D01*
G01D02*
X-18435Y1271092D01*
G01X-15985Y1274263D02*
X-17126Y1274253D01*
G01D02*
X-18435Y1274241D01*
G01X-15985Y1277413D02*
X-17126Y1277402D01*
G01D02*
X-18435Y1277391D01*
G01X-15985Y1280562D02*
X-17126Y1280552D01*
G01D02*
X-18435Y1280541D01*
G01X-15985Y1283712D02*
X-17126Y1283702D01*
G01D02*
X-18435Y1283690D01*
G01X-18174Y1245895D02*
X-18435D01*
G01X-15985Y1245917D02*
X-16213D01*
G01X-14449Y1245933D02*
X-14677D01*
G01X12410Y1246031D02*
X315D01*
G01X-13009Y1246228D02*
X-14147D01*
G01X512Y1246622D02*
X0D01*
G01X512Y1247409D02*
X0D01*
G01X-13009Y1247803D02*
X-14147D01*
G01X12410Y1248000D02*
X315D01*
G01X-14449Y1248098D02*
X-14677D01*
G01X-15985Y1248115D02*
X-16213D01*
G01X-18174Y1248136D02*
X-18435D01*
G01X-18174Y1249044D02*
X-18435D01*
G01X-15985Y1249066D02*
X-16213D01*
G01X-14449Y1249083D02*
X-14677D01*
G01X12410Y1249181D02*
X315D01*
G01X-13009Y1249378D02*
X-14147D01*
G01X512Y1249772D02*
X0D01*
G01X512Y1250559D02*
X0D01*
G01X-13009Y1250953D02*
X-14147D01*
G01X12410Y1251150D02*
X315D01*
G01X-14449Y1251248D02*
X-14677D01*
G01X-15985Y1251264D02*
X-16213D01*
G01X-18174Y1251286D02*
X-18435D01*
G01X-18174Y1252194D02*
X-18435D01*
G01X-15985Y1252216D02*
X-16213D01*
G01X-14449Y1252232D02*
X-14677D01*
G01X12410Y1252331D02*
X315D01*
G01X-13009Y1252528D02*
X-14147D01*
G01X512Y1252921D02*
X0D01*
G01X512Y1253709D02*
X0D01*
G01X-13009Y1254102D02*
X-14147D01*
G01X12410Y1254299D02*
X315D01*
G01X-14449Y1254398D02*
X-14677D01*
G01X-15985Y1254414D02*
X-16213D01*
G01X-18174Y1254435D02*
X-18435D01*
G01X-18174Y1255344D02*
X-18435D01*
G01X-15985Y1255365D02*
X-16213D01*
G01X-14449Y1255382D02*
X-14677D01*
G01X12410Y1255480D02*
X315D01*
G01X-13009Y1255677D02*
X-14147D01*
G01X512Y1256071D02*
X0D01*
G01X512Y1256858D02*
X0D01*
G01X-13009Y1257252D02*
X-14147D01*
G01X12410Y1257449D02*
X315D01*
G01X-14449Y1257547D02*
X-14677D01*
G01X-15985Y1257563D02*
X-16213D01*
G01X-18174Y1257585D02*
X-18435D01*
G01X-18174Y1258493D02*
X-18435D01*
G01X-15985Y1258515D02*
X-16213D01*
G01X-14449Y1258531D02*
X-14677D01*
G01X12410Y1258630D02*
X315D01*
G01X-13009Y1258827D02*
X-14147D01*
G01X512Y1259220D02*
X0D01*
G01X512Y1260008D02*
X0D01*
G01X-13009Y1260402D02*
X-14147D01*
G01X12410Y1260598D02*
X315D01*
G01X-14449Y1260697D02*
X-14677D01*
G01X-15985Y1260713D02*
X-16213D01*
G01X-18174Y1260735D02*
X-18435D01*
G01X-18174Y1261643D02*
X-18435D01*
G01X-15985Y1261665D02*
X-16213D01*
G01X-14449Y1261681D02*
X-14677D01*
G01X12410Y1261780D02*
X315D01*
G01X-13009Y1261976D02*
X-14147D01*
G01X512Y1262370D02*
X0D01*
G01X512Y1263157D02*
X0D01*
G01X-13009Y1263551D02*
X-14147D01*
G01X12410Y1263748D02*
X315D01*
G01X-14449Y1263846D02*
X-14677D01*
G01X-15985Y1263863D02*
X-16213D01*
G01X-18174Y1263884D02*
X-18435D01*
G01X-18174Y1264793D02*
X-18435D01*
G01X-15985Y1264814D02*
X-16213D01*
G01X-14449Y1264831D02*
X-14677D01*
G01X12410Y1264929D02*
X315D01*
G01X-13009Y1265126D02*
X-14147D01*
G01X512Y1265520D02*
X0D01*
G01X512Y1266307D02*
X0D01*
G01X-13009Y1266701D02*
X-14147D01*
G01X12410Y1266898D02*
X315D01*
G01X-14449Y1266996D02*
X-14677D01*
G01X-15985Y1267012D02*
X-16213D01*
G01X-18174Y1267034D02*
X-18435D01*
G01X-18174Y1267942D02*
X-18435D01*
G01X-15985Y1267964D02*
X-16213D01*
G01X-14449Y1267980D02*
X-14677D01*
G01X12410Y1268079D02*
X315D01*
G01X-13009Y1268276D02*
X-14147D01*
G01X512Y1268669D02*
X0D01*
G01X512Y1269457D02*
X0D01*
G01X-13009Y1269850D02*
X-14147D01*
G01X12410Y1270047D02*
X315D01*
G01X-14449Y1270146D02*
X-14677D01*
G01X-15985Y1270162D02*
X-16213D01*
G01X-18174Y1270183D02*
X-18435D01*
G01X-18174Y1271092D02*
X-18435D01*
G01X-15985Y1271113D02*
X-16213D01*
G01X-14449Y1271130D02*
X-14677D01*
G01X12410Y1271228D02*
X315D01*
G01X-13009Y1271425D02*
X-14147D01*
G01X512Y1271819D02*
X0D01*
G01X512Y1272606D02*
X0D01*
G01X-13009Y1273000D02*
X-14147D01*
G01X12410Y1273197D02*
X315D01*
G01X-14449Y1273295D02*
X-14677D01*
G01X-15985Y1273311D02*
X-16213D01*
G01X-18174Y1273333D02*
X-18435D01*
G01X-18174Y1274241D02*
X-18435D01*
G01X-15985Y1274263D02*
X-16213D01*
G01X-14449Y1274280D02*
X-14677D01*
G01X12410Y1274378D02*
X315D01*
G01X-13009Y1274575D02*
X-14147D01*
G01X512Y1274969D02*
X0D01*
G01X512Y1275756D02*
X0D01*
G01X-13009Y1276150D02*
X-14147D01*
G01X12410Y1276346D02*
X315D01*
G01X-14449Y1276445D02*
X-14677D01*
G01X-15985Y1276461D02*
X-16213D01*
G01X-18174Y1276483D02*
X-18435D01*
G01X-18174Y1277391D02*
X-18435D01*
G01X-15985Y1277413D02*
X-16213D01*
G01X-14449Y1277429D02*
X-14677D01*
G01X12410Y1277528D02*
X315D01*
G01X-13009Y1277724D02*
X-14147D01*
G01X512Y1278118D02*
X0D01*
G01X512Y1278906D02*
X0D01*
G01X-13009Y1279299D02*
X-14147D01*
G01X12410Y1279496D02*
X315D01*
G01X-14449Y1279594D02*
X-14677D01*
G01X-15985Y1279611D02*
X-16213D01*
G01X-18174Y1279632D02*
X-18435D01*
G01X-18174Y1280541D02*
X-18435D01*
G01X-15985Y1280562D02*
X-16213D01*
G01X-14449Y1280579D02*
X-14677D01*
G01X12410Y1280677D02*
X315D01*
G01X-13009Y1280874D02*
X-14147D01*
G01X512Y1281268D02*
X0D01*
G01X512Y1282055D02*
X0D01*
G01X-13009Y1282449D02*
X-14147D01*
G01X12410Y1282646D02*
X315D01*
G01X-14449Y1282744D02*
X-14677D01*
G01X-15985Y1282760D02*
X-16213D01*
G01X-18174Y1282782D02*
X-18435D01*
G01X-18174Y1283690D02*
X-18435D01*
G01X-15985Y1283712D02*
X-16213D01*
G01X-14449Y1283728D02*
X-14677D01*
G01X12410Y1283827D02*
X315D01*
G01X-13009Y1284024D02*
X-14147D01*
G01X512Y1284417D02*
X0D01*
G01X-19469Y1248151D02*
X-20801Y1248163D01*
G01X-15985Y1248115D02*
X-18435Y1248136D01*
G01X-19469Y1251300D02*
X-20801Y1251312D01*
G01X-15985Y1251264D02*
X-18435Y1251286D01*
G01X-19469Y1254450D02*
X-20801Y1254462D01*
G01X-15985Y1254414D02*
X-18435Y1254435D01*
G01X-19469Y1257600D02*
X-20801Y1257611D01*
G01X-15985Y1257563D02*
X-18435Y1257585D01*
G01X-19469Y1260749D02*
X-20801Y1260761D01*
G01X-15985Y1260713D02*
X-18435Y1260735D01*
G01X-19469Y1263899D02*
X-20801Y1263911D01*
G01X-15985Y1263863D02*
X-18435Y1263884D01*
G01X-19469Y1267048D02*
X-20801Y1267060D01*
G01X-15985Y1267012D02*
X-18435Y1267034D01*
G01X-19469Y1270198D02*
X-20801Y1270210D01*
G01X-15985Y1270162D02*
X-18435Y1270183D01*
G01X-19469Y1273348D02*
X-20801Y1273359D01*
G01X-15985Y1273311D02*
X-18435Y1273333D01*
G01X-19469Y1276497D02*
X-20801Y1276509D01*
G01X-15985Y1276461D02*
X-18435Y1276483D01*
G01X-19469Y1279647D02*
X-20801Y1279659D01*
G01X-15985Y1279611D02*
X-18435Y1279632D01*
G01X-19469Y1282796D02*
X-20801Y1282808D01*
G01X-15985Y1282760D02*
X-18435Y1282782D01*
G01X-15985Y1248115D02*
X-14449Y1248098D01*
G01X-15985Y1251264D02*
X-14449Y1251248D01*
G01X-15985Y1254414D02*
X-14449Y1254398D01*
G01X-15985Y1257563D02*
X-14449Y1257547D01*
G01X-15985Y1260713D02*
X-14449Y1260697D01*
G01X-15985Y1263863D02*
X-14449Y1263846D01*
G01X-15985Y1267012D02*
X-14449Y1266996D01*
G01X-15985Y1270162D02*
X-14449Y1270146D01*
G01X-15985Y1273311D02*
X-14449Y1273295D01*
G01X-15985Y1276461D02*
X-14449Y1276445D01*
G01X-15985Y1279611D02*
X-14449Y1279594D01*
G01X-15985Y1282760D02*
X-14449Y1282744D01*
G01X-18435Y1248136D02*
X-20801Y1248163D01*
G01X-18435Y1251286D02*
X-20801Y1251312D01*
G01X-18435Y1254435D02*
X-20801Y1254462D01*
G01X-18435Y1257585D02*
X-20801Y1257611D01*
G01X-18435Y1260735D02*
X-20801Y1260761D01*
G01X-18435Y1263884D02*
X-20801Y1263911D01*
G01X-18435Y1267034D02*
X-20801Y1267060D01*
G01X-18435Y1270183D02*
X-20801Y1270210D01*
G01X-18435Y1273333D02*
X-20801Y1273359D01*
G01X-18435Y1276483D02*
X-20801Y1276509D01*
G01X-18435Y1279632D02*
X-20801Y1279659D01*
G01X-18435Y1282782D02*
X-20801Y1282808D01*
G01X-19469Y1248151D02*
X-16213Y1248115D01*
G01X-18174Y1248136D02*
X-14677Y1248098D01*
G01X-19469Y1251300D02*
X-16213Y1251264D01*
G01X-18174Y1251286D02*
X-14677Y1251248D01*
G01X-19469Y1254450D02*
X-16213Y1254414D01*
G01X-18174Y1254435D02*
X-14677Y1254398D01*
G01X-19469Y1257600D02*
X-16213Y1257563D01*
G01X-18174Y1257585D02*
X-14677Y1257547D01*
G01X-19469Y1260749D02*
X-16213Y1260713D01*
G01X-18174Y1260735D02*
X-14677Y1260697D01*
G01X-19469Y1263899D02*
X-16213Y1263863D01*
G01X-18174Y1263884D02*
X-14677Y1263846D01*
G01X-19469Y1267048D02*
X-16213Y1267012D01*
G01X-18174Y1267034D02*
X-14677Y1266996D01*
G01X-19469Y1270198D02*
X-16213Y1270162D01*
G01X-18174Y1270183D02*
X-14677Y1270146D01*
G01X-19469Y1273348D02*
X-16213Y1273311D01*
G01X-18174Y1273333D02*
X-14677Y1273295D01*
G01X-19469Y1276497D02*
X-16213Y1276461D01*
G01X-18174Y1276483D02*
X-14677Y1276445D01*
G01X-19469Y1279647D02*
X-16213Y1279611D01*
G01X-18174Y1279632D02*
X-14677Y1279594D01*
G01X-19469Y1282796D02*
X-16213Y1282760D01*
G01X-18174Y1282782D02*
X-14677Y1282744D01*
G01X-26772Y1420638D02*
Y1241504D01*
G01X-20801Y1245869D02*
Y1245013D01*
G01Y1230121D02*
Y1229265D01*
G01Y1226971D02*
Y1226115D01*
G01X-19469Y1245875D02*
Y1245007D01*
G01Y1230127D02*
Y1229259D01*
G01Y1226977D02*
Y1226109D01*
G01X-18435Y1245895D02*
Y1244987D01*
G01Y1230147D02*
Y1229239D01*
G01Y1226997D02*
Y1226089D01*
G01X-18174Y1245895D02*
Y1244987D01*
G01Y1230147D02*
Y1229239D01*
G01Y1226997D02*
Y1226089D01*
G01X-16213Y1245917D02*
Y1244965D01*
G01Y1230169D02*
Y1229217D01*
G01Y1227019D02*
Y1226067D01*
G01X-15985Y1245917D02*
Y1244965D01*
G01Y1230169D02*
Y1229217D01*
G01Y1227019D02*
Y1226067D01*
G01X0Y1231268D02*
X1969Y1233236D01*
G01X-14537Y1246021D02*
Y1244861D01*
G01Y1230273D02*
Y1229113D01*
G01Y1227123D02*
Y1225963D01*
G01X-13009Y1246228D02*
Y1244654D01*
G01Y1230480D02*
Y1228906D01*
G01Y1227331D02*
Y1225756D01*
G01X-7283Y1422606D02*
Y1241504D01*
G01X315Y1244850D02*
Y1244260D01*
G01Y1227724D02*
Y1227134D01*
G01Y1230874D02*
Y1230283D01*
G01Y1229102D02*
Y1228512D01*
G01Y1225953D02*
Y1225362D01*
G01X512Y1244850D02*
Y1244260D01*
G01Y1227724D02*
Y1227134D01*
G01Y1230874D02*
Y1230283D01*
G01Y1229102D02*
Y1228512D01*
G01Y1225953D02*
Y1225362D01*
G01X709Y1246031D02*
Y1244850D01*
G01Y1230283D02*
Y1229102D01*
G01Y1227134D02*
Y1225953D01*
G01X1074Y1246031D02*
Y1244850D01*
G01Y1230283D02*
Y1229102D01*
G01Y1227134D02*
Y1225953D01*
G01X1184Y1246031D02*
Y1244850D01*
G01Y1230283D02*
Y1229102D01*
G01Y1227134D02*
Y1225953D01*
G01X9965Y1246031D02*
Y1244850D01*
G01Y1230283D02*
Y1229102D01*
G01Y1227134D02*
Y1225953D01*
G01X10075Y1246031D02*
Y1244850D01*
G01Y1230283D02*
Y1229102D01*
G01Y1227134D02*
Y1225953D01*
G01X-14537Y1230273D02*
X-14677Y1230185D01*
G01X-13977Y1230480D02*
X-14449Y1230185D01*
G01X-14537Y1227123D02*
X-14677Y1227035D01*
G01X-13977Y1227331D02*
X-14449Y1227035D01*
G01X-14147Y1230480D02*
X-14537Y1230273D01*
G01X-14147Y1227331D02*
X-14537Y1227123D01*
G01X-26772Y1241504D02*
X-30709Y1239535D01*
G01X1969Y1241898D02*
X0Y1243866D01*
G01X-14677Y1226051D02*
X-14537Y1225963D01*
G01X-14449Y1226051D02*
X-13977Y1225756D01*
G01X-14677Y1229201D02*
X-14537Y1229113D01*
G01X-14449Y1229201D02*
X-13977Y1228906D01*
G01X-14677Y1244949D02*
X-14537Y1244861D01*
G01X-14449Y1244949D02*
X-13977Y1244654D01*
G01X-30709Y1235598D02*
X-26772Y1233630D01*
G01X-14537Y1225963D02*
X-14147Y1225756D01*
G01X-14537Y1229113D02*
X-14147Y1228906D01*
G01X-14537Y1244861D02*
X-14147Y1244654D01*
G01X-19469Y1226983D02*
X-18174Y1226997D01*
G01X-18435D02*
X-20801Y1226971D01*
G01X-18174Y1226997D02*
X-17126Y1227009D01*
G01X-19469Y1230133D02*
X-18174Y1230147D01*
G01X-18435D02*
X-20801Y1230121D01*
G01X-18174Y1230147D02*
X-17126Y1230158D01*
G01X-15985Y1227019D02*
X-14449Y1227035D01*
G01X-14677D02*
X-18174Y1226997D01*
G01X-14677Y1227035D02*
X-16213Y1227019D01*
G01X-15985Y1230169D02*
X-14449Y1230185D01*
G01X-14677D02*
X-18174Y1230147D01*
G01X-14677Y1230185D02*
X-16213Y1230169D01*
G01X-19469Y1226983D02*
X-20801Y1226971D01*
G01X-19469Y1230133D02*
X-20801Y1230121D01*
G01X-15985Y1227019D02*
X-17126Y1227009D01*
G01D02*
X-18435Y1226997D01*
G01X-15985Y1230169D02*
X-17126Y1230158D01*
G01D02*
X-18435Y1230147D01*
G01X512Y1225362D02*
X0D01*
G01X-13009Y1225756D02*
X-14147D01*
G01X12410Y1225953D02*
X315D01*
G01X-14449Y1226051D02*
X-14677D01*
G01X-15985Y1226067D02*
X-16213D01*
G01X-18174Y1226089D02*
X-18435D01*
G01X-18174Y1226997D02*
X-18435D01*
G01X-15985Y1227019D02*
X-16213D01*
G01X-14449Y1227035D02*
X-14677D01*
G01X12410Y1227134D02*
X315D01*
G01X-13009Y1227331D02*
X-14147D01*
G01X512Y1227724D02*
X0D01*
G01X512Y1228512D02*
X0D01*
G01X-13009Y1228906D02*
X-14147D01*
G01X12410Y1229102D02*
X315D01*
G01X-14449Y1229201D02*
X-14677D01*
G01X-15985Y1229217D02*
X-16213D01*
G01X-18174Y1229239D02*
X-18435D01*
G01X-18174Y1230147D02*
X-18435D01*
G01X-15985Y1230169D02*
X-16213D01*
G01X-14449Y1230185D02*
X-14677D01*
G01X12410Y1230283D02*
X315D01*
G01X-13009Y1230480D02*
X-14147D01*
G01X512Y1230874D02*
X0D01*
G01X1969Y1233236D02*
X17323D01*
G01X17717Y1233630D02*
X0D01*
G01X-26772D02*
X-7283D01*
G01X-19469Y1226104D02*
X-20801Y1226115D01*
G01X-15985Y1226067D02*
X-18435Y1226089D01*
G01X-19469Y1229253D02*
X-20801Y1229265D01*
G01X-15985Y1229217D02*
X-18435Y1229239D01*
G01X-15985Y1226067D02*
X-14449Y1226051D01*
G01X-15985Y1229217D02*
X-14449Y1229201D01*
G01X-18435Y1226089D02*
X-20801Y1226115D01*
G01X-18435Y1229239D02*
X-20801Y1229265D01*
G01X-19469Y1226104D02*
X-16213Y1226067D01*
G01X-18174Y1226089D02*
X-14677Y1226051D01*
G01X-19469Y1229253D02*
X-16213Y1229217D01*
G01X-18174Y1229239D02*
X-14677Y1229201D01*
G01X17717Y1241504D02*
X0D01*
G01X-7283D02*
X-26772D01*
G01X17323Y1241898D02*
X1969D01*
G01X512Y1244260D02*
X0D01*
G01X-13009Y1244654D02*
X-14147D01*
G01X12410Y1244850D02*
X315D01*
G01X-14449Y1244949D02*
X-14677D01*
G01X-15985Y1244965D02*
X-16213D01*
G01X-18174Y1244987D02*
X-18435D01*
G01X-19469Y1245001D02*
X-20801Y1245013D01*
G01X-15985Y1244965D02*
X-18435Y1244987D01*
G01X-15985Y1244965D02*
X-14449Y1244949D01*
G01X-18435Y1244987D02*
X-20801Y1245013D01*
G01X-19469Y1245001D02*
X-16213Y1244965D01*
G01X-18174Y1244987D02*
X-14677Y1244949D01*
G01X12634Y1342744D02*
X12416Y1342474D01*
G01X12634Y1339594D02*
X12416Y1339324D01*
G01X12634Y1336445D02*
X12416Y1336175D01*
G01X12634Y1333295D02*
X12416Y1333025D01*
G01X12634Y1330146D02*
X12416Y1329876D01*
G01X12634Y1326996D02*
X12416Y1326726D01*
G01X12634Y1323846D02*
X12416Y1323576D01*
G01X12634Y1320697D02*
X12416Y1320427D01*
G01X12634Y1317547D02*
X12416Y1317277D01*
G01X12634Y1314398D02*
X12416Y1314128D01*
G01X12634Y1311248D02*
X12416Y1310978D01*
G01X12634Y1308098D02*
X12416Y1307828D01*
G01X12287Y1342744D02*
X12057Y1342488D01*
G01X12287Y1339594D02*
X12057Y1339339D01*
G01X12287Y1336445D02*
X12057Y1336189D01*
G01X12287Y1333295D02*
X12057Y1333039D01*
G01X12287Y1330146D02*
X12057Y1329890D01*
G01X12287Y1326996D02*
X12057Y1326740D01*
G01X12287Y1323846D02*
X12057Y1323591D01*
G01X12287Y1320697D02*
X12057Y1320441D01*
G01X12287Y1317547D02*
X12057Y1317291D01*
G01X12287Y1314398D02*
X12057Y1314142D01*
G01X12287Y1311248D02*
X12057Y1310992D01*
G01X12287Y1308098D02*
X12057Y1307843D01*
G01Y1340520D02*
Y1339339D01*
G01Y1343669D02*
Y1342488D01*
G01Y1337370D02*
Y1336189D01*
G01Y1331071D02*
Y1329890D01*
G01Y1334220D02*
Y1333039D01*
G01Y1327921D02*
Y1326740D01*
G01Y1321622D02*
Y1320441D01*
G01Y1324772D02*
Y1323591D01*
G01Y1318472D02*
Y1317291D01*
G01Y1312173D02*
Y1310992D01*
G01Y1315323D02*
Y1314142D01*
G01Y1309024D02*
Y1307843D01*
G01X12410Y1340520D02*
Y1339339D01*
G01Y1343669D02*
Y1342488D01*
G01Y1337370D02*
Y1336189D01*
G01Y1331071D02*
Y1329890D01*
G01Y1334220D02*
Y1333039D01*
G01Y1327921D02*
Y1326740D01*
G01Y1321622D02*
Y1320441D01*
G01Y1324772D02*
Y1323591D01*
G01Y1318472D02*
Y1317291D01*
G01Y1312173D02*
Y1310992D01*
G01Y1315323D02*
Y1314142D01*
G01Y1309024D02*
Y1307843D01*
G01X13353Y1340264D02*
Y1339594D01*
G01Y1343413D02*
Y1342744D01*
G01Y1337114D02*
Y1336445D01*
G01Y1330815D02*
Y1330146D01*
G01Y1333965D02*
Y1333295D01*
G01Y1327665D02*
Y1326996D01*
G01Y1321366D02*
Y1320697D01*
G01Y1324516D02*
Y1323846D01*
G01Y1318217D02*
Y1317547D01*
G01Y1311917D02*
Y1311248D01*
G01Y1315067D02*
Y1314398D01*
G01Y1308768D02*
Y1308098D01*
G01X13701Y1340264D02*
Y1339594D01*
G01Y1343413D02*
Y1342744D01*
G01Y1337114D02*
Y1336445D01*
G01Y1330815D02*
Y1330146D01*
G01Y1333965D02*
Y1333295D01*
G01Y1327665D02*
Y1326996D01*
G01Y1321366D02*
Y1320697D01*
G01Y1324516D02*
Y1323846D01*
G01Y1318217D02*
Y1317547D01*
G01Y1311917D02*
Y1311248D01*
G01Y1315067D02*
Y1314398D01*
G01Y1308768D02*
Y1308098D01*
G01X12057Y1305874D02*
X12287Y1305618D01*
G01X12057Y1309024D02*
X12287Y1308768D01*
G01X12057Y1312173D02*
X12287Y1311917D01*
G01X12057Y1315323D02*
X12287Y1315067D01*
G01X12057Y1318472D02*
X12287Y1318217D01*
G01X12057Y1321622D02*
X12287Y1321366D01*
G01X12057Y1324772D02*
X12287Y1324516D01*
G01X12057Y1327921D02*
X12287Y1327665D01*
G01X12057Y1331071D02*
X12287Y1330815D01*
G01X12057Y1334220D02*
X12287Y1333965D01*
G01X12416Y1305888D02*
X12634Y1305618D01*
G01X12416Y1309038D02*
X12634Y1308768D01*
G01X12416Y1312187D02*
X12634Y1311917D01*
G01X12416Y1315337D02*
X12634Y1315067D01*
G01X12416Y1318487D02*
X12634Y1318217D01*
G01X12416Y1321636D02*
X12634Y1321366D01*
G01X12416Y1324786D02*
X12634Y1324516D01*
G01X12416Y1327935D02*
X12634Y1327665D01*
G01X12416Y1331085D02*
X12634Y1330815D01*
G01X12416Y1334235D02*
X12634Y1333965D01*
G01X12416Y1337384D02*
X12634Y1337114D01*
G01X12416Y1340534D02*
X12634Y1340264D01*
G01X12416Y1343683D02*
X12634Y1343413D01*
G01X12057Y1337370D02*
X12287Y1337114D01*
G01X12057Y1340520D02*
X12287Y1340264D01*
G01X12057Y1343669D02*
X12287Y1343413D01*
G01X13701Y1305618D02*
X12287D01*
G01X13701Y1308098D02*
X12287D01*
G01X13701Y1308768D02*
X12287D01*
G01X13701Y1311248D02*
X12287D01*
G01X13701Y1311917D02*
X12287D01*
G01X13701Y1314398D02*
X12287D01*
G01X13701Y1315067D02*
X12287D01*
G01X13701Y1317547D02*
X12287D01*
G01X13701Y1318217D02*
X12287D01*
G01X13701Y1320697D02*
X12287D01*
G01X13701Y1321366D02*
X12287D01*
G01X13701Y1323846D02*
X12287D01*
G01X13701Y1324516D02*
X12287D01*
G01X13701Y1326996D02*
X12287D01*
G01X13701Y1327665D02*
X12287D01*
G01X13701Y1330146D02*
X12287D01*
G01X13701Y1330815D02*
X12287D01*
G01X13701Y1333295D02*
X12287D01*
G01X13701Y1333965D02*
X12287D01*
G01X13701Y1336445D02*
X12287D01*
G01X13701Y1337114D02*
X12287D01*
G01X13701Y1339594D02*
X12287D01*
G01X13701Y1340264D02*
X12287D01*
G01X13701Y1342744D02*
X12287D01*
G01X13701Y1343413D02*
X12287D01*
G01X12634Y1355343D02*
X12416Y1355072D01*
G01X12634Y1352193D02*
X12416Y1351923D01*
G01X12634Y1349043D02*
X12416Y1348773D01*
G01X12634Y1345894D02*
X12416Y1345624D01*
G01X12287Y1355343D02*
X12057Y1355087D01*
G01X12287Y1352193D02*
X12057Y1351937D01*
G01X12287Y1349043D02*
X12057Y1348787D01*
G01X12287Y1345894D02*
X12057Y1345638D01*
G01Y1356268D02*
Y1355087D01*
G01Y1349969D02*
Y1348787D01*
G01Y1353118D02*
Y1351937D01*
G01Y1346819D02*
Y1345638D01*
G01X12410Y1356268D02*
Y1355087D01*
G01Y1349969D02*
Y1348787D01*
G01Y1353118D02*
Y1351937D01*
G01Y1346819D02*
Y1345638D01*
G01X13353Y1356012D02*
Y1355343D01*
G01Y1349713D02*
Y1349043D01*
G01Y1352862D02*
Y1352193D01*
G01Y1346563D02*
Y1345894D01*
G01X13701Y1356012D02*
Y1355343D01*
G01Y1349713D02*
Y1349043D01*
G01Y1352862D02*
Y1352193D01*
G01Y1346563D02*
Y1345894D01*
G01X12416Y1346833D02*
X12634Y1346563D01*
G01X12416Y1349983D02*
X12634Y1349713D01*
G01X12416Y1353132D02*
X12634Y1352862D01*
G01X12416Y1356282D02*
X12634Y1356012D01*
G01X12057Y1346819D02*
X12287Y1346563D01*
G01X12057Y1349969D02*
X12287Y1349713D01*
G01X12057Y1353118D02*
X12287Y1352862D01*
G01X12057Y1356268D02*
X12287Y1356012D01*
G01X13701Y1345894D02*
X12287D01*
G01X13701Y1346563D02*
X12287D01*
G01X13701Y1349043D02*
X12287D01*
G01X13701Y1349713D02*
X12287D01*
G01X13701Y1352193D02*
X12287D01*
G01X13701Y1352862D02*
X12287D01*
G01X13701Y1355343D02*
X12287D01*
G01X13701Y1356012D02*
X12287D01*
G01X12634Y1304949D02*
X12416Y1304679D01*
G01X12634Y1301799D02*
X12416Y1301529D01*
G01X12634Y1298650D02*
X12416Y1298380D01*
G01X12634Y1295500D02*
X12416Y1295230D01*
G01X12634Y1292350D02*
X12416Y1292080D01*
G01X12634Y1289201D02*
X12416Y1288931D01*
G01X12634Y1286051D02*
X12416Y1285781D01*
G01X12287Y1304949D02*
X12057Y1304693D01*
G01X12287Y1301799D02*
X12057Y1301543D01*
G01X12287Y1298650D02*
X12057Y1298394D01*
G01X12287Y1295500D02*
X12057Y1295244D01*
G01X12287Y1292350D02*
X12057Y1292094D01*
G01X12287Y1289201D02*
X12057Y1288945D01*
G01X12287Y1286051D02*
X12057Y1285795D01*
G01Y1302724D02*
Y1301543D01*
G01Y1305874D02*
Y1304693D01*
G01Y1299575D02*
Y1298394D01*
G01Y1293276D02*
Y1292094D01*
G01Y1296425D02*
Y1295244D01*
G01Y1290126D02*
Y1288945D01*
G01Y1286976D02*
Y1285795D01*
G01X12410Y1302724D02*
Y1301543D01*
G01Y1305874D02*
Y1304693D01*
G01Y1299575D02*
Y1298394D01*
G01Y1293276D02*
Y1292094D01*
G01Y1296425D02*
Y1295244D01*
G01Y1290126D02*
Y1288945D01*
G01Y1286976D02*
Y1285795D01*
G01X13353Y1302469D02*
Y1301799D01*
G01Y1305618D02*
Y1304949D01*
G01Y1299319D02*
Y1298650D01*
G01Y1296169D02*
Y1295500D01*
G01Y1289870D02*
Y1289201D01*
G01Y1293020D02*
Y1292350D01*
G01Y1286720D02*
Y1286051D01*
G01X13701Y1302469D02*
Y1301799D01*
G01Y1305618D02*
Y1304949D01*
G01Y1299319D02*
Y1298650D01*
G01Y1296169D02*
Y1295500D01*
G01Y1289870D02*
Y1289201D01*
G01Y1293020D02*
Y1292350D01*
G01Y1286720D02*
Y1286051D01*
G01X12057Y1286976D02*
X12287Y1286720D01*
G01X12057Y1290126D02*
X12287Y1289870D01*
G01X12057Y1293276D02*
X12287Y1293020D01*
G01X12057Y1296425D02*
X12287Y1296169D01*
G01X12057Y1299575D02*
X12287Y1299319D01*
G01X12057Y1302724D02*
X12287Y1302469D01*
G01X12416Y1286991D02*
X12634Y1286720D01*
G01X12416Y1290140D02*
X12634Y1289870D01*
G01X12416Y1293290D02*
X12634Y1293020D01*
G01X12416Y1296439D02*
X12634Y1296169D01*
G01X12416Y1299589D02*
X12634Y1299319D01*
G01X12416Y1302739D02*
X12634Y1302469D01*
G01X13701Y1286051D02*
X12287D01*
G01X13701Y1286720D02*
X12287D01*
G01X13701Y1289201D02*
X12287D01*
G01X13701Y1289870D02*
X12287D01*
G01X13701Y1292350D02*
X12287D01*
G01X13701Y1293020D02*
X12287D01*
G01X13701Y1295500D02*
X12287D01*
G01X13701Y1296169D02*
X12287D01*
G01X13701Y1298650D02*
X12287D01*
G01X13701Y1299319D02*
X12287D01*
G01X13701Y1301799D02*
X12287D01*
G01X13701Y1302469D02*
X12287D01*
G01X13701Y1304949D02*
X12287D01*
G01X-20801Y1340357D02*
Y1339501D01*
G01Y1343507D02*
Y1342651D01*
G01Y1337207D02*
Y1336352D01*
G01Y1330908D02*
Y1330052D01*
G01Y1334058D02*
Y1333202D01*
G01Y1327759D02*
Y1326903D01*
G01Y1321459D02*
Y1320604D01*
G01Y1324609D02*
Y1323753D01*
G01Y1318310D02*
Y1317454D01*
G01Y1312011D02*
Y1311155D01*
G01Y1315160D02*
Y1314304D01*
G01Y1308861D02*
Y1308005D01*
G01X-19469Y1340363D02*
Y1339495D01*
G01Y1343513D02*
Y1342645D01*
G01Y1337213D02*
Y1336346D01*
G01Y1330914D02*
Y1330046D01*
G01Y1334064D02*
Y1333196D01*
G01Y1327765D02*
Y1326897D01*
G01Y1321465D02*
Y1320598D01*
G01Y1324615D02*
Y1323747D01*
G01Y1318316D02*
Y1317448D01*
G01Y1312017D02*
Y1311149D01*
G01Y1315166D02*
Y1314298D01*
G01Y1308867D02*
Y1307999D01*
G01X-18435Y1340383D02*
Y1339475D01*
G01Y1343533D02*
Y1342624D01*
G01Y1337233D02*
Y1336325D01*
G01Y1330934D02*
Y1330026D01*
G01Y1334084D02*
Y1333176D01*
G01Y1327785D02*
Y1326876D01*
G01Y1321485D02*
Y1320577D01*
G01Y1324635D02*
Y1323727D01*
G01Y1318336D02*
Y1317428D01*
G01Y1312037D02*
Y1311128D01*
G01Y1315186D02*
Y1314278D01*
G01Y1308887D02*
Y1307979D01*
G01X-18174Y1340383D02*
Y1339475D01*
G01Y1343533D02*
Y1342624D01*
G01Y1337233D02*
Y1336325D01*
G01Y1330934D02*
Y1330026D01*
G01Y1334084D02*
Y1333176D01*
G01Y1327785D02*
Y1326876D01*
G01Y1321485D02*
Y1320577D01*
G01Y1324635D02*
Y1323727D01*
G01Y1318336D02*
Y1317428D01*
G01Y1312037D02*
Y1311128D01*
G01Y1315186D02*
Y1314278D01*
G01Y1308887D02*
Y1307979D01*
G01X-16213Y1340405D02*
Y1339453D01*
G01Y1343554D02*
Y1342603D01*
G01Y1337255D02*
Y1336304D01*
G01Y1330956D02*
Y1330004D01*
G01Y1334106D02*
Y1333154D01*
G01Y1327806D02*
Y1326855D01*
G01Y1321507D02*
Y1320556D01*
G01Y1324657D02*
Y1323705D01*
G01Y1318357D02*
Y1317406D01*
G01Y1312058D02*
Y1311107D01*
G01Y1315208D02*
Y1314256D01*
G01Y1308909D02*
Y1307957D01*
G01X-15985Y1340405D02*
Y1339453D01*
G01Y1343554D02*
Y1342603D01*
G01Y1337255D02*
Y1336304D01*
G01Y1330956D02*
Y1330004D01*
G01Y1334106D02*
Y1333154D01*
G01Y1327806D02*
Y1326855D01*
G01Y1321507D02*
Y1320556D01*
G01Y1324657D02*
Y1323705D01*
G01Y1318357D02*
Y1317406D01*
G01Y1312058D02*
Y1311107D01*
G01Y1315208D02*
Y1314256D01*
G01Y1308909D02*
Y1307957D01*
G01X-14537Y1343659D02*
X-14677Y1343571D01*
G01X-13977Y1343866D02*
X-14449Y1343571D01*
G01X-14537Y1340509D02*
X-14677Y1340421D01*
G01X-13977Y1340717D02*
X-14449Y1340421D01*
G01X-14537Y1337359D02*
X-14677Y1337272D01*
G01X-13977Y1337567D02*
X-14449Y1337272D01*
G01X-14537Y1334210D02*
X-14677Y1334122D01*
G01X-13977Y1334417D02*
X-14449Y1334122D01*
G01X-14537Y1331060D02*
X-14677Y1330972D01*
G01X-13977Y1331268D02*
X-14449Y1330972D01*
G01X-14537Y1327911D02*
X-14677Y1327823D01*
G01X-13977Y1328118D02*
X-14449Y1327823D01*
G01X-14537Y1324761D02*
X-14677Y1324673D01*
G01X-13977Y1324969D02*
X-14449Y1324673D01*
G01X-14537Y1321611D02*
X-14677Y1321524D01*
G01X-13977Y1321819D02*
X-14449Y1321524D01*
G01X-14537Y1318462D02*
X-14677Y1318374D01*
G01X-13977Y1318669D02*
X-14449Y1318374D01*
G01X-14537Y1315312D02*
X-14677Y1315224D01*
G01X-13977Y1315520D02*
X-14449Y1315224D01*
G01X-14537Y1312163D02*
X-14677Y1312075D01*
G01X-13977Y1312370D02*
X-14449Y1312075D01*
G01X-14537Y1309013D02*
X-14677Y1308925D01*
G01X-13977Y1309220D02*
X-14449Y1308925D01*
G01X-14537Y1305863D02*
X-14677Y1305776D01*
G01X-13977Y1306071D02*
X-14449Y1305776D01*
G01X-14147Y1343866D02*
X-14537Y1343659D01*
G01X-14147Y1340717D02*
X-14537Y1340509D01*
G01X-14147Y1337567D02*
X-14537Y1337359D01*
G01X-14147Y1334417D02*
X-14537Y1334210D01*
G01X-14147Y1331268D02*
X-14537Y1331060D01*
G01X-14147Y1328118D02*
X-14537Y1327911D01*
G01X-14147Y1324969D02*
X-14537Y1324761D01*
G01X-14147Y1321819D02*
X-14537Y1321611D01*
G01X-14147Y1318669D02*
X-14537Y1318462D01*
G01X-14147Y1315520D02*
X-14537Y1315312D01*
G01Y1340509D02*
Y1339349D01*
G01Y1343659D02*
Y1342499D01*
G01Y1337359D02*
Y1336200D01*
G01Y1331060D02*
Y1329900D01*
G01Y1334210D02*
Y1333050D01*
G01Y1327911D02*
Y1326751D01*
G01Y1321611D02*
Y1320452D01*
G01Y1324761D02*
Y1323601D01*
G01Y1318462D02*
Y1317302D01*
G01Y1312163D02*
Y1311003D01*
G01Y1315312D02*
Y1314152D01*
G01Y1309013D02*
Y1307853D01*
G01X-13009Y1340717D02*
Y1339142D01*
G01Y1343866D02*
Y1342291D01*
G01Y1337567D02*
Y1335992D01*
G01Y1331268D02*
Y1329693D01*
G01Y1334417D02*
Y1332843D01*
G01Y1328118D02*
Y1326543D01*
G01Y1321819D02*
Y1320244D01*
G01Y1324969D02*
Y1323394D01*
G01Y1318669D02*
Y1317094D01*
G01Y1312370D02*
Y1310795D01*
G01Y1315520D02*
Y1313945D01*
G01Y1309220D02*
Y1307646D01*
G01X315Y1345638D02*
Y1345047D01*
G01Y1341110D02*
Y1340520D01*
G01Y1344260D02*
Y1343669D01*
G01Y1342488D02*
Y1341898D01*
G01Y1337961D02*
Y1337370D01*
G01Y1336189D02*
Y1335598D01*
G01Y1339339D02*
Y1338748D01*
G01Y1331661D02*
Y1331071D01*
G01Y1334811D02*
Y1334220D01*
G01Y1333039D02*
Y1332449D01*
G01Y1328512D02*
Y1327921D01*
G01Y1326740D02*
Y1326150D01*
G01Y1329890D02*
Y1329299D01*
G01Y1322213D02*
Y1321622D01*
G01Y1325362D02*
Y1324772D01*
G01Y1323591D02*
Y1323000D01*
G01Y1319063D02*
Y1318472D01*
G01Y1317291D02*
Y1316701D01*
G01Y1320441D02*
Y1319850D01*
G01Y1312764D02*
Y1312173D01*
G01Y1315913D02*
Y1315323D01*
G01Y1314142D02*
Y1313551D01*
G01Y1309614D02*
Y1309024D01*
G01Y1307843D02*
Y1307252D01*
G01Y1310992D02*
Y1310402D01*
G01Y1306465D02*
Y1305874D01*
G01X512Y1345638D02*
Y1345047D01*
G01Y1341110D02*
Y1340520D01*
G01Y1344260D02*
Y1343669D01*
G01Y1342488D02*
Y1341898D01*
G01Y1337961D02*
Y1337370D01*
G01Y1336189D02*
Y1335598D01*
G01Y1339339D02*
Y1338748D01*
G01Y1331661D02*
Y1331071D01*
G01Y1334811D02*
Y1334220D01*
G01Y1333039D02*
Y1332449D01*
G01Y1328512D02*
Y1327921D01*
G01Y1326740D02*
Y1326150D01*
G01Y1329890D02*
Y1329299D01*
G01Y1322213D02*
Y1321622D01*
G01Y1325362D02*
Y1324772D01*
G01Y1323591D02*
Y1323000D01*
G01Y1319063D02*
Y1318472D01*
G01Y1317291D02*
Y1316701D01*
G01Y1320441D02*
Y1319850D01*
G01Y1312764D02*
Y1312173D01*
G01Y1315913D02*
Y1315323D01*
G01Y1314142D02*
Y1313551D01*
G01Y1309614D02*
Y1309024D01*
G01Y1307843D02*
Y1307252D01*
G01Y1310992D02*
Y1310402D01*
G01Y1306465D02*
Y1305874D01*
G01X709Y1340520D02*
Y1339339D01*
G01Y1343669D02*
Y1342488D01*
G01Y1337370D02*
Y1336189D01*
G01Y1331071D02*
Y1329890D01*
G01Y1334220D02*
Y1333039D01*
G01Y1327921D02*
Y1326740D01*
G01Y1321622D02*
Y1320441D01*
G01Y1324772D02*
Y1323591D01*
G01Y1318472D02*
Y1317291D01*
G01Y1312173D02*
Y1310992D01*
G01Y1315323D02*
Y1314142D01*
G01Y1309024D02*
Y1307843D01*
G01X1074Y1340520D02*
Y1339339D01*
G01Y1343669D02*
Y1342488D01*
G01Y1337370D02*
Y1336189D01*
G01Y1331071D02*
Y1329890D01*
G01Y1334220D02*
Y1333039D01*
G01Y1327921D02*
Y1326740D01*
G01Y1321622D02*
Y1320441D01*
G01Y1324772D02*
Y1323591D01*
G01Y1318472D02*
Y1317291D01*
G01Y1312173D02*
Y1310992D01*
G01Y1315323D02*
Y1314142D01*
G01Y1309024D02*
Y1307843D01*
G01X1184Y1340520D02*
Y1339339D01*
G01Y1343669D02*
Y1342488D01*
G01Y1337370D02*
Y1336189D01*
G01Y1331071D02*
Y1329890D01*
G01Y1334220D02*
Y1333039D01*
G01Y1327921D02*
Y1326740D01*
G01Y1321622D02*
Y1320441D01*
G01Y1324772D02*
Y1323591D01*
G01Y1318472D02*
Y1317291D01*
G01Y1312173D02*
Y1310992D01*
G01Y1315323D02*
Y1314142D01*
G01Y1309024D02*
Y1307843D01*
G01X9965Y1340520D02*
Y1339339D01*
G01Y1343669D02*
Y1342488D01*
G01Y1337370D02*
Y1336189D01*
G01Y1331071D02*
Y1329890D01*
G01Y1334220D02*
Y1333039D01*
G01Y1327921D02*
Y1326740D01*
G01Y1321622D02*
Y1320441D01*
G01Y1324772D02*
Y1323591D01*
G01Y1318472D02*
Y1317291D01*
G01Y1312173D02*
Y1310992D01*
G01Y1315323D02*
Y1314142D01*
G01Y1309024D02*
Y1307843D01*
G01X10075Y1340520D02*
Y1339339D01*
G01Y1343669D02*
Y1342488D01*
G01Y1337370D02*
Y1336189D01*
G01Y1331071D02*
Y1329890D01*
G01Y1334220D02*
Y1333039D01*
G01Y1327921D02*
Y1326740D01*
G01Y1321622D02*
Y1320441D01*
G01Y1324772D02*
Y1323591D01*
G01Y1318472D02*
Y1317291D01*
G01Y1312173D02*
Y1310992D01*
G01Y1315323D02*
Y1314142D01*
G01Y1309024D02*
Y1307843D01*
G01X-14147Y1312370D02*
X-14537Y1312163D01*
G01X-14147Y1309220D02*
X-14537Y1309013D01*
G01X-14147Y1306071D02*
X-14537Y1305863D01*
G01X-14677Y1307941D02*
X-14537Y1307853D01*
G01X-14449Y1307941D02*
X-13977Y1307646D01*
G01X-14677Y1311091D02*
X-14537Y1311003D01*
G01X-14449Y1311091D02*
X-13977Y1310795D01*
G01X-14677Y1314240D02*
X-14537Y1314152D01*
G01X-14449Y1314240D02*
X-13977Y1313945D01*
G01X-14677Y1317390D02*
X-14537Y1317302D01*
G01X-14449Y1317390D02*
X-13977Y1317094D01*
G01X-14677Y1320539D02*
X-14537Y1320452D01*
G01X-14449Y1320539D02*
X-13977Y1320244D01*
G01X-14677Y1323689D02*
X-14537Y1323601D01*
G01X-14449Y1323689D02*
X-13977Y1323394D01*
G01X-14677Y1326839D02*
X-14537Y1326751D01*
G01X-14449Y1326839D02*
X-13977Y1326543D01*
G01X-14677Y1329988D02*
X-14537Y1329900D01*
G01X-14449Y1329988D02*
X-13977Y1329693D01*
G01X-14677Y1333138D02*
X-14537Y1333050D01*
G01X-14449Y1333138D02*
X-13977Y1332843D01*
G01X-14677Y1336287D02*
X-14537Y1336200D01*
G01X-14449Y1336287D02*
X-13977Y1335992D01*
G01X-14537Y1307853D02*
X-14147Y1307646D01*
G01X-14537Y1311003D02*
X-14147Y1310795D01*
G01X-14537Y1314152D02*
X-14147Y1313945D01*
G01X-14537Y1317302D02*
X-14147Y1317094D01*
G01X-14537Y1320452D02*
X-14147Y1320244D01*
G01X-14537Y1323601D02*
X-14147Y1323394D01*
G01X-14537Y1326751D02*
X-14147Y1326543D01*
G01X-14537Y1329900D02*
X-14147Y1329693D01*
G01X-14537Y1333050D02*
X-14147Y1332843D01*
G01X-14537Y1336200D02*
X-14147Y1335992D01*
G01X-14537Y1339349D02*
X-14147Y1339142D01*
G01X-14537Y1342499D02*
X-14147Y1342291D01*
G01X-14677Y1339437D02*
X-14537Y1339349D01*
G01X-14449Y1339437D02*
X-13977Y1339142D01*
G01X-14677Y1342587D02*
X-14537Y1342499D01*
G01X-14449Y1342587D02*
X-13977Y1342291D01*
G01X-19469Y1305723D02*
X-18174Y1305737D01*
G01X-18435D02*
X-20801Y1305711D01*
G01X-18174Y1305737D02*
X-17126Y1305749D01*
G01X-15985Y1305759D02*
X-14449Y1305776D01*
G01X-14677D02*
X-18174Y1305737D01*
G01X-14677Y1305776D02*
X-16213Y1305759D01*
G01X-19469Y1305723D02*
X-20801Y1305711D01*
G01X-15985Y1305759D02*
X-17126Y1305749D01*
G01D02*
X-18435Y1305737D01*
G01X-18174D02*
X-18435D01*
G01X-15985Y1305759D02*
X-16213D01*
G01X-14449Y1305776D02*
X-14677D01*
G01X12410Y1305874D02*
X315D01*
G01X-13009Y1306071D02*
X-14147D01*
G01X512Y1306465D02*
X0D01*
G01X512Y1307252D02*
X0D01*
G01X-13009Y1307646D02*
X-14147D01*
G01X12410Y1307843D02*
X315D01*
G01X-14449Y1307941D02*
X-14677D01*
G01X-15985Y1307957D02*
X-16213D01*
G01X-18174Y1307979D02*
X-18435D01*
G01X-18174Y1308887D02*
X-18435D01*
G01X-15985Y1308909D02*
X-16213D01*
G01X-14449Y1308925D02*
X-14677D01*
G01X12410Y1309024D02*
X315D01*
G01X-13009Y1309220D02*
X-14147D01*
G01X512Y1309614D02*
X0D01*
G01X512Y1310402D02*
X0D01*
G01X-13009Y1310795D02*
X-14147D01*
G01X12410Y1310992D02*
X315D01*
G01X-14449Y1311091D02*
X-14677D01*
G01X-15985Y1311107D02*
X-16213D01*
G01X-18174Y1311128D02*
X-18435D01*
G01X-18174Y1312037D02*
X-18435D01*
G01X-15985Y1312058D02*
X-16213D01*
G01X-14449Y1312075D02*
X-14677D01*
G01X12410Y1312173D02*
X315D01*
G01X-13009Y1312370D02*
X-14147D01*
G01X-19469Y1307993D02*
X-20801Y1308005D01*
G01X-15985Y1307957D02*
X-18435Y1307979D01*
G01X-19469Y1311143D02*
X-20801Y1311155D01*
G01X-15985Y1311107D02*
X-18435Y1311128D01*
G01X-19469Y1314293D02*
X-20801Y1314304D01*
G01X-15985Y1314256D02*
X-18435Y1314278D01*
G01X-15985Y1307957D02*
X-14449Y1307941D01*
G01X-15985Y1311107D02*
X-14449Y1311091D01*
G01X-15985Y1314256D02*
X-14449Y1314240D01*
G01X-15985Y1317406D02*
X-14449Y1317390D01*
G01X-18435Y1307979D02*
X-20801Y1308005D01*
G01X-18435Y1311128D02*
X-20801Y1311155D01*
G01X-18435Y1314278D02*
X-20801Y1314304D01*
G01X-18435Y1317428D02*
X-20801Y1317454D01*
G01X-19469Y1307993D02*
X-16213Y1307957D01*
G01X-18174Y1307979D02*
X-14677Y1307941D01*
G01X-19469Y1311143D02*
X-16213Y1311107D01*
G01X-18174Y1311128D02*
X-14677Y1311091D01*
G01X-19469Y1314293D02*
X-16213Y1314256D01*
G01X-18174Y1314278D02*
X-14677Y1314240D01*
G01X-19469Y1317442D02*
X-16213Y1317406D01*
G01X-18174Y1317428D02*
X-14677Y1317390D01*
G01X-19469Y1308873D02*
X-18174Y1308887D01*
G01X-18435D02*
X-20801Y1308861D01*
G01X-18174Y1308887D02*
X-17126Y1308898D01*
G01X-19469Y1312022D02*
X-18174Y1312037D01*
G01X-18435D02*
X-20801Y1312011D01*
G01X-18174Y1312037D02*
X-17126Y1312048D01*
G01X-19469Y1315172D02*
X-18174Y1315186D01*
G01X-18435D02*
X-20801Y1315160D01*
G01X-18174Y1315186D02*
X-17126Y1315198D01*
G01X-19469Y1318322D02*
X-18174Y1318336D01*
G01X-18435D02*
X-20801Y1318310D01*
G01X-18174Y1318336D02*
X-17126Y1318347D01*
G01X-19469Y1321471D02*
X-18174Y1321485D01*
G01X-18435D02*
X-20801Y1321459D01*
G01X-18174Y1321485D02*
X-17126Y1321497D01*
G01X-19469Y1324621D02*
X-18174Y1324635D01*
G01X-18435D02*
X-20801Y1324609D01*
G01X-18174Y1324635D02*
X-17126Y1324646D01*
G01X-19469Y1327770D02*
X-18174Y1327785D01*
G01X-18435D02*
X-20801Y1327759D01*
G01X-18174Y1327785D02*
X-17126Y1327796D01*
G01X-19469Y1330920D02*
X-18174Y1330934D01*
G01X-18435D02*
X-20801Y1330908D01*
G01X-18174Y1330934D02*
X-17126Y1330946D01*
G01X-19469Y1334070D02*
X-18174Y1334084D01*
G01X-18435D02*
X-20801Y1334058D01*
G01X-18174Y1334084D02*
X-17126Y1334095D01*
G01X-19469Y1337219D02*
X-18174Y1337233D01*
G01X-18435D02*
X-20801Y1337207D01*
G01X-18174Y1337233D02*
X-17126Y1337245D01*
G01X-19469Y1340369D02*
X-18174Y1340383D01*
G01X-18435D02*
X-20801Y1340357D01*
G01X-18174Y1340383D02*
X-17126Y1340394D01*
G01X-19469Y1343519D02*
X-18174Y1343533D01*
G01X-18435D02*
X-20801Y1343507D01*
G01X-18174Y1343533D02*
X-17126Y1343544D01*
G01X-15985Y1308909D02*
X-14449Y1308925D01*
G01X-14677D02*
X-18174Y1308887D01*
G01X-14677Y1308925D02*
X-16213Y1308909D01*
G01X-15985Y1312058D02*
X-14449Y1312075D01*
G01X-14677D02*
X-18174Y1312037D01*
G01X-14677Y1312075D02*
X-16213Y1312058D01*
G01X-15985Y1315208D02*
X-14449Y1315224D01*
G01X-14677D02*
X-18174Y1315186D01*
G01X-14677Y1315224D02*
X-16213Y1315208D01*
G01X-15985Y1318357D02*
X-14449Y1318374D01*
G01X-14677D02*
X-18174Y1318336D01*
G01X-14677Y1318374D02*
X-16213Y1318357D01*
G01X-15985Y1321507D02*
X-14449Y1321524D01*
G01X-14677D02*
X-18174Y1321485D01*
G01X-14677Y1321524D02*
X-16213Y1321507D01*
G01X-15985Y1324657D02*
X-14449Y1324673D01*
G01X-14677D02*
X-18174Y1324635D01*
G01X-14677Y1324673D02*
X-16213Y1324657D01*
G01X-15985Y1327806D02*
X-14449Y1327823D01*
G01X-14677D02*
X-18174Y1327785D01*
G01X-14677Y1327823D02*
X-16213Y1327806D01*
G01X-15985Y1330956D02*
X-14449Y1330972D01*
G01X-14677D02*
X-18174Y1330934D01*
G01X-14677Y1330972D02*
X-16213Y1330956D01*
G01X-15985Y1334106D02*
X-14449Y1334122D01*
G01X-14677D02*
X-18174Y1334084D01*
G01X-14677Y1334122D02*
X-16213Y1334106D01*
G01X-15985Y1337255D02*
X-14449Y1337272D01*
G01X-14677D02*
X-18174Y1337233D01*
G01X-14677Y1337272D02*
X-16213Y1337255D01*
G01X-15985Y1340405D02*
X-14449Y1340421D01*
G01X-14677D02*
X-18174Y1340383D01*
G01X-14677Y1340421D02*
X-16213Y1340405D01*
G01X-15985Y1343554D02*
X-14449Y1343571D01*
G01X-14677D02*
X-18174Y1343533D01*
G01X-14677Y1343571D02*
X-16213Y1343554D01*
G01X-19469Y1308873D02*
X-20801Y1308861D01*
G01X-19469Y1312022D02*
X-20801Y1312011D01*
G01X-19469Y1315172D02*
X-20801Y1315160D01*
G01X-19469Y1318322D02*
X-20801Y1318310D01*
G01X-19469Y1321471D02*
X-20801Y1321459D01*
G01X-19469Y1324621D02*
X-20801Y1324609D01*
G01X-19469Y1327770D02*
X-20801Y1327759D01*
G01X-19469Y1330920D02*
X-20801Y1330908D01*
G01X-19469Y1334070D02*
X-20801Y1334058D01*
G01X-19469Y1337219D02*
X-20801Y1337207D01*
G01X-19469Y1340369D02*
X-20801Y1340357D01*
G01X-19469Y1343519D02*
X-20801Y1343507D01*
G01X-15985Y1308909D02*
X-17126Y1308898D01*
G01D02*
X-18435Y1308887D01*
G01X-15985Y1312058D02*
X-17126Y1312048D01*
G01D02*
X-18435Y1312037D01*
G01X-15985Y1315208D02*
X-17126Y1315198D01*
G01D02*
X-18435Y1315186D01*
G01X-15985Y1318357D02*
X-17126Y1318347D01*
G01D02*
X-18435Y1318336D01*
G01X-15985Y1321507D02*
X-17126Y1321497D01*
G01D02*
X-18435Y1321485D01*
G01X-15985Y1324657D02*
X-17126Y1324646D01*
G01D02*
X-18435Y1324635D01*
G01X-15985Y1327806D02*
X-17126Y1327796D01*
G01D02*
X-18435Y1327785D01*
G01X-15985Y1330956D02*
X-17126Y1330946D01*
G01D02*
X-18435Y1330934D01*
G01X-15985Y1334106D02*
X-17126Y1334095D01*
G01D02*
X-18435Y1334084D01*
G01X-15985Y1337255D02*
X-17126Y1337245D01*
G01D02*
X-18435Y1337233D01*
G01X-15985Y1340405D02*
X-17126Y1340394D01*
G01D02*
X-18435Y1340383D01*
G01X-15985Y1343554D02*
X-17126Y1343544D01*
G01D02*
X-18435Y1343533D01*
G01X512Y1312764D02*
X0D01*
G01X512Y1313551D02*
X0D01*
G01X-13009Y1313945D02*
X-14147D01*
G01X12410Y1314142D02*
X315D01*
G01X-14449Y1314240D02*
X-14677D01*
G01X-15985Y1314256D02*
X-16213D01*
G01X-18174Y1314278D02*
X-18435D01*
G01X-18174Y1315186D02*
X-18435D01*
G01X-15985Y1315208D02*
X-16213D01*
G01X-14449Y1315224D02*
X-14677D01*
G01X12410Y1315323D02*
X315D01*
G01X-13009Y1315520D02*
X-14147D01*
G01X512Y1315913D02*
X0D01*
G01X512Y1316701D02*
X0D01*
G01X-13009Y1317094D02*
X-14147D01*
G01X12410Y1317291D02*
X315D01*
G01X-14449Y1317390D02*
X-14677D01*
G01X-15985Y1317406D02*
X-16213D01*
G01X-18174Y1317428D02*
X-18435D01*
G01X-18174Y1318336D02*
X-18435D01*
G01X-15985Y1318357D02*
X-16213D01*
G01X-14449Y1318374D02*
X-14677D01*
G01X12410Y1318472D02*
X315D01*
G01X-13009Y1318669D02*
X-14147D01*
G01X512Y1319063D02*
X0D01*
G01X512Y1319850D02*
X0D01*
G01X-13009Y1320244D02*
X-14147D01*
G01X12410Y1320441D02*
X315D01*
G01X-14449Y1320539D02*
X-14677D01*
G01X-15985Y1320556D02*
X-16213D01*
G01X-18174Y1320577D02*
X-18435D01*
G01X-18174Y1321485D02*
X-18435D01*
G01X-15985Y1321507D02*
X-16213D01*
G01X-14449Y1321524D02*
X-14677D01*
G01X12410Y1321622D02*
X315D01*
G01X-13009Y1321819D02*
X-14147D01*
G01X512Y1322213D02*
X0D01*
G01X512Y1323000D02*
X0D01*
G01X-13009Y1323394D02*
X-14147D01*
G01X12410Y1323591D02*
X315D01*
G01X-14449Y1323689D02*
X-14677D01*
G01X-15985Y1323705D02*
X-16213D01*
G01X-18174Y1323727D02*
X-18435D01*
G01X-18174Y1324635D02*
X-18435D01*
G01X-15985Y1324657D02*
X-16213D01*
G01X-14449Y1324673D02*
X-14677D01*
G01X12410Y1324772D02*
X315D01*
G01X-13009Y1324969D02*
X-14147D01*
G01X512Y1325362D02*
X0D01*
G01X512Y1326150D02*
X0D01*
G01X-13009Y1326543D02*
X-14147D01*
G01X12410Y1326740D02*
X315D01*
G01X-14449Y1326839D02*
X-14677D01*
G01X-15985Y1326855D02*
X-16213D01*
G01X-18174Y1326876D02*
X-18435D01*
G01X-18174Y1327785D02*
X-18435D01*
G01X-15985Y1327806D02*
X-16213D01*
G01X-14449Y1327823D02*
X-14677D01*
G01X12410Y1327921D02*
X315D01*
G01X-13009Y1328118D02*
X-14147D01*
G01X512Y1328512D02*
X0D01*
G01X512Y1329299D02*
X0D01*
G01X-13009Y1329693D02*
X-14147D01*
G01X12410Y1329890D02*
X315D01*
G01X-14449Y1329988D02*
X-14677D01*
G01X-15985Y1330004D02*
X-16213D01*
G01X-18174Y1330026D02*
X-18435D01*
G01X-18174Y1330934D02*
X-18435D01*
G01X-15985Y1330956D02*
X-16213D01*
G01X-14449Y1330972D02*
X-14677D01*
G01X12410Y1331071D02*
X315D01*
G01X-13009Y1331268D02*
X-14147D01*
G01X512Y1331661D02*
X0D01*
G01X512Y1332449D02*
X0D01*
G01X-13009Y1332843D02*
X-14147D01*
G01X12410Y1333039D02*
X315D01*
G01X-14449Y1333138D02*
X-14677D01*
G01X-15985Y1333154D02*
X-16213D01*
G01X-18174Y1333176D02*
X-18435D01*
G01X-18174Y1334084D02*
X-18435D01*
G01X-15985Y1334106D02*
X-16213D01*
G01X-14449Y1334122D02*
X-14677D01*
G01X12410Y1334220D02*
X315D01*
G01X-13009Y1334417D02*
X-14147D01*
G01X512Y1334811D02*
X0D01*
G01X512Y1335598D02*
X0D01*
G01X-13009Y1335992D02*
X-14147D01*
G01X12410Y1336189D02*
X315D01*
G01X-14449Y1336287D02*
X-14677D01*
G01X-15985Y1336304D02*
X-16213D01*
G01X-18174Y1336325D02*
X-18435D01*
G01X-18174Y1337233D02*
X-18435D01*
G01X-15985Y1337255D02*
X-16213D01*
G01X-14449Y1337272D02*
X-14677D01*
G01X12410Y1337370D02*
X315D01*
G01X-13009Y1337567D02*
X-14147D01*
G01X512Y1337961D02*
X0D01*
G01X512Y1338748D02*
X0D01*
G01X-13009Y1339142D02*
X-14147D01*
G01X12410Y1339339D02*
X315D01*
G01X-14449Y1339437D02*
X-14677D01*
G01X-15985Y1339453D02*
X-16213D01*
G01X-18174Y1339475D02*
X-18435D01*
G01X-18174Y1340383D02*
X-18435D01*
G01X-15985Y1340405D02*
X-16213D01*
G01X-14449Y1340421D02*
X-14677D01*
G01X12410Y1340520D02*
X315D01*
G01X-13009Y1340717D02*
X-14147D01*
G01X512Y1341110D02*
X0D01*
G01X512Y1341898D02*
X0D01*
G01X-13009Y1342291D02*
X-14147D01*
G01X12410Y1342488D02*
X315D01*
G01X-14449Y1342587D02*
X-14677D01*
G01X-15985Y1342603D02*
X-16213D01*
G01X-18174Y1342624D02*
X-18435D01*
G01X-18174Y1343533D02*
X-18435D01*
G01X-15985Y1343554D02*
X-16213D01*
G01X-14449Y1343571D02*
X-14677D01*
G01X12410Y1343669D02*
X315D01*
G01X-13009Y1343866D02*
X-14147D01*
G01X512Y1344260D02*
X0D01*
G01X512Y1345047D02*
X0D01*
G01X-19469Y1317442D02*
X-20801Y1317454D01*
G01X-15985Y1317406D02*
X-18435Y1317428D01*
G01X-19469Y1320592D02*
X-20801Y1320604D01*
G01X-15985Y1320556D02*
X-18435Y1320577D01*
G01X-19469Y1323741D02*
X-20801Y1323753D01*
G01X-15985Y1323705D02*
X-18435Y1323727D01*
G01X-19469Y1326891D02*
X-20801Y1326903D01*
G01X-15985Y1326855D02*
X-18435Y1326876D01*
G01X-19469Y1330041D02*
X-20801Y1330052D01*
G01X-15985Y1330004D02*
X-18435Y1330026D01*
G01X-19469Y1333190D02*
X-20801Y1333202D01*
G01X-15985Y1333154D02*
X-18435Y1333176D01*
G01X-19469Y1336340D02*
X-20801Y1336352D01*
G01X-15985Y1336304D02*
X-18435Y1336325D01*
G01X-19469Y1339489D02*
X-20801Y1339501D01*
G01X-15985Y1339453D02*
X-18435Y1339475D01*
G01X-19469Y1342639D02*
X-20801Y1342651D01*
G01X-15985Y1342603D02*
X-18435Y1342624D01*
G01X-15985Y1320556D02*
X-14449Y1320539D01*
G01X-15985Y1323705D02*
X-14449Y1323689D01*
G01X-15985Y1326855D02*
X-14449Y1326839D01*
G01X-15985Y1330004D02*
X-14449Y1329988D01*
G01X-15985Y1333154D02*
X-14449Y1333138D01*
G01X-15985Y1336304D02*
X-14449Y1336287D01*
G01X-15985Y1339453D02*
X-14449Y1339437D01*
G01X-15985Y1342603D02*
X-14449Y1342587D01*
G01X-18435Y1320577D02*
X-20801Y1320604D01*
G01X-18435Y1323727D02*
X-20801Y1323753D01*
G01X-18435Y1326876D02*
X-20801Y1326903D01*
G01X-18435Y1330026D02*
X-20801Y1330052D01*
G01X-18435Y1333176D02*
X-20801Y1333202D01*
G01X-18435Y1336325D02*
X-20801Y1336352D01*
G01X-18435Y1339475D02*
X-20801Y1339501D01*
G01X-18435Y1342624D02*
X-20801Y1342651D01*
G01X-19469Y1320592D02*
X-16213Y1320556D01*
G01X-18174Y1320577D02*
X-14677Y1320539D01*
G01X-19469Y1323741D02*
X-16213Y1323705D01*
G01X-18174Y1323727D02*
X-14677Y1323689D01*
G01X-19469Y1326891D02*
X-16213Y1326855D01*
G01X-18174Y1326876D02*
X-14677Y1326839D01*
G01X-19469Y1330041D02*
X-16213Y1330004D01*
G01X-18174Y1330026D02*
X-14677Y1329988D01*
G01X-19469Y1333190D02*
X-16213Y1333154D01*
G01X-18174Y1333176D02*
X-14677Y1333138D01*
G01X-19469Y1336340D02*
X-16213Y1336304D01*
G01X-18174Y1336325D02*
X-14677Y1336287D01*
G01X-19469Y1339489D02*
X-16213Y1339453D01*
G01X-18174Y1339475D02*
X-14677Y1339437D01*
G01X-19469Y1342639D02*
X-16213Y1342603D01*
G01X-18174Y1342624D02*
X-14677Y1342587D01*
G01X-20801Y1356105D02*
Y1355249D01*
G01Y1349806D02*
Y1348950D01*
G01Y1352956D02*
Y1352100D01*
G01Y1346656D02*
Y1345800D01*
G01X-19469Y1356111D02*
Y1355243D01*
G01Y1349812D02*
Y1348944D01*
G01Y1352961D02*
Y1352094D01*
G01Y1346662D02*
Y1345794D01*
G01X-18435Y1356131D02*
Y1355223D01*
G01Y1349832D02*
Y1348924D01*
G01Y1352981D02*
Y1352073D01*
G01Y1346682D02*
Y1345774D01*
G01X-18174Y1356131D02*
Y1355223D01*
G01Y1349832D02*
Y1348924D01*
G01Y1352981D02*
Y1352073D01*
G01Y1346682D02*
Y1345774D01*
G01X-16213Y1356153D02*
Y1355201D01*
G01Y1349854D02*
Y1348902D01*
G01Y1353003D02*
Y1352052D01*
G01Y1346704D02*
Y1345752D01*
G01X-15985Y1356153D02*
Y1355201D01*
G01Y1349854D02*
Y1348902D01*
G01Y1353003D02*
Y1352052D01*
G01Y1346704D02*
Y1345752D01*
G01X-14537Y1356257D02*
X-14677Y1356169D01*
G01X-13977Y1356465D02*
X-14449Y1356169D01*
G01X-14537Y1353107D02*
X-14677Y1353020D01*
G01X-13977Y1353315D02*
X-14449Y1353020D01*
G01X-14537Y1349958D02*
X-14677Y1349870D01*
G01X-13977Y1350165D02*
X-14449Y1349870D01*
G01X-14537Y1346808D02*
X-14677Y1346720D01*
G01X-13977Y1347016D02*
X-14449Y1346720D01*
G01X-14147Y1356465D02*
X-14537Y1356257D01*
G01X-14147Y1353315D02*
X-14537Y1353107D01*
G01X-14147Y1350165D02*
X-14537Y1349958D01*
G01X-14147Y1347016D02*
X-14537Y1346808D01*
G01Y1356257D02*
Y1355097D01*
G01Y1349958D02*
Y1348798D01*
G01Y1353107D02*
Y1351948D01*
G01Y1346808D02*
Y1345648D01*
G01X-13009Y1356465D02*
Y1354890D01*
G01Y1350165D02*
Y1348591D01*
G01Y1353315D02*
Y1351740D01*
G01Y1347016D02*
Y1345441D01*
G01X315Y1356858D02*
Y1356268D01*
G01Y1355087D02*
Y1354496D01*
G01Y1350559D02*
Y1349969D01*
G01Y1353709D02*
Y1353118D01*
G01Y1351937D02*
Y1351346D01*
G01Y1347409D02*
Y1346819D01*
G01Y1348787D02*
Y1348197D01*
G01X512Y1356858D02*
Y1356268D01*
G01Y1355087D02*
Y1354496D01*
G01Y1350559D02*
Y1349969D01*
G01Y1353709D02*
Y1353118D01*
G01Y1351937D02*
Y1351346D01*
G01Y1347409D02*
Y1346819D01*
G01Y1348787D02*
Y1348197D01*
G01X709Y1356268D02*
Y1355087D01*
G01Y1349969D02*
Y1348787D01*
G01Y1353118D02*
Y1351937D01*
G01Y1346819D02*
Y1345638D01*
G01X1074Y1356268D02*
Y1355087D01*
G01Y1349969D02*
Y1348787D01*
G01Y1353118D02*
Y1351937D01*
G01Y1346819D02*
Y1345638D01*
G01X1184Y1356268D02*
Y1355087D01*
G01Y1349969D02*
Y1348787D01*
G01Y1353118D02*
Y1351937D01*
G01Y1346819D02*
Y1345638D01*
G01X9965Y1356268D02*
Y1355087D01*
G01Y1349969D02*
Y1348787D01*
G01Y1353118D02*
Y1351937D01*
G01Y1346819D02*
Y1345638D01*
G01X10075Y1356268D02*
Y1355087D01*
G01Y1349969D02*
Y1348787D01*
G01Y1353118D02*
Y1351937D01*
G01Y1346819D02*
Y1345638D01*
G01X-14537Y1345648D02*
X-14147Y1345441D01*
G01X-14537Y1348798D02*
X-14147Y1348591D01*
G01X-14537Y1351948D02*
X-14147Y1351740D01*
G01X-14537Y1355097D02*
X-14147Y1354890D01*
G01X-14677Y1345736D02*
X-14537Y1345648D01*
G01X-14449Y1345736D02*
X-13977Y1345441D01*
G01X-14677Y1348886D02*
X-14537Y1348798D01*
G01X-14449Y1348886D02*
X-13977Y1348591D01*
G01X-14677Y1352035D02*
X-14537Y1351948D01*
G01X-14449Y1352035D02*
X-13977Y1351740D01*
G01X-14677Y1355185D02*
X-14537Y1355097D01*
G01X-14449Y1355185D02*
X-13977Y1354890D01*
G01X-19469Y1346668D02*
X-18174Y1346682D01*
G01X-18435D02*
X-20801Y1346656D01*
G01X-18174Y1346682D02*
X-17126Y1346694D01*
G01X-19469Y1349818D02*
X-18174Y1349832D01*
G01X-18435D02*
X-20801Y1349806D01*
G01X-18174Y1349832D02*
X-17126Y1349843D01*
G01X-19469Y1352967D02*
X-18174Y1352981D01*
G01X-18435D02*
X-20801Y1352956D01*
G01X-18174Y1352981D02*
X-17126Y1352993D01*
G01X-19469Y1356117D02*
X-18174Y1356131D01*
G01X-18435D02*
X-20801Y1356105D01*
G01X-18174Y1356131D02*
X-17126Y1356143D01*
G01X-15985Y1346704D02*
X-14449Y1346720D01*
G01X-14677D02*
X-18174Y1346682D01*
G01X-14677Y1346720D02*
X-16213Y1346704D01*
G01X-15985Y1349854D02*
X-14449Y1349870D01*
G01X-14677D02*
X-18174Y1349832D01*
G01X-14677Y1349870D02*
X-16213Y1349854D01*
G01X-15985Y1353003D02*
X-14449Y1353020D01*
G01X-14677D02*
X-18174Y1352981D01*
G01X-14677Y1353020D02*
X-16213Y1353003D01*
G01X-15985Y1356153D02*
X-14449Y1356169D01*
G01X-14677D02*
X-18174Y1356131D01*
G01X-14677Y1356169D02*
X-16213Y1356153D01*
G01X-19469Y1346668D02*
X-20801Y1346656D01*
G01X-19469Y1349818D02*
X-20801Y1349806D01*
G01X-19469Y1352967D02*
X-20801Y1352956D01*
G01X-19469Y1356117D02*
X-20801Y1356105D01*
G01X-15985Y1346704D02*
X-17126Y1346694D01*
G01D02*
X-18435Y1346682D01*
G01X-15985Y1349854D02*
X-17126Y1349843D01*
G01D02*
X-18435Y1349832D01*
G01X-15985Y1353003D02*
X-17126Y1352993D01*
G01D02*
X-18435Y1352981D01*
G01X-15985Y1356153D02*
X-17126Y1356143D01*
G01D02*
X-18435Y1356131D01*
G01X-13009Y1345441D02*
X-14147D01*
G01X12410Y1345638D02*
X315D01*
G01X-14449Y1345736D02*
X-14677D01*
G01X-15985Y1345752D02*
X-16213D01*
G01X-18174Y1345774D02*
X-18435D01*
G01X-18174Y1346682D02*
X-18435D01*
G01X-15985Y1346704D02*
X-16213D01*
G01X-14449Y1346720D02*
X-14677D01*
G01X12410Y1346819D02*
X315D01*
G01X-13009Y1347016D02*
X-14147D01*
G01X512Y1347409D02*
X0D01*
G01X512Y1348197D02*
X0D01*
G01X-13009Y1348591D02*
X-14147D01*
G01X12410Y1348787D02*
X315D01*
G01X-14449Y1348886D02*
X-14677D01*
G01X-15985Y1348902D02*
X-16213D01*
G01X-18174Y1348924D02*
X-18435D01*
G01X-18174Y1349832D02*
X-18435D01*
G01X-15985Y1349854D02*
X-16213D01*
G01X-14449Y1349870D02*
X-14677D01*
G01X12410Y1349969D02*
X315D01*
G01X-13009Y1350165D02*
X-14147D01*
G01X512Y1350559D02*
X0D01*
G01X512Y1351346D02*
X0D01*
G01X-13009Y1351740D02*
X-14147D01*
G01X12410Y1351937D02*
X315D01*
G01X-14449Y1352035D02*
X-14677D01*
G01X-15985Y1352052D02*
X-16213D01*
G01X-18174Y1352073D02*
X-18435D01*
G01X-18174Y1352981D02*
X-18435D01*
G01X-15985Y1353003D02*
X-16213D01*
G01X-14449Y1353020D02*
X-14677D01*
G01X12410Y1353118D02*
X315D01*
G01X-13009Y1353315D02*
X-14147D01*
G01X512Y1353709D02*
X0D01*
G01X512Y1354496D02*
X0D01*
G01X-13009Y1354890D02*
X-14147D01*
G01X12410Y1355087D02*
X315D01*
G01X-14449Y1355185D02*
X-14677D01*
G01X-15985Y1355201D02*
X-16213D01*
G01X-18174Y1355223D02*
X-18435D01*
G01X-18174Y1356131D02*
X-18435D01*
G01X-15985Y1356153D02*
X-16213D01*
G01X-14449Y1356169D02*
X-14677D01*
G01X12410Y1356268D02*
X315D01*
G01X-13009Y1356465D02*
X-14147D01*
G01X512Y1356858D02*
X0D01*
G01X-19469Y1345789D02*
X-20801Y1345800D01*
G01X-15985Y1345752D02*
X-18435Y1345774D01*
G01X-19469Y1348938D02*
X-20801Y1348950D01*
G01X-15985Y1348902D02*
X-18435Y1348924D01*
G01X-19469Y1352088D02*
X-20801Y1352100D01*
G01X-15985Y1352052D02*
X-18435Y1352073D01*
G01X-19469Y1355237D02*
X-20801Y1355249D01*
G01X-15985Y1355201D02*
X-18435Y1355223D01*
G01X-15985Y1345752D02*
X-14449Y1345736D01*
G01X-15985Y1348902D02*
X-14449Y1348886D01*
G01X-15985Y1352052D02*
X-14449Y1352035D01*
G01X-15985Y1355201D02*
X-14449Y1355185D01*
G01X-18435Y1345774D02*
X-20801Y1345800D01*
G01X-18435Y1348924D02*
X-20801Y1348950D01*
G01X-18435Y1352073D02*
X-20801Y1352100D01*
G01X-18435Y1355223D02*
X-20801Y1355249D01*
G01X-19469Y1345789D02*
X-16213Y1345752D01*
G01X-18174Y1345774D02*
X-14677Y1345736D01*
G01X-19469Y1348938D02*
X-16213Y1348902D01*
G01X-18174Y1348924D02*
X-14677Y1348886D01*
G01X-19469Y1352088D02*
X-16213Y1352052D01*
G01X-18174Y1352073D02*
X-14677Y1352035D01*
G01X-19469Y1355237D02*
X-16213Y1355201D01*
G01X-18174Y1355223D02*
X-14677Y1355185D01*
G01X-20801Y1302562D02*
Y1301706D01*
G01Y1305711D02*
Y1304856D01*
G01Y1299412D02*
Y1298556D01*
G01Y1293113D02*
Y1292257D01*
G01Y1296263D02*
Y1295407D01*
G01Y1289963D02*
Y1289107D01*
G01Y1286814D02*
Y1285958D01*
G01X-19469Y1302568D02*
Y1301700D01*
G01Y1305717D02*
Y1304850D01*
G01Y1299418D02*
Y1298550D01*
G01Y1293119D02*
Y1292251D01*
G01Y1296269D02*
Y1295401D01*
G01Y1289969D02*
Y1289102D01*
G01Y1286820D02*
Y1285952D01*
G01X-18435Y1302588D02*
Y1301680D01*
G01Y1305737D02*
Y1304829D01*
G01Y1299438D02*
Y1298530D01*
G01Y1293139D02*
Y1292231D01*
G01Y1296289D02*
Y1295380D01*
G01Y1289989D02*
Y1289081D01*
G01Y1286840D02*
Y1285931D01*
G01X-18174Y1302588D02*
Y1301680D01*
G01Y1305737D02*
Y1304829D01*
G01Y1299438D02*
Y1298530D01*
G01Y1293139D02*
Y1292231D01*
G01Y1296289D02*
Y1295380D01*
G01Y1289989D02*
Y1289081D01*
G01Y1286840D02*
Y1285931D01*
G01X-16213Y1302609D02*
Y1301658D01*
G01Y1305759D02*
Y1304807D01*
G01Y1299460D02*
Y1298508D01*
G01Y1293161D02*
Y1292209D01*
G01Y1296310D02*
Y1295359D01*
G01Y1290011D02*
Y1289059D01*
G01Y1286861D02*
Y1285910D01*
G01X-15985Y1302609D02*
Y1301658D01*
G01Y1305759D02*
Y1304807D01*
G01Y1299460D02*
Y1298508D01*
G01Y1293161D02*
Y1292209D01*
G01Y1296310D02*
Y1295359D01*
G01Y1290011D02*
Y1289059D01*
G01Y1286861D02*
Y1285910D01*
G01X-14537Y1302714D02*
X-14677Y1302626D01*
G01X-13977Y1302921D02*
X-14449Y1302626D01*
G01X-14537Y1299564D02*
X-14677Y1299476D01*
G01X-13977Y1299772D02*
X-14449Y1299476D01*
G01X-14537Y1296415D02*
X-14677Y1296327D01*
G01X-13977Y1296622D02*
X-14449Y1296327D01*
G01X-14537Y1293265D02*
X-14677Y1293177D01*
G01X-13977Y1293472D02*
X-14449Y1293177D01*
G01X-14537Y1290115D02*
X-14677Y1290028D01*
G01X-13977Y1290323D02*
X-14449Y1290028D01*
G01X-14537Y1302714D02*
Y1301554D01*
G01Y1305863D02*
Y1304704D01*
G01Y1299564D02*
Y1298404D01*
G01Y1293265D02*
Y1292105D01*
G01Y1296415D02*
Y1295255D01*
G01Y1290115D02*
Y1288956D01*
G01Y1286966D02*
Y1285806D01*
G01X-13009Y1302921D02*
Y1301346D01*
G01Y1306071D02*
Y1304496D01*
G01Y1299772D02*
Y1298197D01*
G01Y1293472D02*
Y1291898D01*
G01Y1296622D02*
Y1295047D01*
G01Y1290323D02*
Y1288748D01*
G01Y1287173D02*
Y1285598D01*
G01X315Y1303315D02*
Y1302724D01*
G01Y1304693D02*
Y1304102D01*
G01Y1300165D02*
Y1299575D01*
G01Y1298394D02*
Y1297803D01*
G01Y1301543D02*
Y1300953D01*
G01Y1293866D02*
Y1293276D01*
G01Y1297016D02*
Y1296425D01*
G01Y1295244D02*
Y1294654D01*
G01Y1290717D02*
Y1290126D01*
G01Y1288945D02*
Y1288354D01*
G01Y1292094D02*
Y1291504D01*
G01Y1287567D02*
Y1286976D01*
G01Y1285795D02*
Y1285205D01*
G01X512Y1303315D02*
Y1302724D01*
G01Y1304693D02*
Y1304102D01*
G01Y1300165D02*
Y1299575D01*
G01Y1298394D02*
Y1297803D01*
G01Y1301543D02*
Y1300953D01*
G01Y1293866D02*
Y1293276D01*
G01Y1297016D02*
Y1296425D01*
G01Y1295244D02*
Y1294654D01*
G01Y1290717D02*
Y1290126D01*
G01Y1288945D02*
Y1288354D01*
G01Y1292094D02*
Y1291504D01*
G01Y1287567D02*
Y1286976D01*
G01Y1285795D02*
Y1285205D01*
G01X709Y1302724D02*
Y1301543D01*
G01Y1305874D02*
Y1304693D01*
G01Y1299575D02*
Y1298394D01*
G01Y1293276D02*
Y1292094D01*
G01Y1296425D02*
Y1295244D01*
G01Y1290126D02*
Y1288945D01*
G01Y1286976D02*
Y1285795D01*
G01X1074Y1302724D02*
Y1301543D01*
G01Y1305874D02*
Y1304693D01*
G01Y1299575D02*
Y1298394D01*
G01Y1293276D02*
Y1292094D01*
G01Y1296425D02*
Y1295244D01*
G01Y1290126D02*
Y1288945D01*
G01Y1286976D02*
Y1285795D01*
G01X1184Y1302724D02*
Y1301543D01*
G01Y1305874D02*
Y1304693D01*
G01Y1299575D02*
Y1298394D01*
G01Y1293276D02*
Y1292094D01*
G01Y1296425D02*
Y1295244D01*
G01Y1290126D02*
Y1288945D01*
G01Y1286976D02*
Y1285795D01*
G01X9965Y1302724D02*
Y1301543D01*
G01Y1305874D02*
Y1304693D01*
G01Y1299575D02*
Y1298394D01*
G01Y1293276D02*
Y1292094D01*
G01Y1296425D02*
Y1295244D01*
G01Y1290126D02*
Y1288945D01*
G01Y1286976D02*
Y1285795D01*
G01X10075Y1302724D02*
Y1301543D01*
G01Y1305874D02*
Y1304693D01*
G01Y1299575D02*
Y1298394D01*
G01Y1293276D02*
Y1292094D01*
G01Y1296425D02*
Y1295244D01*
G01Y1290126D02*
Y1288945D01*
G01Y1286976D02*
Y1285795D01*
G01X-14537Y1286966D02*
X-14677Y1286878D01*
G01X-13977Y1287173D02*
X-14449Y1286878D01*
G01X-14147Y1302921D02*
X-14537Y1302714D01*
G01X-14147Y1299772D02*
X-14537Y1299564D01*
G01X-14147Y1296622D02*
X-14537Y1296415D01*
G01X-14147Y1293472D02*
X-14537Y1293265D01*
G01X-14147Y1290323D02*
X-14537Y1290115D01*
G01X-14147Y1287173D02*
X-14537Y1286966D01*
G01Y1285806D02*
X-14147Y1285598D01*
G01X-14677Y1285894D02*
X-14537Y1285806D01*
G01X-14449Y1285894D02*
X-13977Y1285598D01*
G01X-14677Y1289043D02*
X-14537Y1288956D01*
G01X-14449Y1289043D02*
X-13977Y1288748D01*
G01X-14677Y1292193D02*
X-14537Y1292105D01*
G01X-14449Y1292193D02*
X-13977Y1291898D01*
G01X-14677Y1295343D02*
X-14537Y1295255D01*
G01X-14449Y1295343D02*
X-13977Y1295047D01*
G01X-14677Y1298492D02*
X-14537Y1298404D01*
G01X-14449Y1298492D02*
X-13977Y1298197D01*
G01X-14677Y1301642D02*
X-14537Y1301554D01*
G01X-14449Y1301642D02*
X-13977Y1301346D01*
G01X-14677Y1304791D02*
X-14537Y1304704D01*
G01X-14449Y1304791D02*
X-13977Y1304496D01*
G01X-14537Y1288956D02*
X-14147Y1288748D01*
G01X-14537Y1292105D02*
X-14147Y1291898D01*
G01X-14537Y1295255D02*
X-14147Y1295047D01*
G01X-14537Y1298404D02*
X-14147Y1298197D01*
G01X-14537Y1301554D02*
X-14147Y1301346D01*
G01X-14537Y1304704D02*
X-14147Y1304496D01*
G01X-19469Y1286826D02*
X-18174Y1286840D01*
G01X-18435D02*
X-20801Y1286814D01*
G01X-18174Y1286840D02*
X-17126Y1286851D01*
G01X-19469Y1289975D02*
X-18174Y1289989D01*
G01X-18435D02*
X-20801Y1289963D01*
G01X-18174Y1289989D02*
X-17126Y1290001D01*
G01X-19469Y1293125D02*
X-18174Y1293139D01*
G01X-18435D02*
X-20801Y1293113D01*
G01X-18174Y1293139D02*
X-17126Y1293150D01*
G01X-19469Y1296274D02*
X-18174Y1296289D01*
G01X-18435D02*
X-20801Y1296263D01*
G01X-18174Y1296289D02*
X-17126Y1296300D01*
G01X-19469Y1299424D02*
X-18174Y1299438D01*
G01X-18435D02*
X-20801Y1299412D01*
G01X-18174Y1299438D02*
X-17126Y1299450D01*
G01X-19469Y1302574D02*
X-18174Y1302588D01*
G01X-18435D02*
X-20801Y1302562D01*
G01X-18174Y1302588D02*
X-17126Y1302599D01*
G01X-15985Y1286861D02*
X-14449Y1286878D01*
G01X-14677D02*
X-18174Y1286840D01*
G01X-14677Y1286878D02*
X-16213Y1286861D01*
G01X-15985Y1290011D02*
X-14449Y1290028D01*
G01X-14677D02*
X-18174Y1289989D01*
G01X-14677Y1290028D02*
X-16213Y1290011D01*
G01X-15985Y1293161D02*
X-14449Y1293177D01*
G01X-14677D02*
X-18174Y1293139D01*
G01X-14677Y1293177D02*
X-16213Y1293161D01*
G01X-15985Y1296310D02*
X-14449Y1296327D01*
G01X-14677D02*
X-18174Y1296289D01*
G01X-14677Y1296327D02*
X-16213Y1296310D01*
G01X-15985Y1299460D02*
X-14449Y1299476D01*
G01X-14677D02*
X-18174Y1299438D01*
G01X-14677Y1299476D02*
X-16213Y1299460D01*
G01X-15985Y1302609D02*
X-14449Y1302626D01*
G01X-14677D02*
X-18174Y1302588D01*
G01X-14677Y1302626D02*
X-16213Y1302609D01*
G01X-19469Y1286826D02*
X-20801Y1286814D01*
G01X-19469Y1289975D02*
X-20801Y1289963D01*
G01X-19469Y1293125D02*
X-20801Y1293113D01*
G01X-19469Y1296274D02*
X-20801Y1296263D01*
G01X-19469Y1299424D02*
X-20801Y1299412D01*
G01X-19469Y1302574D02*
X-20801Y1302562D01*
G01X-15985Y1286861D02*
X-17126Y1286851D01*
G01D02*
X-18435Y1286840D01*
G01X-15985Y1290011D02*
X-17126Y1290001D01*
G01D02*
X-18435Y1289989D01*
G01X-15985Y1293161D02*
X-17126Y1293150D01*
G01D02*
X-18435Y1293139D01*
G01X-15985Y1296310D02*
X-17126Y1296300D01*
G01D02*
X-18435Y1296289D01*
G01X-15985Y1299460D02*
X-17126Y1299450D01*
G01D02*
X-18435Y1299438D01*
G01X-15985Y1302609D02*
X-17126Y1302599D01*
G01D02*
X-18435Y1302588D01*
G01X512Y1285205D02*
X0D01*
G01X-13009Y1285598D02*
X-14147D01*
G01X12410Y1285795D02*
X315D01*
G01X-14449Y1285894D02*
X-14677D01*
G01X-15985Y1285910D02*
X-16213D01*
G01X-18174Y1285931D02*
X-18435D01*
G01X-18174Y1286840D02*
X-18435D01*
G01X-15985Y1286861D02*
X-16213D01*
G01X-14449Y1286878D02*
X-14677D01*
G01X12410Y1286976D02*
X315D01*
G01X-13009Y1287173D02*
X-14147D01*
G01X512Y1287567D02*
X0D01*
G01X512Y1288354D02*
X0D01*
G01X-13009Y1288748D02*
X-14147D01*
G01X12410Y1288945D02*
X315D01*
G01X-14449Y1289043D02*
X-14677D01*
G01X-15985Y1289059D02*
X-16213D01*
G01X-18174Y1289081D02*
X-18435D01*
G01Y1289989D02*
X-18174D01*
G01X-15985Y1290011D02*
X-16213D01*
G01X-14449Y1290028D02*
X-14677D01*
G01X12410Y1290126D02*
X315D01*
G01X-13009Y1290323D02*
X-14147D01*
G01X512Y1290717D02*
X0D01*
G01X512Y1291504D02*
X0D01*
G01X-13009Y1291898D02*
X-14147D01*
G01X12410Y1292094D02*
X315D01*
G01X-14449Y1292193D02*
X-14677D01*
G01X-15985Y1292209D02*
X-16213D01*
G01X-18174Y1292231D02*
X-18435D01*
G01X-18174Y1293139D02*
X-18435D01*
G01X-15985Y1293161D02*
X-16213D01*
G01X-14449Y1293177D02*
X-14677D01*
G01X12410Y1293276D02*
X315D01*
G01X-13009Y1293472D02*
X-14147D01*
G01X512Y1293866D02*
X0D01*
G01X512Y1294654D02*
X0D01*
G01X-13009Y1295047D02*
X-14147D01*
G01X12410Y1295244D02*
X315D01*
G01X-14449Y1295343D02*
X-14677D01*
G01X-15985Y1295359D02*
X-16213D01*
G01X-18174Y1295380D02*
X-18435D01*
G01X-18174Y1296289D02*
X-18435D01*
G01X-15985Y1296310D02*
X-16213D01*
G01X-14449Y1296327D02*
X-14677D01*
G01X12410Y1296425D02*
X315D01*
G01X-13009Y1296622D02*
X-14147D01*
G01X512Y1297016D02*
X0D01*
G01X512Y1297803D02*
X0D01*
G01X-13009Y1298197D02*
X-14147D01*
G01X12410Y1298394D02*
X315D01*
G01X-14449Y1298492D02*
X-14677D01*
G01X-15985Y1298508D02*
X-16213D01*
G01X-18174Y1298530D02*
X-18435D01*
G01X-18174Y1299438D02*
X-18435D01*
G01X-16213Y1299460D02*
X-15985D01*
G01X-14449Y1299476D02*
X-14677D01*
G01X12410Y1299575D02*
X315D01*
G01X-13009Y1299772D02*
X-14147D01*
G01X512Y1300165D02*
X0D01*
G01X512Y1300953D02*
X0D01*
G01X-13009Y1301346D02*
X-14147D01*
G01X12410Y1301543D02*
X315D01*
G01X-14449Y1301642D02*
X-14677D01*
G01X-15985Y1301658D02*
X-16213D01*
G01X-18174Y1301680D02*
X-18435D01*
G01X-18174Y1302588D02*
X-18435D01*
G01X-15985Y1302609D02*
X-16213D01*
G01X-14449Y1302626D02*
X-14677D01*
G01X12410Y1302724D02*
X315D01*
G01X-13009Y1302921D02*
X-14147D01*
G01X512Y1303315D02*
X0D01*
G01X512Y1304102D02*
X0D01*
G01X-13009Y1304496D02*
X-14147D01*
G01X12410Y1304693D02*
X315D01*
G01X-14449Y1304791D02*
X-14677D01*
G01X-15985Y1304807D02*
X-16213D01*
G01X-18174Y1304829D02*
X-18435D01*
G01X-19469Y1285946D02*
X-20801Y1285958D01*
G01X-15985Y1285910D02*
X-18435Y1285931D01*
G01X-19469Y1289096D02*
X-20801Y1289107D01*
G01X-15985Y1289059D02*
X-18435Y1289081D01*
G01X-19469Y1292245D02*
X-20801Y1292257D01*
G01X-15985Y1292209D02*
X-18435Y1292231D01*
G01X-19469Y1295395D02*
X-20801Y1295407D01*
G01X-15985Y1295359D02*
X-18435Y1295380D01*
G01X-19469Y1298544D02*
X-20801Y1298556D01*
G01X-15985Y1298508D02*
X-18435Y1298530D01*
G01X-19469Y1301694D02*
X-20801Y1301706D01*
G01X-15985Y1301658D02*
X-18435Y1301680D01*
G01X-19469Y1304844D02*
X-20801Y1304856D01*
G01X-15985Y1304807D02*
X-18435Y1304829D01*
G01X-15985Y1285910D02*
X-14449Y1285894D01*
G01X-15985Y1289059D02*
X-14449Y1289043D01*
G01X-15985Y1292209D02*
X-14449Y1292193D01*
G01X-15985Y1295359D02*
X-14449Y1295343D01*
G01X-15985Y1298508D02*
X-14449Y1298492D01*
G01X-15985Y1301658D02*
X-14449Y1301642D01*
G01X-15985Y1304807D02*
X-14449Y1304791D01*
G01X-18435Y1285931D02*
X-20801Y1285958D01*
G01X-18435Y1289081D02*
X-20801Y1289107D01*
G01X-18435Y1292231D02*
X-20801Y1292257D01*
G01X-18435Y1295380D02*
X-20801Y1295407D01*
G01X-18435Y1298530D02*
X-20801Y1298556D01*
G01X-18435Y1301680D02*
X-20801Y1301706D01*
G01X-18435Y1304829D02*
X-20801Y1304856D01*
G01X-19469Y1285946D02*
X-16213Y1285910D01*
G01X-18174Y1285931D02*
X-14677Y1285894D01*
G01X-19469Y1289096D02*
X-16213Y1289059D01*
G01X-18174Y1289081D02*
X-14677Y1289043D01*
G01X-19469Y1292245D02*
X-16213Y1292209D01*
G01X-18174Y1292231D02*
X-14677Y1292193D01*
G01X-19469Y1295395D02*
X-16213Y1295359D01*
G01X-18174Y1295380D02*
X-14677Y1295343D01*
G01X-19469Y1298544D02*
X-16213Y1298508D01*
G01X-18174Y1298530D02*
X-14677Y1298492D01*
G01X-19469Y1301694D02*
X-16213Y1301658D01*
G01X-18174Y1301680D02*
X-14677Y1301642D01*
G01X-19469Y1304844D02*
X-16213Y1304807D01*
G01X-18174Y1304829D02*
X-14677Y1304791D01*
G01X22441Y1459220D02*
Y1429693D01*
G01X12634Y1418335D02*
X12416Y1418065D01*
G01X12634Y1415185D02*
X12416Y1414915D01*
G01X12634Y1412035D02*
X12416Y1411765D01*
G01X12634Y1408886D02*
X12416Y1408616D01*
G01X12634Y1405736D02*
X12416Y1405466D01*
G01X12634Y1402587D02*
X12416Y1402317D01*
G01X12634Y1399437D02*
X12416Y1399167D01*
G01X12634Y1396287D02*
X12416Y1396017D01*
G01X12634Y1393138D02*
X12416Y1392868D01*
G01X12634Y1389988D02*
X12416Y1389718D01*
G01X12634Y1386839D02*
X12416Y1386569D01*
G01X12634Y1383689D02*
X12416Y1383419D01*
G01X12634Y1380539D02*
X12416Y1380269D01*
G01X12634Y1377390D02*
X12416Y1377120D01*
G01X12634Y1374240D02*
X12416Y1373970D01*
G01X12634Y1371091D02*
X12416Y1370820D01*
G01X12634Y1367941D02*
X12416Y1367671D01*
G01X12287Y1418335D02*
X12057Y1418079D01*
G01X12287Y1415185D02*
X12057Y1414929D01*
G01X12287Y1412035D02*
X12057Y1411780D01*
G01X12287Y1408886D02*
X12057Y1408630D01*
G01X12287Y1405736D02*
X12057Y1405480D01*
G01X12287Y1402587D02*
X12057Y1402331D01*
G01X12287Y1399437D02*
X12057Y1399181D01*
G01X12287Y1396287D02*
X12057Y1396031D01*
G01X12287Y1393138D02*
X12057Y1392882D01*
G01X12287Y1389988D02*
X12057Y1389732D01*
G01X12287Y1386839D02*
X12057Y1386583D01*
G01X12287Y1383689D02*
X12057Y1383433D01*
G01X12287Y1380539D02*
X12057Y1380283D01*
G01X12287Y1377390D02*
X12057Y1377134D01*
G01X12287Y1374240D02*
X12057Y1373984D01*
G01X12287Y1371091D02*
X12057Y1370835D01*
G01X12287Y1367941D02*
X12057Y1367685D01*
G01Y1416110D02*
Y1414929D01*
G01Y1419260D02*
Y1418079D01*
G01Y1412961D02*
Y1411780D01*
G01Y1406661D02*
Y1405480D01*
G01Y1409811D02*
Y1408630D01*
G01Y1403512D02*
Y1402331D01*
G01Y1397213D02*
Y1396031D01*
G01Y1400362D02*
Y1399181D01*
G01Y1394063D02*
Y1392882D01*
G01Y1387764D02*
Y1386583D01*
G01Y1390913D02*
Y1389732D01*
G01Y1384614D02*
Y1383433D01*
G01Y1378315D02*
Y1377134D01*
G01Y1381465D02*
Y1380283D01*
G01Y1375165D02*
Y1373984D01*
G01Y1368866D02*
Y1367685D01*
G01Y1372016D02*
Y1370835D01*
G01X12410Y1416110D02*
Y1414929D01*
G01Y1419260D02*
Y1418079D01*
G01Y1412961D02*
Y1411780D01*
G01Y1406661D02*
Y1405480D01*
G01Y1409811D02*
Y1408630D01*
G01Y1403512D02*
Y1402331D01*
G01Y1397213D02*
Y1396031D01*
G01Y1400362D02*
Y1399181D01*
G01Y1394063D02*
Y1392882D01*
G01Y1387764D02*
Y1386583D01*
G01Y1390913D02*
Y1389732D01*
G01Y1384614D02*
Y1383433D01*
G01Y1378315D02*
Y1377134D01*
G01Y1381465D02*
Y1380283D01*
G01Y1375165D02*
Y1373984D01*
G01Y1368866D02*
Y1367685D01*
G01Y1372016D02*
Y1370835D01*
G01X13353Y1415854D02*
Y1415185D01*
G01Y1419004D02*
Y1418335D01*
G01Y1412705D02*
Y1412035D01*
G01Y1406406D02*
Y1405736D01*
G01Y1409555D02*
Y1408886D01*
G01Y1403256D02*
Y1402587D01*
G01Y1396957D02*
Y1396287D01*
G01Y1400106D02*
Y1399437D01*
G01Y1393807D02*
Y1393138D01*
G01Y1387508D02*
Y1386839D01*
G01Y1390657D02*
Y1389988D01*
G01Y1384358D02*
Y1383689D01*
G01Y1378059D02*
Y1377390D01*
G01Y1381209D02*
Y1380539D01*
G01Y1374909D02*
Y1374240D01*
G01Y1368610D02*
Y1367941D01*
G01Y1371760D02*
Y1371091D01*
G01X13701Y1415854D02*
Y1415185D01*
G01Y1419004D02*
Y1418335D01*
G01Y1412705D02*
Y1412035D01*
G01Y1406406D02*
Y1405736D01*
G01Y1409555D02*
Y1408886D01*
G01Y1403256D02*
Y1402587D01*
G01Y1396957D02*
Y1396287D01*
G01Y1400106D02*
Y1399437D01*
G01Y1393807D02*
Y1393138D01*
G01Y1387508D02*
Y1386839D01*
G01Y1390657D02*
Y1389988D01*
G01Y1384358D02*
Y1383689D01*
G01Y1378059D02*
Y1377390D01*
G01Y1381209D02*
Y1380539D01*
G01Y1374909D02*
Y1374240D01*
G01Y1368610D02*
Y1367941D01*
G01Y1371760D02*
Y1371091D01*
G01X12416Y1365731D02*
X12634Y1365461D01*
G01X12416Y1368880D02*
X12634Y1368610D01*
G01X12416Y1372030D02*
X12634Y1371760D01*
G01X12416Y1375180D02*
X12634Y1374909D01*
G01X12416Y1378329D02*
X12634Y1378059D01*
G01X12416Y1381479D02*
X12634Y1381209D01*
G01X12057Y1365717D02*
X12287Y1365461D01*
G01X12057Y1368866D02*
X12287Y1368610D01*
G01X12057Y1372016D02*
X12287Y1371760D01*
G01X12057Y1375165D02*
X12287Y1374909D01*
G01X12057Y1378315D02*
X12287Y1378059D01*
G01X12057Y1381465D02*
X12287Y1381209D01*
G01X12057Y1384614D02*
X12287Y1384358D01*
G01X12057Y1387764D02*
X12287Y1387508D01*
G01X12057Y1390913D02*
X12287Y1390657D01*
G01X12057Y1394063D02*
X12287Y1393807D01*
G01X12057Y1397213D02*
X12287Y1396957D01*
G01X12057Y1400362D02*
X12287Y1400106D01*
G01X12057Y1403512D02*
X12287Y1403256D01*
G01X12057Y1406661D02*
X12287Y1406406D01*
G01X12057Y1409811D02*
X12287Y1409555D01*
G01X12057Y1412961D02*
X12287Y1412705D01*
G01X12057Y1416110D02*
X12287Y1415854D01*
G01X12057Y1419260D02*
X12287Y1419004D01*
G01X12416Y1384628D02*
X12634Y1384358D01*
G01X12416Y1387778D02*
X12634Y1387508D01*
G01X12416Y1390928D02*
X12634Y1390657D01*
G01X12416Y1394077D02*
X12634Y1393807D01*
G01X12416Y1397227D02*
X12634Y1396957D01*
G01X12416Y1400376D02*
X12634Y1400106D01*
G01X12416Y1403526D02*
X12634Y1403256D01*
G01X12416Y1406676D02*
X12634Y1406406D01*
G01X12416Y1409825D02*
X12634Y1409555D01*
G01X12416Y1412975D02*
X12634Y1412705D01*
G01X12416Y1416124D02*
X12634Y1415854D01*
G01X12416Y1419274D02*
X12634Y1419004D01*
G01X13701Y1365461D02*
X12287D01*
G01X13701Y1367941D02*
X12287D01*
G01X13701Y1368610D02*
X12287D01*
G01X13701Y1371091D02*
X12287D01*
G01X13701Y1371760D02*
X12287D01*
G01X13701Y1374240D02*
X12287D01*
G01X13701Y1374909D02*
X12287D01*
G01X13701Y1377390D02*
X12287D01*
G01X13701Y1378059D02*
X12287D01*
G01X13701Y1380539D02*
X12287D01*
G01X13701Y1381209D02*
X12287D01*
G01X13701Y1383689D02*
X12287D01*
G01X13701Y1384358D02*
X12287D01*
G01X13701Y1386839D02*
X12287D01*
G01X13701Y1387508D02*
X12287D01*
G01X13701Y1389988D02*
X12287D01*
G01X13701Y1390657D02*
X12287D01*
G01X13701Y1393138D02*
X12287D01*
G01X13701Y1393807D02*
X12287D01*
G01X13701Y1396287D02*
X12287D01*
G01X13701Y1396957D02*
X12287D01*
G01X13701Y1399437D02*
X12287D01*
G01X13701Y1400106D02*
X12287D01*
G01X13701Y1402587D02*
X12287D01*
G01X13701Y1403256D02*
X12287D01*
G01X13701Y1405736D02*
X12287D01*
G01X13701Y1406406D02*
X12287D01*
G01X13701Y1408886D02*
X12287D01*
G01X13701Y1409555D02*
X12287D01*
G01X13701Y1412035D02*
X12287D01*
G01X13701Y1412705D02*
X12287D01*
G01X13701Y1415185D02*
X12287D01*
G01X13701Y1415854D02*
X12287D01*
G01X13701Y1418335D02*
X12287D01*
G01X13701Y1419004D02*
X12287D01*
G01X12634Y1364791D02*
X12416Y1364521D01*
G01X12634Y1361642D02*
X12416Y1361372D01*
G01X12634Y1358492D02*
X12416Y1358222D01*
G01X12287Y1364791D02*
X12057Y1364535D01*
G01X12287Y1361642D02*
X12057Y1361386D01*
G01X12287Y1358492D02*
X12057Y1358236D01*
G01Y1365717D02*
Y1364535D01*
G01Y1359417D02*
Y1358236D01*
G01Y1362567D02*
Y1361386D01*
G01X12410Y1365717D02*
Y1364535D01*
G01Y1359417D02*
Y1358236D01*
G01Y1362567D02*
Y1361386D01*
G01X13353Y1365461D02*
Y1364791D01*
G01Y1359161D02*
Y1358492D01*
G01Y1362311D02*
Y1361642D01*
G01X13701Y1365461D02*
Y1364791D01*
G01Y1359161D02*
Y1358492D01*
G01Y1362311D02*
Y1361642D01*
G01X12416Y1359431D02*
X12634Y1359161D01*
G01X12416Y1362581D02*
X12634Y1362311D01*
G01X12057Y1359417D02*
X12287Y1359161D01*
G01X12057Y1362567D02*
X12287Y1362311D01*
G01X13701Y1358492D02*
X12287D01*
G01X13701Y1359161D02*
X12287D01*
G01X13701Y1361642D02*
X12287D01*
G01X13701Y1362311D02*
X12287D01*
G01X13701Y1364791D02*
X12287D01*
G01X35827Y1395138D02*
X40551Y1399783D01*
G01X40547Y1398676D02*
X35827Y1394034D01*
G01Y1393406D02*
Y1395138D01*
G01X39236Y1391437D02*
X35827Y1393406D01*
G01X3937Y1429693D02*
X0Y1425756D01*
G01X22441Y1429693D02*
X3937D01*
G01X-20942Y1409647D02*
X-21109Y1408991D01*
G01X-20272Y1409319D02*
X-20439Y1408663D01*
G01X-20272Y1402757D02*
X-20439Y1402101D01*
G01X-16418Y1408006D02*
X-16586Y1407350D01*
G01X-20272Y1390290D02*
X-20439Y1389634D01*
G01X-15748Y1407678D02*
X-15916Y1407022D01*
G01X-20942Y1384713D02*
X-21109Y1384056D01*
G01X-16418Y1395867D02*
X-16586Y1395211D01*
G01Y1383072D02*
X-16754Y1382416D01*
G01X-15748Y1383072D02*
X-15916Y1382416D01*
G01X-20942Y1403249D02*
X-21109Y1402757D01*
G01X-20942Y1390782D02*
X-21109Y1390290D01*
G01X-15916Y1395047D02*
X-16083Y1394555D01*
G01X-20942Y1378807D02*
X-21109Y1378315D01*
G01X-20942Y1376182D02*
X-21109Y1375690D01*
G01X-20774Y1409975D02*
X-20942Y1409647D01*
G01X-20104Y1403085D02*
X-20272Y1402757D01*
G01X-15916Y1407022D02*
X-16083Y1406694D01*
G01X-20104Y1390618D02*
X-20272Y1390290D01*
G01X-16586Y1395211D02*
X-16754Y1394883D01*
G01X-19937Y1384713D02*
X-20272Y1384056D01*
G01Y1378315D02*
X-20439Y1377987D01*
G01X-20272Y1375690D02*
X-20439Y1375362D01*
G01X-15916Y1382416D02*
X-16083Y1382088D01*
G01X-20439Y1397836D02*
X-20942Y1397016D01*
G01X-20607Y1403741D02*
X-20942Y1403249D01*
G01X-19937Y1397344D02*
X-20272Y1396852D01*
G01X-20607Y1391274D02*
X-20942Y1390782D01*
G01X-16083Y1394555D02*
X-16418Y1394063D01*
G01X-20607Y1385205D02*
X-20942Y1384713D01*
G01X-16754Y1382416D02*
X-17089Y1381924D01*
G01X-20439Y1410303D02*
X-20774Y1409975D01*
G01X-19937Y1409647D02*
X-20272Y1409319D01*
G01Y1404069D02*
X-20607Y1403741D01*
G01X-16586Y1407350D02*
X-16921Y1407022D01*
G01X-19769Y1403413D02*
X-20104Y1403085D01*
G01X-16083Y1406694D02*
X-16418Y1406366D01*
G01X-20272Y1391602D02*
X-20607Y1391274D01*
G01X-16754Y1394883D02*
X-17256Y1394391D01*
G01X-19769Y1390946D02*
X-20104Y1390618D01*
G01X-16418Y1394063D02*
X-16754Y1393735D01*
G01X-20104Y1385697D02*
X-20607Y1385205D01*
G01Y1379135D02*
X-20942Y1378807D01*
G01X-20104Y1378479D02*
X-20272Y1378315D01*
G01X-16083Y1382088D02*
X-16418Y1381760D01*
G01X-20439Y1376674D02*
X-20942Y1376182D01*
G01X-20104Y1375854D02*
X-20272Y1375690D01*
G01X-19769Y1398328D02*
X-20439Y1397836D01*
G01X-19937Y1410631D02*
X-20439Y1410303D01*
G01X-19434Y1409975D02*
X-19937Y1409647D01*
G01X-16921Y1407022D02*
X-17424Y1406694D01*
G01X-16418Y1406366D02*
X-16921Y1406038D01*
G01X-19434Y1397672D02*
X-19937Y1397344D01*
G01X-19434Y1385041D02*
X-19937Y1384713D01*
G01X-17089Y1381924D02*
X-17591Y1381596D01*
G01X-14537Y1419249D02*
X-14677Y1419161D01*
G01X-13977Y1419457D02*
X-14449Y1419161D01*
G01X-14537Y1416100D02*
X-14677Y1416012D01*
G01X-13977Y1416307D02*
X-14449Y1416012D01*
G01X-14537Y1412950D02*
X-14677Y1412862D01*
G01X-13977Y1413157D02*
X-14449Y1412862D01*
G01X-14537Y1409800D02*
X-14677Y1409713D01*
G01X-13977Y1410008D02*
X-14449Y1409713D01*
G01X-14537Y1406651D02*
X-14677Y1406563D01*
G01X-13977Y1406858D02*
X-14449Y1406563D01*
G01X-14537Y1403501D02*
X-14677Y1403413D01*
G01X-13977Y1403709D02*
X-14449Y1403413D01*
G01X-14537Y1400352D02*
X-14677Y1400264D01*
G01X-13977Y1400559D02*
X-14449Y1400264D01*
G01X-14537Y1397202D02*
X-14677Y1397114D01*
G01X-13977Y1397409D02*
X-14449Y1397114D01*
G01X-14537Y1394052D02*
X-14677Y1393965D01*
G01X-13977Y1394260D02*
X-14449Y1393965D01*
G01X-14537Y1390903D02*
X-14677Y1390815D01*
G01X-13977Y1391110D02*
X-14449Y1390815D01*
G01X-14537Y1387753D02*
X-14677Y1387665D01*
G01X-13977Y1387961D02*
X-14449Y1387665D01*
G01X-14537Y1384604D02*
X-14677Y1384516D01*
G01X-13977Y1384811D02*
X-14449Y1384516D01*
G01X-14537Y1381454D02*
X-14677Y1381366D01*
G01X-13977Y1381661D02*
X-14449Y1381366D01*
G01X-14537Y1378304D02*
X-14677Y1378217D01*
G01X-14147Y1419457D02*
X-14537Y1419249D01*
G01X-14147Y1416307D02*
X-14537Y1416100D01*
G01X-14147Y1413157D02*
X-14537Y1412950D01*
G01X-14147Y1410008D02*
X-14537Y1409800D01*
G01X-14147Y1406858D02*
X-14537Y1406651D01*
G01X-14147Y1403709D02*
X-14537Y1403501D01*
G01X-14147Y1400559D02*
X-14537Y1400352D01*
G01X-30709Y1429693D02*
Y1424575D01*
G01X-23622Y1413092D02*
Y1412272D01*
G01Y1388157D02*
Y1387337D01*
G01Y1369457D02*
Y1368144D01*
G01X-21109Y1408991D02*
Y1407678D01*
G01Y1402757D02*
Y1402101D01*
G01Y1400624D02*
Y1399804D01*
G01Y1390290D02*
Y1389634D01*
G01Y1384056D02*
Y1383072D01*
G01Y1378315D02*
Y1377659D01*
G01Y1381596D02*
Y1380776D01*
G01Y1375690D02*
Y1375034D01*
G01Y1374214D02*
Y1373394D01*
G01X-20801Y1415948D02*
Y1415092D01*
G01Y1419097D02*
Y1418241D01*
G01Y1412798D02*
Y1411942D01*
G01Y1406499D02*
Y1405643D01*
G01Y1409648D02*
Y1408793D01*
G01Y1403349D02*
Y1402493D01*
G01Y1397050D02*
Y1396194D01*
G01Y1400200D02*
Y1399344D01*
G01Y1393900D02*
Y1393044D01*
G01Y1387601D02*
Y1386745D01*
G01Y1390751D02*
Y1389895D01*
G01Y1384452D02*
Y1383596D01*
G01Y1378152D02*
Y1377296D01*
G01Y1381302D02*
Y1380446D01*
G01Y1375003D02*
Y1374147D01*
G01Y1368704D02*
Y1367848D01*
G01Y1371853D02*
Y1370997D01*
G01X-20439Y1408663D02*
Y1408006D01*
G01Y1377987D02*
Y1377494D01*
G01Y1375362D02*
Y1375034D01*
G01X-20272Y1384056D02*
Y1383072D01*
G01X-19469Y1415954D02*
Y1415086D01*
G01Y1419103D02*
Y1418235D01*
G01Y1412804D02*
Y1411936D01*
G01Y1406505D02*
Y1405637D01*
G01Y1409654D02*
Y1408787D01*
G01Y1403355D02*
Y1402487D01*
G01Y1397056D02*
Y1396188D01*
G01Y1400206D02*
Y1399338D01*
G01Y1393906D02*
Y1393039D01*
G01Y1387607D02*
Y1386739D01*
G01Y1390757D02*
Y1389889D01*
G01Y1384457D02*
Y1383590D01*
G01Y1378158D02*
Y1377291D01*
G01Y1381308D02*
Y1380440D01*
G01Y1375009D02*
Y1374141D01*
G01Y1368709D02*
Y1367842D01*
G01Y1371859D02*
Y1370991D01*
G01X-19099Y1397672D02*
Y1394227D01*
G01X-18435Y1415974D02*
Y1415065D01*
G01Y1419123D02*
Y1418215D01*
G01Y1412824D02*
Y1411916D01*
G01Y1406525D02*
Y1405617D01*
G01Y1409674D02*
Y1408766D01*
G01Y1403375D02*
Y1402467D01*
G01Y1397076D02*
Y1396168D01*
G01Y1400226D02*
Y1399317D01*
G01Y1393926D02*
Y1393018D01*
G01Y1387627D02*
Y1386719D01*
G01Y1390777D02*
Y1389869D01*
G01Y1384478D02*
Y1383569D01*
G01Y1378178D02*
Y1377270D01*
G01Y1381328D02*
Y1380420D01*
G01Y1375029D02*
Y1374120D01*
G01Y1368730D02*
Y1367821D01*
G01Y1371879D02*
Y1370971D01*
G01X-18429Y1398492D02*
Y1394063D01*
G01Y1370277D02*
Y1367324D01*
G01X-18174Y1415974D02*
Y1415065D01*
G01Y1419123D02*
Y1418215D01*
G01Y1412824D02*
Y1411916D01*
G01Y1406525D02*
Y1405617D01*
G01Y1409674D02*
Y1408766D01*
G01Y1403375D02*
Y1402467D01*
G01Y1397076D02*
Y1396168D01*
G01Y1400226D02*
Y1399317D01*
G01Y1393926D02*
Y1393018D01*
G01Y1387627D02*
Y1386719D01*
G01Y1390777D02*
Y1389869D01*
G01Y1384478D02*
Y1383569D01*
G01Y1378178D02*
Y1377270D01*
G01Y1381328D02*
Y1380420D01*
G01Y1375029D02*
Y1374120D01*
G01Y1368730D02*
Y1367821D01*
G01Y1371879D02*
Y1370971D01*
G01X-17759Y1370441D02*
Y1367160D01*
G01X-17424Y1398492D02*
Y1397672D01*
G01X-16586Y1383728D02*
Y1383072D01*
G01X-16418Y1408663D02*
Y1408006D01*
G01X-16213Y1415995D02*
Y1415044D01*
G01Y1419145D02*
Y1418193D01*
G01Y1412846D02*
Y1411894D01*
G01Y1406546D02*
Y1405595D01*
G01Y1409696D02*
Y1408744D01*
G01Y1403397D02*
Y1402445D01*
G01Y1397098D02*
Y1396146D01*
G01Y1400247D02*
Y1399296D01*
G01Y1393948D02*
Y1392996D01*
G01Y1387649D02*
Y1386697D01*
G01Y1390798D02*
Y1389847D01*
G01Y1384499D02*
Y1383548D01*
G01Y1378200D02*
Y1377248D01*
G01Y1381350D02*
Y1380398D01*
G01Y1375050D02*
Y1374099D01*
G01Y1368751D02*
Y1367800D01*
G01Y1371901D02*
Y1370949D01*
G01X-15985Y1415995D02*
Y1415044D01*
G01Y1419145D02*
Y1418193D01*
G01Y1412846D02*
Y1411894D01*
G01Y1406546D02*
Y1405595D01*
G01Y1409696D02*
Y1408744D01*
G01Y1403397D02*
Y1402445D01*
G01Y1397098D02*
Y1396146D01*
G01Y1400247D02*
Y1399296D01*
G01Y1393948D02*
Y1392996D01*
G01Y1387649D02*
Y1386697D01*
G01Y1390798D02*
Y1389847D01*
G01Y1384499D02*
Y1383548D01*
G01Y1378200D02*
Y1377248D01*
G01Y1381350D02*
Y1380398D01*
G01Y1375050D02*
Y1374099D01*
G01Y1368751D02*
Y1367800D01*
G01Y1371901D02*
Y1370949D01*
G01X-15748Y1413092D02*
Y1412272D01*
G01Y1408991D02*
Y1407678D01*
G01Y1404398D02*
Y1403577D01*
G01Y1400624D02*
Y1399804D01*
G01Y1391930D02*
Y1391110D01*
G01Y1388157D02*
Y1387337D01*
G01Y1384056D02*
Y1383072D01*
G01Y1379463D02*
Y1378643D01*
G01Y1374214D02*
Y1373394D01*
G01Y1376839D02*
Y1376018D01*
G01Y1372081D02*
Y1371097D01*
G01Y1366504D02*
Y1365520D01*
G01X-20942Y1397016D02*
X-21109Y1396031D01*
G01X-20272Y1396852D02*
X-20439Y1395867D01*
G01X-15748Y1396031D02*
X-15916Y1395047D01*
G01X-13977Y1378512D02*
X-14449Y1378217D01*
G01X-14537Y1375155D02*
X-14677Y1375067D01*
G01X-13977Y1375362D02*
X-14449Y1375067D01*
G01X-14537Y1372005D02*
X-14677Y1371917D01*
G01X-13977Y1372213D02*
X-14449Y1371917D01*
G01X-14537Y1368856D02*
X-14677Y1368768D01*
G01X-13977Y1369063D02*
X-14449Y1368768D01*
G01X-14537Y1365706D02*
X-14677Y1365618D01*
G01X-13977Y1365913D02*
X-14449Y1365618D01*
G01X-14147Y1397409D02*
X-14537Y1397202D01*
G01X-14147Y1394260D02*
X-14537Y1394052D01*
G01X-14147Y1391110D02*
X-14537Y1390903D01*
G01X-14147Y1387961D02*
X-14537Y1387753D01*
G01X-14147Y1384811D02*
X-14537Y1384604D01*
G01X-14147Y1381661D02*
X-14537Y1381454D01*
G01X-14147Y1378512D02*
X-14537Y1378304D01*
G01X-14147Y1375362D02*
X-14537Y1375155D01*
G01X-14147Y1372213D02*
X-14537Y1372005D01*
G01X-14147Y1369063D02*
X-14537Y1368856D01*
G01X-14147Y1365913D02*
X-14537Y1365706D01*
G01X-17256Y1394391D02*
X-17591Y1394227D01*
G01X-16754Y1393735D02*
X-17424Y1393407D01*
G01X-19937Y1391766D02*
X-20272Y1391602D01*
G01X-19769Y1385861D02*
X-20104Y1385697D01*
G01X-16418Y1381760D02*
X-16754Y1381596D01*
G01X-19769Y1378643D02*
X-20104Y1378479D01*
G01X-19769Y1376018D02*
X-20104Y1375854D01*
G01X-19769Y1379463D02*
X-20607Y1379135D01*
G01X-19434Y1410795D02*
X-19937Y1410631D01*
G01X-19769Y1404233D02*
X-20272Y1404069D01*
G01X-17591Y1394227D02*
X-18094Y1394063D01*
G01X-18931Y1385205D02*
X-19434Y1385041D01*
G01X-14537Y1416100D02*
Y1414940D01*
G01Y1419249D02*
Y1418089D01*
G01Y1412950D02*
Y1411790D01*
G01Y1406651D02*
Y1405491D01*
G01Y1409800D02*
Y1408641D01*
G01Y1403501D02*
Y1402341D01*
G01Y1397202D02*
Y1396042D01*
G01Y1400352D02*
Y1399192D01*
G01Y1394052D02*
Y1392893D01*
G01Y1387753D02*
Y1386593D01*
G01Y1390903D02*
Y1389743D01*
G01Y1384604D02*
Y1383444D01*
G01Y1378304D02*
Y1377144D01*
G01Y1381454D02*
Y1380294D01*
G01Y1375155D02*
Y1373995D01*
G01Y1368856D02*
Y1367696D01*
G01Y1372005D02*
Y1370845D01*
G01X-13068Y1381596D02*
Y1380776D01*
G01X-13009Y1419457D02*
Y1417882D01*
G01Y1416307D02*
Y1414732D01*
G01Y1413157D02*
Y1411583D01*
G01Y1406858D02*
Y1405283D01*
G01Y1410008D02*
Y1408433D01*
G01Y1403709D02*
Y1402134D01*
G01Y1397409D02*
Y1395835D01*
G01Y1400559D02*
Y1398984D01*
G01Y1394260D02*
Y1392685D01*
G01Y1387961D02*
Y1386386D01*
G01Y1391110D02*
Y1389535D01*
G01Y1384811D02*
Y1383236D01*
G01Y1378512D02*
Y1376937D01*
G01Y1381661D02*
Y1380087D01*
G01Y1375362D02*
Y1373787D01*
G01Y1369063D02*
Y1367488D01*
G01Y1372213D02*
Y1370638D01*
G01X315Y1419850D02*
Y1419260D01*
G01Y1416701D02*
Y1416110D01*
G01Y1414929D02*
Y1414339D01*
G01Y1418079D02*
Y1417488D01*
G01Y1410402D02*
Y1409811D01*
G01Y1413551D02*
Y1412961D01*
G01Y1411780D02*
Y1411189D01*
G01Y1407252D02*
Y1406661D01*
G01Y1405480D02*
Y1404890D01*
G01Y1408630D02*
Y1408039D01*
G01Y1400953D02*
Y1400362D01*
G01Y1404102D02*
Y1403512D01*
G01Y1402331D02*
Y1401740D01*
G01Y1397803D02*
Y1397213D01*
G01Y1396031D02*
Y1395441D01*
G01Y1399181D02*
Y1398591D01*
G01Y1391504D02*
Y1390913D01*
G01Y1394654D02*
Y1394063D01*
G01Y1392882D02*
Y1392291D01*
G01Y1388354D02*
Y1387764D01*
G01Y1389732D02*
Y1389142D01*
G01Y1382055D02*
Y1381465D01*
G01Y1385205D02*
Y1384614D01*
G01Y1383433D02*
Y1382843D01*
G01Y1386583D02*
Y1385992D01*
G01Y1378906D02*
Y1378315D01*
G01Y1380283D02*
Y1379693D01*
G01Y1372606D02*
Y1372016D01*
G01Y1375756D02*
Y1375165D01*
G01Y1373984D02*
Y1373394D01*
G01Y1377134D02*
Y1376543D01*
G01Y1369457D02*
Y1368866D01*
G01Y1370835D02*
Y1370244D01*
G01Y1366307D02*
Y1365717D01*
G01Y1367685D02*
Y1367094D01*
G01X512Y1419850D02*
Y1419260D01*
G01Y1416701D02*
Y1416110D01*
G01Y1414929D02*
Y1414339D01*
G01Y1418079D02*
Y1417488D01*
G01Y1410402D02*
Y1409811D01*
G01Y1413551D02*
Y1412961D01*
G01Y1411780D02*
Y1411189D01*
G01Y1407252D02*
Y1406661D01*
G01Y1405480D02*
Y1404890D01*
G01Y1408630D02*
Y1408039D01*
G01Y1400953D02*
Y1400362D01*
G01Y1404102D02*
Y1403512D01*
G01Y1402331D02*
Y1401740D01*
G01Y1397803D02*
Y1397213D01*
G01Y1396031D02*
Y1395441D01*
G01Y1399181D02*
Y1398591D01*
G01Y1391504D02*
Y1390913D01*
G01Y1394654D02*
Y1394063D01*
G01Y1392882D02*
Y1392291D01*
G01Y1388354D02*
Y1387764D01*
G01Y1389732D02*
Y1389142D01*
G01Y1382055D02*
Y1381465D01*
G01Y1385205D02*
Y1384614D01*
G01Y1383433D02*
Y1382843D01*
G01Y1386583D02*
Y1385992D01*
G01Y1378906D02*
Y1378315D01*
G01Y1380283D02*
Y1379693D01*
G01Y1372606D02*
Y1372016D01*
G01Y1375756D02*
Y1375165D01*
G01Y1373984D02*
Y1373394D01*
G01Y1377134D02*
Y1376543D01*
G01Y1369457D02*
Y1368866D01*
G01Y1370835D02*
Y1370244D01*
G01Y1366307D02*
Y1365717D01*
G01Y1367685D02*
Y1367094D01*
G01X709Y1416110D02*
Y1414929D01*
G01Y1419260D02*
Y1418079D01*
G01Y1412961D02*
Y1411780D01*
G01Y1406661D02*
Y1405480D01*
G01Y1409811D02*
Y1408630D01*
G01Y1403512D02*
Y1402331D01*
G01Y1397213D02*
Y1396031D01*
G01Y1400362D02*
Y1399181D01*
G01Y1394063D02*
Y1392882D01*
G01Y1387764D02*
Y1386583D01*
G01Y1390913D02*
Y1389732D01*
G01Y1384614D02*
Y1383433D01*
G01Y1378315D02*
Y1377134D01*
G01Y1381465D02*
Y1380283D01*
G01Y1375165D02*
Y1373984D01*
G01Y1368866D02*
Y1367685D01*
G01Y1372016D02*
Y1370835D01*
G01X1074Y1416110D02*
Y1414929D01*
G01Y1419260D02*
Y1418079D01*
G01Y1412961D02*
Y1411780D01*
G01Y1406661D02*
Y1405480D01*
G01Y1409811D02*
Y1408630D01*
G01Y1403512D02*
Y1402331D01*
G01Y1397213D02*
Y1396031D01*
G01Y1400362D02*
Y1399181D01*
G01Y1394063D02*
Y1392882D01*
G01Y1387764D02*
Y1386583D01*
G01Y1390913D02*
Y1389732D01*
G01Y1384614D02*
Y1383433D01*
G01Y1378315D02*
Y1377134D01*
G01Y1381465D02*
Y1380283D01*
G01Y1375165D02*
Y1373984D01*
G01Y1368866D02*
Y1367685D01*
G01Y1372016D02*
Y1370835D01*
G01X1184Y1416110D02*
Y1414929D01*
G01Y1419260D02*
Y1418079D01*
G01Y1412961D02*
Y1411780D01*
G01Y1406661D02*
Y1405480D01*
G01Y1409811D02*
Y1408630D01*
G01Y1403512D02*
Y1402331D01*
G01Y1397213D02*
Y1396031D01*
G01Y1400362D02*
Y1399181D01*
G01Y1394063D02*
Y1392882D01*
G01Y1387764D02*
Y1386583D01*
G01Y1390913D02*
Y1389732D01*
G01Y1384614D02*
Y1383433D01*
G01Y1378315D02*
Y1377134D01*
G01Y1381465D02*
Y1380283D01*
G01Y1375165D02*
Y1373984D01*
G01Y1368866D02*
Y1367685D01*
G01Y1372016D02*
Y1370835D01*
G01X9965Y1416110D02*
Y1414929D01*
G01Y1419260D02*
Y1418079D01*
G01Y1412961D02*
Y1411780D01*
G01Y1406661D02*
Y1405480D01*
G01Y1409811D02*
Y1408630D01*
G01Y1403512D02*
Y1402331D01*
G01Y1397213D02*
Y1396031D01*
G01Y1400362D02*
Y1399181D01*
G01Y1394063D02*
Y1392882D01*
G01Y1387764D02*
Y1386583D01*
G01Y1390913D02*
Y1389732D01*
G01Y1384614D02*
Y1383433D01*
G01Y1378315D02*
Y1377134D01*
G01Y1381465D02*
Y1380283D01*
G01Y1375165D02*
Y1373984D01*
G01Y1368866D02*
Y1367685D01*
G01Y1372016D02*
Y1370835D01*
G01X10075Y1416110D02*
Y1414929D01*
G01Y1419260D02*
Y1418079D01*
G01Y1412961D02*
Y1411780D01*
G01Y1406661D02*
Y1405480D01*
G01Y1409811D02*
Y1408630D01*
G01Y1403512D02*
Y1402331D01*
G01Y1397213D02*
Y1396031D01*
G01Y1400362D02*
Y1399181D01*
G01Y1394063D02*
Y1392882D01*
G01Y1387764D02*
Y1386583D01*
G01Y1390913D02*
Y1389732D01*
G01Y1384614D02*
Y1383433D01*
G01Y1378315D02*
Y1377134D01*
G01Y1381465D02*
Y1380283D01*
G01Y1375165D02*
Y1373984D01*
G01Y1368866D02*
Y1367685D01*
G01Y1372016D02*
Y1370835D01*
G01X-15748Y1372081D02*
X-23622Y1369457D01*
G01X-18429Y1370277D02*
X-22952Y1368800D01*
G01X-15748Y1371097D02*
X-17759Y1370441D01*
G01X-21109Y1396031D02*
X-20942Y1395047D01*
G01X-16586Y1397016D02*
X-16418Y1395867D01*
G01X-15916Y1397180D02*
X-15748Y1396031D01*
G01X-21109Y1375034D02*
X-20942Y1374542D01*
G01X-20439Y1375034D02*
X-20272Y1374542D01*
G01X-21109Y1377659D02*
X-20942Y1377167D01*
G01Y1395047D02*
X-20774Y1394555D01*
G01X-21109Y1383072D02*
X-20942Y1382416D01*
G01X-20272Y1383072D02*
X-20104Y1382416D01*
G01X-21109Y1389634D02*
X-20942Y1388978D01*
G01X-20439Y1389634D02*
X-20272Y1388978D01*
G01X-20439Y1395867D02*
X-20272Y1395211D01*
G01X-16754Y1384384D02*
X-16586Y1383728D01*
G01X-21109Y1402101D02*
X-20942Y1401445D01*
G01X-20439Y1402101D02*
X-20272Y1401445D01*
G01X-15916Y1384713D02*
X-15748Y1384056D01*
G01X-21109Y1407678D02*
X-20942Y1407022D01*
G01X-20439Y1408006D02*
X-20272Y1407350D01*
G01X-16586Y1409319D02*
X-16418Y1408663D01*
G01X-15916Y1409647D02*
X-15748Y1408991D01*
G01X-20439Y1377494D02*
X-20272Y1377167D01*
G01X-20942Y1382416D02*
X-20774Y1382088D01*
G01X-20104Y1382416D02*
X-19769Y1381924D01*
G01X-20272Y1395211D02*
X-20104Y1394883D01*
G01X-20942Y1407022D02*
X-20774Y1406694D01*
G01X-16251Y1397836D02*
X-15916Y1397180D01*
G01X-16083Y1409975D02*
X-15916Y1409647D01*
G01X-20942Y1388978D02*
X-20607Y1388485D01*
G01X-20272Y1388978D02*
X-19937Y1388485D01*
G01X-17089Y1384876D02*
X-16754Y1384384D01*
G01X-16251Y1385205D02*
X-15916Y1384713D01*
G01X-20774Y1394555D02*
X-20439Y1394063D01*
G01X-20942Y1401445D02*
X-20607Y1400953D01*
G01X-20272Y1401445D02*
X-19937Y1400953D01*
G01X-16921Y1397508D02*
X-16586Y1397016D01*
G01X-20942Y1374542D02*
X-20607Y1374214D01*
G01X-20272Y1374542D02*
X-19937Y1374214D01*
G01X-20942Y1377167D02*
X-20439Y1376674D01*
G01X-20272Y1377167D02*
X-20104Y1377002D01*
G01X-20774Y1382088D02*
X-20439Y1381760D01*
G01X-20607Y1388485D02*
X-20272Y1388157D01*
G01X-19937Y1388485D02*
X-19602Y1388157D01*
G01X-20439Y1394063D02*
X-20104Y1393735D01*
G01Y1394883D02*
X-19602Y1394391D01*
G01X-20607Y1400953D02*
X-20272Y1400624D01*
G01X-19937Y1400953D02*
X-19602Y1400624D01*
G01X-16754Y1398328D02*
X-16251Y1397836D01*
G01X-20774Y1406694D02*
X-20439Y1406366D01*
G01X-20272Y1407350D02*
X-19937Y1407022D01*
G01X-16921Y1409647D02*
X-16586Y1409319D01*
G01X-16418Y1410303D02*
X-16083Y1409975D01*
G01X-17089Y1385861D02*
X-16251Y1385205D01*
G01X-14537Y1367696D02*
X-14147Y1367488D01*
G01X-14537Y1370845D02*
X-14147Y1370638D01*
G01X-14537Y1373995D02*
X-14147Y1373787D01*
G01X-14677Y1367783D02*
X-14537Y1367696D01*
G01X-14449Y1367783D02*
X-13977Y1367488D01*
G01X-14677Y1370933D02*
X-14537Y1370845D01*
G01X-14449Y1370933D02*
X-13977Y1370638D01*
G01X-14677Y1374083D02*
X-14537Y1373995D01*
G01X-14449Y1374083D02*
X-13977Y1373787D01*
G01X-14677Y1377232D02*
X-14537Y1377144D01*
G01X-14449Y1377232D02*
X-13977Y1376937D01*
G01X-14677Y1380382D02*
X-14537Y1380294D01*
G01X-14449Y1380382D02*
X-13977Y1380087D01*
G01X-14677Y1383531D02*
X-14537Y1383444D01*
G01X-14449Y1383531D02*
X-13977Y1383236D01*
G01X-14677Y1386681D02*
X-14537Y1386593D01*
G01X-14449Y1386681D02*
X-13977Y1386386D01*
G01X-14677Y1389831D02*
X-14537Y1389743D01*
G01X-14449Y1389831D02*
X-13977Y1389535D01*
G01X-14677Y1392980D02*
X-14537Y1392893D01*
G01X-14449Y1392980D02*
X-13977Y1392685D01*
G01X-14677Y1396130D02*
X-14537Y1396042D01*
G01X-14449Y1396130D02*
X-13977Y1395835D01*
G01X-14677Y1399280D02*
X-14537Y1399192D01*
G01X-14449Y1399280D02*
X-13977Y1398984D01*
G01X-14677Y1402429D02*
X-14537Y1402341D01*
G01X-14449Y1402429D02*
X-13977Y1402134D01*
G01X-14677Y1405579D02*
X-14537Y1405491D01*
G01X-14449Y1405579D02*
X-13977Y1405283D01*
G01X-14677Y1408728D02*
X-14537Y1408641D01*
G01X-14449Y1408728D02*
X-13977Y1408433D01*
G01X-14677Y1411878D02*
X-14537Y1411790D01*
G01X-14449Y1411878D02*
X-13977Y1411583D01*
G01X-14677Y1415028D02*
X-14537Y1414940D01*
G01X-14449Y1415028D02*
X-13977Y1414732D01*
G01X-14677Y1418177D02*
X-14537Y1418089D01*
G01X-14449Y1418177D02*
X-13977Y1417882D01*
G01X-19769Y1381924D02*
X-19267Y1381596D01*
G01X-20439Y1406366D02*
X-19937Y1406038D01*
G01Y1407022D02*
X-19434Y1406694D01*
G01X-17424Y1409975D02*
X-16921Y1409647D01*
G01Y1410631D02*
X-16418Y1410303D01*
G01X-20104Y1377002D02*
X-19769Y1376839D01*
G01X-20439Y1381760D02*
X-20104Y1381596D01*
G01X-17424Y1385041D02*
X-17089Y1384876D01*
G01X-20104Y1393735D02*
X-19434Y1393407D01*
G01X-19602Y1394391D02*
X-19267Y1394227D01*
G01X-30709Y1424575D02*
X-26772Y1422606D01*
G01X-14537Y1377144D02*
X-14147Y1376937D01*
G01X-14537Y1380294D02*
X-14147Y1380087D01*
G01X-14537Y1383444D02*
X-14147Y1383236D01*
G01X-14537Y1386593D02*
X-14147Y1386386D01*
G01X-14537Y1389743D02*
X-14147Y1389535D01*
G01X-14537Y1392893D02*
X-14147Y1392685D01*
G01X-14537Y1396042D02*
X-14147Y1395835D01*
G01X-14537Y1399192D02*
X-14147Y1398984D01*
G01X-14537Y1402341D02*
X-14147Y1402134D01*
G01X-14537Y1405491D02*
X-14147Y1405283D01*
G01X-14537Y1408641D02*
X-14147Y1408433D01*
G01X-14537Y1411790D02*
X-14147Y1411583D01*
G01X-14537Y1414940D02*
X-14147Y1414732D01*
G01X-14537Y1418089D02*
X-14147Y1417882D01*
G01X-18429Y1367324D02*
X-22952Y1368800D01*
G01X-15748Y1366504D02*
X-17759Y1367160D01*
G01X-17424Y1385041D02*
X-17926Y1385205D01*
G01X-16921Y1397508D02*
X-17424Y1397672D01*
G01X-19434Y1405874D02*
X-19937Y1406038D01*
G01X-23622Y1368144D02*
X-15748Y1365520D01*
G01X-18429Y1393243D02*
X-19434Y1393407D01*
G01X-17089Y1385861D02*
X-17759Y1386025D01*
G01X-16754Y1398328D02*
X-17424Y1398492D01*
G01X-18764Y1405710D02*
X-19434Y1405874D01*
G01X-18764Y1406530D02*
X-19434Y1406694D01*
G01X-17424Y1409975D02*
X-18094Y1410139D01*
G01X-16921Y1410631D02*
X-18094Y1410959D01*
G01X-19469Y1365566D02*
X-18174Y1365580D01*
G01X-18435D02*
X-20801Y1365554D01*
G01X-18174Y1365580D02*
X-17126Y1365591D01*
G01X-19469Y1368715D02*
X-18174Y1368730D01*
G01X-18435D02*
X-20801Y1368704D01*
G01X-18174Y1368730D02*
X-17126Y1368741D01*
G01X-19469Y1371865D02*
X-18174Y1371879D01*
G01X-18435D02*
X-20801Y1371853D01*
G01X-18174Y1371879D02*
X-17126Y1371891D01*
G01X-19469Y1375015D02*
X-18174Y1375029D01*
G01X-18435D02*
X-20801Y1375003D01*
G01X-18174Y1375029D02*
X-17126Y1375040D01*
G01X-19469Y1378164D02*
X-18174Y1378178D01*
G01X-18435D02*
X-20801Y1378152D01*
G01X-18174Y1378178D02*
X-17126Y1378190D01*
G01X-19469Y1381314D02*
X-18174Y1381328D01*
G01X-18435D02*
X-20801Y1381302D01*
G01X-18174Y1381328D02*
X-17126Y1381339D01*
G01X-15985Y1365602D02*
X-14449Y1365618D01*
G01X-14677D02*
X-18174Y1365580D01*
G01X-14677Y1365618D02*
X-16213Y1365602D01*
G01X-15985Y1368751D02*
X-14449Y1368768D01*
G01X-14677D02*
X-18174Y1368730D01*
G01X-14677Y1368768D02*
X-16213Y1368751D01*
G01X-15985Y1371901D02*
X-14449Y1371917D01*
G01X-14677D02*
X-18174Y1371879D01*
G01X-14677Y1371917D02*
X-16213Y1371901D01*
G01X-15985Y1375050D02*
X-14449Y1375067D01*
G01X-14677D02*
X-18174Y1375029D01*
G01X-14677Y1375067D02*
X-16213Y1375050D01*
G01X-15985Y1378200D02*
X-14449Y1378217D01*
G01X-14677D02*
X-18174Y1378178D01*
G01X-14677Y1378217D02*
X-16213Y1378200D01*
G01X-15985Y1381350D02*
X-14449Y1381366D01*
G01X-14677D02*
X-18174Y1381328D01*
G01X-14677Y1381366D02*
X-16213Y1381350D01*
G01X-19469Y1365566D02*
X-20801Y1365554D01*
G01X-19469Y1368715D02*
X-20801Y1368704D01*
G01X-19469Y1371865D02*
X-20801Y1371853D01*
G01X-19469Y1375015D02*
X-20801Y1375003D01*
G01X-19469Y1378164D02*
X-20801Y1378152D01*
G01X-19469Y1381314D02*
X-20801Y1381302D01*
G01X-19469Y1384463D02*
X-20801Y1384452D01*
G01X-15985Y1365602D02*
X-17126Y1365591D01*
G01D02*
X-18435Y1365580D01*
G01X-15985Y1368751D02*
X-17126Y1368741D01*
G01D02*
X-18435Y1368730D01*
G01X-15985Y1371901D02*
X-17126Y1371891D01*
G01D02*
X-18435Y1371879D01*
G01X-15985Y1375050D02*
X-17126Y1375040D01*
G01D02*
X-18435Y1375029D01*
G01X-15985Y1378200D02*
X-17126Y1378190D01*
G01D02*
X-18435Y1378178D01*
G01X-15985Y1381350D02*
X-17126Y1381339D01*
G01D02*
X-18435Y1381328D01*
G01X-15985Y1384499D02*
X-17126Y1384489D01*
G01D02*
X-18435Y1384478D01*
G01X-18174Y1365580D02*
X-18435D01*
G01X-15985Y1365602D02*
X-16213D01*
G01X-14449Y1365618D02*
X-14677D01*
G01X12410Y1365717D02*
X315D01*
G01X-13009Y1365913D02*
X-14147D01*
G01X512Y1366307D02*
X0D01*
G01X512Y1367094D02*
X0D01*
G01X-13009Y1367488D02*
X-14147D01*
G01X12410Y1367685D02*
X315D01*
G01X-14449Y1367783D02*
X-14677D01*
G01X-15985Y1367800D02*
X-16213D01*
G01X-18174Y1367821D02*
X-18435D01*
G01X-18174Y1368730D02*
X-18435D01*
G01X-15985Y1368751D02*
X-16213D01*
G01X-14449Y1368768D02*
X-14677D01*
G01X12410Y1368866D02*
X315D01*
G01X-13009Y1369063D02*
X-14147D01*
G01X512Y1369457D02*
X0D01*
G01X512Y1370244D02*
X0D01*
G01X-13009Y1370638D02*
X-14147D01*
G01X12410Y1370835D02*
X315D01*
G01X-14449Y1370933D02*
X-14677D01*
G01X-15985Y1370949D02*
X-16213D01*
G01X-18174Y1370971D02*
X-18435D01*
G01X-18174Y1371879D02*
X-18435D01*
G01X-16213Y1371901D02*
X-15985D01*
G01X-14449Y1371917D02*
X-14677D01*
G01X12410Y1372016D02*
X315D01*
G01X-13009Y1372213D02*
X-14147D01*
G01X512Y1372606D02*
X0D01*
G01X512Y1373394D02*
X0D01*
G01X-15748D02*
X-21109D01*
G01X-13009Y1373787D02*
X-14147D01*
G01X12410Y1373984D02*
X315D01*
G01X-14449Y1374083D02*
X-14677D01*
G01X-15985Y1374099D02*
X-16213D01*
G01X-18174Y1374120D02*
X-18435D01*
G01X-15748Y1374214D02*
X-19937D01*
G01X-20607D02*
X-21109D01*
G01X-18174Y1375029D02*
X-18435D01*
G01X-15985Y1375050D02*
X-16213D01*
G01X-14449Y1375067D02*
X-14677D01*
G01X12410Y1375165D02*
X315D01*
G01X-13009Y1375362D02*
X-14147D01*
G01X512Y1375756D02*
X0D01*
G01X-15748Y1376018D02*
X-19769D01*
G01X512Y1376543D02*
X0D01*
G01X-15748Y1376839D02*
X-19769D01*
G01X-13009Y1376937D02*
X-14147D01*
G01X12410Y1377134D02*
X315D01*
G01X-14449Y1377232D02*
X-14677D01*
G01X-15985Y1377248D02*
X-16213D01*
G01X-18174Y1377270D02*
X-18435D01*
G01X-18174Y1378178D02*
X-18435D01*
G01X-15985Y1378200D02*
X-16213D01*
G01X-14449Y1378217D02*
X-14677D01*
G01X12410Y1378315D02*
X315D01*
G01X-13009Y1378512D02*
X-14147D01*
G01X-15748Y1378643D02*
X-19769D01*
G01X512Y1378906D02*
X0D01*
G01X-15748Y1379463D02*
X-19769D01*
G01X512Y1379693D02*
X0D01*
G01X-13009Y1380087D02*
X-14147D01*
G01X12410Y1380283D02*
X315D01*
G01X-14449Y1380382D02*
X-14677D01*
G01X-15985Y1380398D02*
X-16213D01*
G01X-18174Y1380420D02*
X-18435D01*
G01X-13068Y1380776D02*
X-21109D01*
G01X-18174Y1381328D02*
X-18435D01*
G01X-15985Y1381350D02*
X-16213D01*
G01X-14449Y1381366D02*
X-14677D01*
G01X12410Y1381465D02*
X315D01*
G01X-13068Y1381596D02*
X-16754D01*
G01X-17591D02*
X-19267D01*
G01X-20104D02*
X-21109D01*
G01X-13009Y1381661D02*
X-14147D01*
G01X512Y1382055D02*
X0D01*
G01X512Y1382843D02*
X0D01*
G01X-13009Y1383236D02*
X-14147D01*
G01X12410Y1383433D02*
X315D01*
G01X-14449Y1383531D02*
X-14677D01*
G01X-15985Y1383548D02*
X-16213D01*
G01X-18174Y1383569D02*
X-18435D01*
G01X-18174Y1384478D02*
X-18435D01*
G01X-15985Y1384499D02*
X-16213D01*
G01X-14449Y1384516D02*
X-14677D01*
G01X12410Y1384614D02*
X315D01*
G01X-13009Y1384811D02*
X-14147D01*
G01X512Y1385205D02*
X0D01*
G01X-17926D02*
X-18931D01*
G01X512Y1385992D02*
X0D01*
G01X-17759Y1386025D02*
X-19099D01*
G01X-13009Y1386386D02*
X-14147D01*
G01X12410Y1386583D02*
X315D01*
G01X-14449Y1386681D02*
X-14677D01*
G01X-15985Y1386697D02*
X-16213D01*
G01X-18174Y1386719D02*
X-18435D01*
G01X-15748Y1387337D02*
X-23622D01*
G01X-18174Y1387627D02*
X-18435D01*
G01X-15985Y1387649D02*
X-16213D01*
G01X-14449Y1387665D02*
X-14677D01*
G01X12410Y1387764D02*
X315D01*
G01X-13009Y1387961D02*
X-14147D01*
G01X-15748Y1388157D02*
X-19602D01*
G01X-20272D02*
X-23622D01*
G01X512Y1388354D02*
X0D01*
G01X512Y1389142D02*
X0D01*
G01X-19469Y1367836D02*
X-20801Y1367848D01*
G01X-15985Y1367800D02*
X-18435Y1367821D01*
G01X-19469Y1370985D02*
X-20801Y1370997D01*
G01X-15985Y1370949D02*
X-18435Y1370971D01*
G01X-19469Y1374135D02*
X-20801Y1374147D01*
G01X-15985Y1374099D02*
X-18435Y1374120D01*
G01X-19469Y1377285D02*
X-20801Y1377296D01*
G01X-15985Y1377248D02*
X-18435Y1377270D01*
G01X-19469Y1380434D02*
X-20801Y1380446D01*
G01X-15985Y1380398D02*
X-18435Y1380420D01*
G01X-19469Y1383584D02*
X-20801Y1383596D01*
G01X-15985Y1383548D02*
X-18435Y1383569D01*
G01X-19469Y1386733D02*
X-20801Y1386745D01*
G01X-15985Y1386697D02*
X-18435Y1386719D01*
G01X-19469Y1389883D02*
X-20801Y1389895D01*
G01X-15985Y1389847D02*
X-18435Y1389869D01*
G01X-19469Y1393033D02*
X-20801Y1393044D01*
G01X-15985Y1392996D02*
X-18435Y1393018D01*
G01X-15985Y1367800D02*
X-14449Y1367783D01*
G01X-15985Y1370949D02*
X-14449Y1370933D01*
G01X-15985Y1374099D02*
X-14449Y1374083D01*
G01X-15985Y1377248D02*
X-14449Y1377232D01*
G01X-15985Y1380398D02*
X-14449Y1380382D01*
G01X-15985Y1383548D02*
X-14449Y1383531D01*
G01X-15985Y1386697D02*
X-14449Y1386681D01*
G01X-15985Y1389847D02*
X-14449Y1389831D01*
G01X-15985Y1392996D02*
X-14449Y1392980D01*
G01X-18435Y1367821D02*
X-20801Y1367848D01*
G01X-18435Y1370971D02*
X-20801Y1370997D01*
G01X-18435Y1374120D02*
X-20801Y1374147D01*
G01X-18435Y1377270D02*
X-20801Y1377296D01*
G01X-18435Y1380420D02*
X-20801Y1380446D01*
G01X-18435Y1383569D02*
X-20801Y1383596D01*
G01X-18435Y1386719D02*
X-20801Y1386745D01*
G01X-18435Y1389869D02*
X-20801Y1389895D01*
G01X-18435Y1393018D02*
X-20801Y1393044D01*
G01X-19469Y1367836D02*
X-16213Y1367800D01*
G01X-18174Y1367821D02*
X-14677Y1367783D01*
G01X-19469Y1370985D02*
X-16213Y1370949D01*
G01X-18174Y1370971D02*
X-14677Y1370933D01*
G01X-19469Y1374135D02*
X-16213Y1374099D01*
G01X-18174Y1374120D02*
X-14677Y1374083D01*
G01X-19469Y1377285D02*
X-16213Y1377248D01*
G01X-18174Y1377270D02*
X-14677Y1377232D01*
G01X-19469Y1380434D02*
X-16213Y1380398D01*
G01X-18174Y1380420D02*
X-14677Y1380382D01*
G01X-19469Y1383584D02*
X-16213Y1383548D01*
G01X-18174Y1383569D02*
X-14677Y1383531D01*
G01X-19469Y1386733D02*
X-16213Y1386697D01*
G01X-18174Y1386719D02*
X-14677Y1386681D01*
G01X-19469Y1389883D02*
X-16213Y1389847D01*
G01X-18174Y1389869D02*
X-14677Y1389831D01*
G01X-19469Y1393033D02*
X-16213Y1392996D01*
G01X-18174Y1393018D02*
X-14677Y1392980D01*
G01X-19469Y1384463D02*
X-18174Y1384478D01*
G01X-18435D02*
X-20801Y1384452D01*
G01X-18174Y1384478D02*
X-17126Y1384489D01*
G01X-19469Y1387613D02*
X-18174Y1387627D01*
G01X-18435D02*
X-20801Y1387601D01*
G01X-18174Y1387627D02*
X-17126Y1387639D01*
G01X-19469Y1390763D02*
X-18174Y1390777D01*
G01X-18435D02*
X-20801Y1390751D01*
G01X-18174Y1390777D02*
X-17126Y1390788D01*
G01X-19469Y1393912D02*
X-18174Y1393926D01*
G01X-18435D02*
X-20801Y1393900D01*
G01X-18174Y1393926D02*
X-17126Y1393938D01*
G01X-19469Y1397062D02*
X-18174Y1397076D01*
G01X-18435D02*
X-20801Y1397050D01*
G01X-18174Y1397076D02*
X-17126Y1397087D01*
G01X-19469Y1400211D02*
X-18174Y1400226D01*
G01X-18435D02*
X-20801Y1400200D01*
G01X-18174Y1400226D02*
X-17126Y1400237D01*
G01X-19469Y1403361D02*
X-18174Y1403375D01*
G01X-18435D02*
X-20801Y1403349D01*
G01X-18174Y1403375D02*
X-17126Y1403387D01*
G01X-19469Y1406511D02*
X-18174Y1406525D01*
G01X-18435D02*
X-20801Y1406499D01*
G01X-18174Y1406525D02*
X-17126Y1406536D01*
G01X-19469Y1409660D02*
X-18174Y1409674D01*
G01X-18435D02*
X-20801Y1409648D01*
G01X-18174Y1409674D02*
X-17126Y1409686D01*
G01X-19469Y1412810D02*
X-18174Y1412824D01*
G01X-18435D02*
X-20801Y1412798D01*
G01X-18174Y1412824D02*
X-17126Y1412835D01*
G01X-19469Y1415959D02*
X-18174Y1415974D01*
G01X-18435D02*
X-20801Y1415948D01*
G01X-18174Y1415974D02*
X-17126Y1415985D01*
G01X-19469Y1419109D02*
X-18174Y1419123D01*
G01X-18435D02*
X-20801Y1419097D01*
G01X-18174Y1419123D02*
X-17126Y1419135D01*
G01X-15985Y1384499D02*
X-14449Y1384516D01*
G01X-14677D02*
X-18174Y1384478D01*
G01X-14677Y1384516D02*
X-16213Y1384499D01*
G01X-15985Y1387649D02*
X-14449Y1387665D01*
G01X-14677D02*
X-18174Y1387627D01*
G01X-14677Y1387665D02*
X-16213Y1387649D01*
G01X-15985Y1390798D02*
X-14449Y1390815D01*
G01X-14677D02*
X-18174Y1390777D01*
G01X-14677Y1390815D02*
X-16213Y1390798D01*
G01X-15985Y1393948D02*
X-14449Y1393965D01*
G01X-14677D02*
X-18174Y1393926D01*
G01X-14677Y1393965D02*
X-16213Y1393948D01*
G01X-15985Y1397098D02*
X-14449Y1397114D01*
G01X-14677D02*
X-18174Y1397076D01*
G01X-14677Y1397114D02*
X-16213Y1397098D01*
G01X-15985Y1400247D02*
X-14449Y1400264D01*
G01X-14677D02*
X-18174Y1400226D01*
G01X-14677Y1400264D02*
X-16213Y1400247D01*
G01X-15985Y1403397D02*
X-14449Y1403413D01*
G01X-14677D02*
X-18174Y1403375D01*
G01X-14677Y1403413D02*
X-16213Y1403397D01*
G01X-15985Y1406546D02*
X-14449Y1406563D01*
G01X-14677D02*
X-18174Y1406525D01*
G01X-14677Y1406563D02*
X-16213Y1406546D01*
G01X-15985Y1409696D02*
X-14449Y1409713D01*
G01X-14677D02*
X-18174Y1409674D01*
G01X-14677Y1409713D02*
X-16213Y1409696D01*
G01X-15985Y1412846D02*
X-14449Y1412862D01*
G01X-14677D02*
X-18174Y1412824D01*
G01X-14677Y1412862D02*
X-16213Y1412846D01*
G01X-15985Y1415995D02*
X-14449Y1416012D01*
G01X-14677D02*
X-18174Y1415974D01*
G01X-14677Y1416012D02*
X-16213Y1415995D01*
G01X-15985Y1419145D02*
X-14449Y1419161D01*
G01X-14677D02*
X-18174Y1419123D01*
G01X-14677Y1419161D02*
X-16213Y1419145D01*
G01X-19469Y1387613D02*
X-20801Y1387601D01*
G01X-19469Y1390763D02*
X-20801Y1390751D01*
G01X-19469Y1393912D02*
X-20801Y1393900D01*
G01X-19469Y1397062D02*
X-20801Y1397050D01*
G01X-19469Y1400211D02*
X-20801Y1400200D01*
G01X-19469Y1403361D02*
X-20801Y1403349D01*
G01X-19469Y1406511D02*
X-20801Y1406499D01*
G01X-19469Y1409660D02*
X-20801Y1409648D01*
G01X-19469Y1412810D02*
X-20801Y1412798D01*
G01X-19469Y1415959D02*
X-20801Y1415948D01*
G01X-19469Y1419109D02*
X-20801Y1419097D01*
G01X-15985Y1387649D02*
X-17126Y1387639D01*
G01D02*
X-18435Y1387627D01*
G01X-15985Y1390798D02*
X-17126Y1390788D01*
G01D02*
X-18435Y1390777D01*
G01X-15985Y1393948D02*
X-17126Y1393938D01*
G01D02*
X-18435Y1393926D01*
G01X-15985Y1397098D02*
X-17126Y1397087D01*
G01D02*
X-18435Y1397076D01*
G01X-15985Y1400247D02*
X-17126Y1400237D01*
G01D02*
X-18435Y1400226D01*
G01X-15985Y1403397D02*
X-17126Y1403387D01*
G01D02*
X-18435Y1403375D01*
G01X-15985Y1406546D02*
X-17126Y1406536D01*
G01D02*
X-18435Y1406525D01*
G01X-15985Y1409696D02*
X-17126Y1409686D01*
G01D02*
X-18435Y1409674D01*
G01X-15985Y1412846D02*
X-17126Y1412835D01*
G01D02*
X-18435Y1412824D01*
G01X-15985Y1415995D02*
X-17126Y1415985D01*
G01D02*
X-18435Y1415974D01*
G01X-15985Y1419145D02*
X-17126Y1419135D01*
G01D02*
X-18435Y1419123D01*
G01X-13009Y1389535D02*
X-14147D01*
G01X12410Y1389732D02*
X315D01*
G01X-14449Y1389831D02*
X-14677D01*
G01X-15985Y1389847D02*
X-16213D01*
G01X-18174Y1389869D02*
X-18435D01*
G01X-18174Y1390777D02*
X-18435D01*
G01X-15985Y1390798D02*
X-16213D01*
G01X-14449Y1390815D02*
X-14677D01*
G01X12410Y1390913D02*
X315D01*
G01X-13009Y1391110D02*
X-14147D01*
G01X-15748D02*
X-19099D01*
G01X512Y1391504D02*
X0D01*
G01X-15748Y1391930D02*
X-19099D01*
G01X512Y1392291D02*
X0D01*
G01X-13009Y1392685D02*
X-14147D01*
G01X12410Y1392882D02*
X315D01*
G01X-14449Y1392980D02*
X-14677D01*
G01X-15985Y1392996D02*
X-16213D01*
G01X-18174Y1393018D02*
X-18435D01*
G01X-18174Y1393926D02*
X-18435D01*
G01X-15985Y1393948D02*
X-16213D01*
G01X-14449Y1393965D02*
X-14677D01*
G01X12410Y1394063D02*
X315D01*
G01X-18094D02*
X-18429D01*
G01X-19099Y1394227D02*
X-19267D01*
G01X-13009Y1394260D02*
X-14147D01*
G01X512Y1394654D02*
X0D01*
G01X512Y1395441D02*
X0D01*
G01X-13009Y1395835D02*
X-14147D01*
G01X12410Y1396031D02*
X315D01*
G01X-14449Y1396130D02*
X-14677D01*
G01X-15985Y1396146D02*
X-16213D01*
G01X-18174Y1396168D02*
X-18435D01*
G01X-18174Y1397076D02*
X-18435D01*
G01X-15985Y1397098D02*
X-16213D01*
G01X-14449Y1397114D02*
X-14677D01*
G01X12410Y1397213D02*
X315D01*
G01X-13009Y1397409D02*
X-14147D01*
G01X-19099Y1397672D02*
X-19434D01*
G01X512Y1397803D02*
X0D01*
G01X-18429Y1398492D02*
X-19099D01*
G01X512Y1398591D02*
X0D01*
G01X-13009Y1398984D02*
X-14147D01*
G01X12410Y1399181D02*
X315D01*
G01X-14449Y1399280D02*
X-14677D01*
G01X-15985Y1399296D02*
X-16213D01*
G01X-18174Y1399317D02*
X-18435D01*
G01X-15748Y1399804D02*
X-21109D01*
G01X-18174Y1400226D02*
X-18435D01*
G01X-15985Y1400247D02*
X-16213D01*
G01X-14449Y1400264D02*
X-14677D01*
G01X12410Y1400362D02*
X315D01*
G01X-13009Y1400559D02*
X-14147D01*
G01X-15748Y1400624D02*
X-19602D01*
G01X-20272D02*
X-21109D01*
G01X512Y1400953D02*
X0D01*
G01X512Y1401740D02*
X0D01*
G01X-13009Y1402134D02*
X-14147D01*
G01X12410Y1402331D02*
X315D01*
G01X-14449Y1402429D02*
X-14677D01*
G01X-15985Y1402445D02*
X-16213D01*
G01X-18174Y1402467D02*
X-18435D01*
G01X-18174Y1403375D02*
X-18435D01*
G01X-15985Y1403397D02*
X-16213D01*
G01X-14449Y1403413D02*
X-14677D01*
G01X12410Y1403512D02*
X315D01*
G01X-15748Y1403577D02*
X-18931D01*
G01X-13009Y1403709D02*
X-14147D01*
G01X512Y1404102D02*
X0D01*
G01X-15748Y1404398D02*
X-18931D01*
G01X512Y1404890D02*
X0D01*
G01X-13009Y1405283D02*
X-14147D01*
G01X12410Y1405480D02*
X315D01*
G01X-14449Y1405579D02*
X-14677D01*
G01X-15985Y1405595D02*
X-16213D01*
G01X-18174Y1405617D02*
X-18435D01*
G01X-18094Y1405710D02*
X-18764D01*
G01X-18174Y1406525D02*
X-18435D01*
G01X-18094Y1406530D02*
X-18764D01*
G01X-15985Y1406546D02*
X-16213D01*
G01X-14449Y1406563D02*
X-14677D01*
G01X12410Y1406661D02*
X315D01*
G01X-13009Y1406858D02*
X-14147D01*
G01X512Y1407252D02*
X0D01*
G01X512Y1408039D02*
X0D01*
G01X-13009Y1408433D02*
X-14147D01*
G01X12410Y1408630D02*
X315D01*
G01X-14449Y1408728D02*
X-14677D01*
G01X-15985Y1408744D02*
X-16213D01*
G01X-18174Y1408766D02*
X-18435D01*
G01X-18174Y1409674D02*
X-18435D01*
G01X-15985Y1409696D02*
X-16213D01*
G01X-14449Y1409713D02*
X-14677D01*
G01X12410Y1409811D02*
X315D01*
G01X-13009Y1410008D02*
X-14147D01*
G01X-18094Y1410139D02*
X-18764D01*
G01X512Y1410402D02*
X0D01*
G01X-18094Y1410959D02*
X-18764D01*
G01X512Y1411189D02*
X0D01*
G01X-13009Y1411583D02*
X-14147D01*
G01X12410Y1411780D02*
X315D01*
G01X-14449Y1411878D02*
X-14677D01*
G01X-15985Y1411894D02*
X-16213D01*
G01X-18174Y1411916D02*
X-18435D01*
G01X-15748Y1412272D02*
X-23622D01*
G01X-18174Y1412824D02*
X-18435D01*
G01X-15985Y1412846D02*
X-16213D01*
G01X-14449Y1412862D02*
X-14677D01*
G01X12410Y1412961D02*
X315D01*
G01X-15748Y1413092D02*
X-23622D01*
G01X-13009Y1413157D02*
X-14147D01*
G01X512Y1413551D02*
X0D01*
G01X512Y1414339D02*
X0D01*
G01X-13009Y1414732D02*
X-14147D01*
G01X12410Y1414929D02*
X315D01*
G01X-14449Y1415028D02*
X-14677D01*
G01X-15985Y1415044D02*
X-16213D01*
G01X-18174Y1415065D02*
X-18435D01*
G01X-18174Y1415974D02*
X-18435D01*
G01X-15985Y1415995D02*
X-16213D01*
G01X-14449Y1416012D02*
X-14677D01*
G01X12410Y1416110D02*
X315D01*
G01X-13009Y1416307D02*
X-14147D01*
G01X512Y1416701D02*
X0D01*
G01X512Y1417488D02*
X0D01*
G01X-13009Y1417882D02*
X-14147D01*
G01X12410Y1418079D02*
X315D01*
G01X-14449Y1418177D02*
X-14677D01*
G01X-15985Y1418193D02*
X-16213D01*
G01X-18174Y1418215D02*
X-18435D01*
G01X-18174Y1419123D02*
X-18435D01*
G01X-15985Y1419145D02*
X-16213D01*
G01X-14449Y1419161D02*
X-14677D01*
G01X12410Y1419260D02*
X315D01*
G01X-13009Y1419457D02*
X-14147D01*
G01X512Y1419850D02*
X0D01*
G01X-7283Y1422606D02*
X-26772D01*
G01X-19469Y1396182D02*
X-20801Y1396194D01*
G01X-15985Y1396146D02*
X-18435Y1396168D01*
G01X-19469Y1399332D02*
X-20801Y1399344D01*
G01X-15985Y1399296D02*
X-18435Y1399317D01*
G01X-19469Y1402481D02*
X-20801Y1402493D01*
G01X-15985Y1402445D02*
X-18435Y1402467D01*
G01X-19469Y1405631D02*
X-20801Y1405643D01*
G01X-15985Y1405595D02*
X-18435Y1405617D01*
G01X-19469Y1408781D02*
X-20801Y1408793D01*
G01X-15985Y1408744D02*
X-18435Y1408766D01*
G01X-19469Y1411930D02*
X-20801Y1411942D01*
G01X-15985Y1411894D02*
X-18435Y1411916D01*
G01X-19469Y1415080D02*
X-20801Y1415092D01*
G01X-15985Y1415044D02*
X-18435Y1415065D01*
G01X-19469Y1418230D02*
X-20801Y1418241D01*
G01X-15985Y1418193D02*
X-18435Y1418215D01*
G01X-15985Y1396146D02*
X-14449Y1396130D01*
G01X-15985Y1399296D02*
X-14449Y1399280D01*
G01X-15985Y1402445D02*
X-14449Y1402429D01*
G01X-15985Y1405595D02*
X-14449Y1405579D01*
G01X-15985Y1408744D02*
X-14449Y1408728D01*
G01X-15985Y1411894D02*
X-14449Y1411878D01*
G01X-15985Y1415044D02*
X-14449Y1415028D01*
G01X-15985Y1418193D02*
X-14449Y1418177D01*
G01X-18435Y1396168D02*
X-20801Y1396194D01*
G01X-18435Y1399317D02*
X-20801Y1399344D01*
G01X-18435Y1402467D02*
X-20801Y1402493D01*
G01X-18435Y1405617D02*
X-20801Y1405643D01*
G01X-18435Y1408766D02*
X-20801Y1408793D01*
G01X-18435Y1411916D02*
X-20801Y1411942D01*
G01X-18435Y1415065D02*
X-20801Y1415092D01*
G01X-18435Y1418215D02*
X-20801Y1418241D01*
G01X-19469Y1396182D02*
X-16213Y1396146D01*
G01X-18174Y1396168D02*
X-14677Y1396130D01*
G01X-19469Y1399332D02*
X-16213Y1399296D01*
G01X-18174Y1399317D02*
X-14677Y1399280D01*
G01X-19469Y1402481D02*
X-16213Y1402445D01*
G01X-18174Y1402467D02*
X-14677Y1402429D01*
G01X-19469Y1405631D02*
X-16213Y1405595D01*
G01X-18174Y1405617D02*
X-14677Y1405579D01*
G01X-19469Y1408781D02*
X-16213Y1408744D01*
G01X-18174Y1408766D02*
X-14677Y1408728D01*
G01X-19469Y1411930D02*
X-16213Y1411894D01*
G01X-18174Y1411916D02*
X-14677Y1411878D01*
G01X-19469Y1415080D02*
X-16213Y1415044D01*
G01X-18174Y1415065D02*
X-14677Y1415028D01*
G01X-19469Y1418230D02*
X-16213Y1418193D01*
G01X-18174Y1418215D02*
X-14677Y1418177D01*
G01X-16921Y1406038D02*
X-18094Y1405710D01*
G01X-19099Y1386025D02*
X-19769Y1385861D01*
G01X-19099Y1391110D02*
X-19769Y1390946D01*
G01X-19099Y1398492D02*
X-19769Y1398328D01*
G01X-17424Y1406694D02*
X-18094Y1406530D01*
G01X-18764Y1410139D02*
X-19434Y1409975D01*
G01X-18764Y1410959D02*
X-19434Y1410795D01*
G01X-19099Y1391930D02*
X-19937Y1391766D01*
G01X-18931Y1403577D02*
X-19769Y1403413D01*
G01X-18931Y1404398D02*
X-19769Y1404233D01*
G01X-17424Y1393407D02*
X-18429Y1393243D01*
G01X-20801Y1365554D02*
Y1364698D01*
G01Y1359255D02*
Y1358399D01*
G01Y1362404D02*
Y1361548D01*
G01X-19469Y1365560D02*
Y1364692D01*
G01Y1359261D02*
Y1358393D01*
G01Y1362410D02*
Y1361543D01*
G01X-18435Y1365580D02*
Y1364672D01*
G01Y1359281D02*
Y1358372D01*
G01Y1362430D02*
Y1361522D01*
G01X-18174Y1365580D02*
Y1364672D01*
G01Y1359281D02*
Y1358372D01*
G01Y1362430D02*
Y1361522D01*
G01X-16213Y1365602D02*
Y1364650D01*
G01Y1359302D02*
Y1358351D01*
G01Y1362452D02*
Y1361500D01*
G01X-15985Y1365602D02*
Y1364650D01*
G01Y1359302D02*
Y1358351D01*
G01Y1362452D02*
Y1361500D01*
G01X-14537Y1362556D02*
X-14677Y1362469D01*
G01X-13977Y1362764D02*
X-14449Y1362469D01*
G01X-14537Y1359407D02*
X-14677Y1359319D01*
G01X-13977Y1359614D02*
X-14449Y1359319D01*
G01X-14147Y1362764D02*
X-14537Y1362556D01*
G01X-14147Y1359614D02*
X-14537Y1359407D01*
G01Y1365706D02*
Y1364546D01*
G01Y1359407D02*
Y1358247D01*
G01Y1362556D02*
Y1361396D01*
G01X-13009Y1365913D02*
Y1364339D01*
G01Y1359614D02*
Y1358039D01*
G01Y1362764D02*
Y1361189D01*
G01X315Y1364535D02*
Y1363945D01*
G01Y1360008D02*
Y1359417D01*
G01Y1363157D02*
Y1362567D01*
G01Y1361386D02*
Y1360795D01*
G01Y1358236D02*
Y1357646D01*
G01X512Y1364535D02*
Y1363945D01*
G01Y1360008D02*
Y1359417D01*
G01Y1363157D02*
Y1362567D01*
G01Y1361386D02*
Y1360795D01*
G01Y1358236D02*
Y1357646D01*
G01X709Y1365717D02*
Y1364535D01*
G01Y1359417D02*
Y1358236D01*
G01Y1362567D02*
Y1361386D01*
G01X1074Y1365717D02*
Y1364535D01*
G01Y1359417D02*
Y1358236D01*
G01Y1362567D02*
Y1361386D01*
G01X1184Y1365717D02*
Y1364535D01*
G01Y1359417D02*
Y1358236D01*
G01Y1362567D02*
Y1361386D01*
G01X9965Y1365717D02*
Y1364535D01*
G01Y1359417D02*
Y1358236D01*
G01Y1362567D02*
Y1361386D01*
G01X10075Y1365717D02*
Y1364535D01*
G01Y1359417D02*
Y1358236D01*
G01Y1362567D02*
Y1361386D01*
G01X-14537Y1358247D02*
X-14147Y1358039D01*
G01X-14537Y1361396D02*
X-14147Y1361189D01*
G01X-14537Y1364546D02*
X-14147Y1364339D01*
G01X-14677Y1358335D02*
X-14537Y1358247D01*
G01X-14449Y1358335D02*
X-13977Y1358039D01*
G01X-14677Y1361484D02*
X-14537Y1361396D01*
G01X-14449Y1361484D02*
X-13977Y1361189D01*
G01X-14677Y1364634D02*
X-14537Y1364546D01*
G01X-14449Y1364634D02*
X-13977Y1364339D01*
G01X-19469Y1359267D02*
X-18174Y1359281D01*
G01X-18435D02*
X-20801Y1359255D01*
G01X-18174Y1359281D02*
X-17126Y1359292D01*
G01X-19469Y1362416D02*
X-18174Y1362430D01*
G01X-18435D02*
X-20801Y1362404D01*
G01X-18174Y1362430D02*
X-17126Y1362442D01*
G01X-15985Y1359302D02*
X-14449Y1359319D01*
G01X-14677D02*
X-18174Y1359281D01*
G01X-14677Y1359319D02*
X-16213Y1359302D01*
G01X-15985Y1362452D02*
X-14449Y1362469D01*
G01X-14677D02*
X-18174Y1362430D01*
G01X-14677Y1362469D02*
X-16213Y1362452D01*
G01X-19469Y1359267D02*
X-20801Y1359255D01*
G01X-19469Y1362416D02*
X-20801Y1362404D01*
G01X-15985Y1359302D02*
X-17126Y1359292D01*
G01D02*
X-18435Y1359281D01*
G01X-15985Y1362452D02*
X-17126Y1362442D01*
G01D02*
X-18435Y1362430D01*
G01X512Y1357646D02*
X0D01*
G01X-13009Y1358039D02*
X-14147D01*
G01X12410Y1358236D02*
X315D01*
G01X-14449Y1358335D02*
X-14677D01*
G01X-15985Y1358351D02*
X-16213D01*
G01X-18174Y1358372D02*
X-18435D01*
G01X-18174Y1359281D02*
X-18435D01*
G01X-15985Y1359302D02*
X-16213D01*
G01X-14449Y1359319D02*
X-14677D01*
G01X12410Y1359417D02*
X315D01*
G01X-13009Y1359614D02*
X-14147D01*
G01X512Y1360008D02*
X0D01*
G01X512Y1360795D02*
X0D01*
G01X-13009Y1361189D02*
X-14147D01*
G01X12410Y1361386D02*
X315D01*
G01X-14449Y1361484D02*
X-14677D01*
G01X-15985Y1361500D02*
X-16213D01*
G01X-18174Y1361522D02*
X-18435D01*
G01X-18174Y1362430D02*
X-18435D01*
G01X-15985Y1362452D02*
X-16213D01*
G01X-14449Y1362469D02*
X-14677D01*
G01X12410Y1362567D02*
X315D01*
G01X-13009Y1362764D02*
X-14147D01*
G01X512Y1363157D02*
X0D01*
G01X512Y1363945D02*
X0D01*
G01X-13009Y1364339D02*
X-14147D01*
G01X12410Y1364535D02*
X315D01*
G01X-14449Y1364634D02*
X-14677D01*
G01X-15985Y1364650D02*
X-16213D01*
G01X-18174Y1364672D02*
X-18435D01*
G01X-19469Y1358387D02*
X-20801Y1358399D01*
G01X-15985Y1358351D02*
X-18435Y1358372D01*
G01X-19469Y1361537D02*
X-20801Y1361548D01*
G01X-15985Y1361500D02*
X-18435Y1361522D01*
G01X-19469Y1364686D02*
X-20801Y1364698D01*
G01X-15985Y1364650D02*
X-18435Y1364672D01*
G01X-15985Y1358351D02*
X-14449Y1358335D01*
G01X-15985Y1361500D02*
X-14449Y1361484D01*
G01X-15985Y1364650D02*
X-14449Y1364634D01*
G01X-18435Y1358372D02*
X-20801Y1358399D01*
G01X-18435Y1361522D02*
X-20801Y1361548D01*
G01X-18435Y1364672D02*
X-20801Y1364698D01*
G01X-19469Y1358387D02*
X-16213Y1358351D01*
G01X-18174Y1358372D02*
X-14677Y1358335D01*
G01X-19469Y1361537D02*
X-16213Y1361500D01*
G01X-18174Y1361522D02*
X-14677Y1361484D01*
G01X-19469Y1364686D02*
X-16213Y1364650D01*
G01X-18174Y1364672D02*
X-14677Y1364634D01*
G01X22441Y1441110D02*
X11811D01*
G01X22441Y1449772D02*
X11811D01*
G01X11861Y1441110D02*
G03Y1449771I-50J4331D01*
G01X22441Y1489142D02*
X11811D01*
G01X22441Y1500559D02*
Y1471031D01*
G01Y1480480D02*
X11811D01*
G01X11861D02*
G03Y1489141I-50J4331D01*
G01X-9055Y1459220D02*
Y1438354D01*
G01X11893Y1441111D02*
X-9055Y1440717D01*
G01X11817Y1441110D02*
X-9055Y1440717D01*
G01X22441Y1459220D02*
X-9055D01*
G01Y1450165D02*
X11813Y1449772D01*
G01X11893Y1449771D02*
X-9055Y1450165D01*
G01X16142Y1445441D02*
G03I-4331J0D01*
G01X11827Y1449772D02*
G03Y1441110I-16J-4331D01*
G01X-30709Y1505677D02*
Y1500559D01*
G01X0Y1504496D02*
X3937Y1500559D01*
G01X22441D02*
X3937D01*
G01X11817Y1489142D02*
X-9055Y1489535D01*
G01X11893Y1489141D02*
X-9055Y1489535D01*
G01Y1494654D02*
Y1471031D01*
G01X11893Y1480481D02*
X-9055Y1480087D01*
G01D02*
X11813Y1480480D01*
G01X22441Y1471031D02*
X-9055D01*
G01X16142Y1484811D02*
G03I-4331J0D01*
G01X11827Y1489142D02*
G03Y1480480I-16J-4331D01*
G01X12287Y1574240D02*
X12057Y1573984D01*
G01X12634Y1574240D02*
X12416Y1573970D01*
G01X12634Y1571091D02*
X12416Y1570820D01*
G01X12634Y1567941D02*
X12416Y1567671D01*
G01X12634Y1564791D02*
X12416Y1564521D01*
G01X12634Y1561642D02*
X12416Y1561372D01*
G01X12634Y1558492D02*
X12416Y1558222D01*
G01X12634Y1555343D02*
X12416Y1555072D01*
G01X12634Y1552193D02*
X12416Y1551923D01*
G01X12634Y1549043D02*
X12416Y1548773D01*
G01X12634Y1545894D02*
X12416Y1545624D01*
G01X12287Y1571091D02*
X12057Y1570835D01*
G01X12287Y1567941D02*
X12057Y1567685D01*
G01X12287Y1564791D02*
X12057Y1564535D01*
G01X12287Y1561642D02*
X12057Y1561386D01*
G01X12287Y1558492D02*
X12057Y1558236D01*
G01X12287Y1555343D02*
X12057Y1555087D01*
G01X12287Y1552193D02*
X12057Y1551937D01*
G01X12287Y1549043D02*
X12057Y1548787D01*
G01X12287Y1545894D02*
X12057Y1545638D01*
G01Y1575165D02*
Y1573984D01*
G01Y1572016D02*
Y1570835D01*
G01Y1565717D02*
Y1564535D01*
G01Y1568866D02*
Y1567685D01*
G01Y1562567D02*
Y1561386D01*
G01Y1556268D02*
Y1555087D01*
G01Y1559417D02*
Y1558236D01*
G01Y1553118D02*
Y1551937D01*
G01Y1546819D02*
Y1545638D01*
G01Y1549969D02*
Y1548787D01*
G01X12410Y1575165D02*
Y1573984D01*
G01Y1572016D02*
Y1570835D01*
G01Y1565717D02*
Y1564535D01*
G01Y1568866D02*
Y1567685D01*
G01Y1562567D02*
Y1561386D01*
G01Y1556268D02*
Y1555087D01*
G01Y1559417D02*
Y1558236D01*
G01Y1553118D02*
Y1551937D01*
G01Y1546819D02*
Y1545638D01*
G01Y1549969D02*
Y1548787D01*
G01X13353Y1574909D02*
Y1574240D01*
G01Y1571760D02*
Y1571091D01*
G01Y1565461D02*
Y1564791D01*
G01Y1568610D02*
Y1567941D01*
G01Y1562311D02*
Y1561642D01*
G01Y1556012D02*
Y1555343D01*
G01Y1559161D02*
Y1558492D01*
G01Y1552862D02*
Y1552193D01*
G01Y1546563D02*
Y1545894D01*
G01Y1549713D02*
Y1549043D01*
G01X13701Y1574909D02*
Y1574240D01*
G01Y1571760D02*
Y1571091D01*
G01Y1565461D02*
Y1564791D01*
G01Y1568610D02*
Y1567941D01*
G01Y1562311D02*
Y1561642D01*
G01Y1556012D02*
Y1555343D01*
G01Y1559161D02*
Y1558492D01*
G01Y1552862D02*
Y1552193D01*
G01Y1546563D02*
Y1545894D01*
G01Y1549713D02*
Y1549043D01*
G01X12057Y1546819D02*
X12287Y1546563D01*
G01X12057Y1549969D02*
X12287Y1549713D01*
G01X12057Y1553118D02*
X12287Y1552862D01*
G01X12057Y1556268D02*
X12287Y1556012D01*
G01X12057Y1559417D02*
X12287Y1559161D01*
G01X12057Y1562567D02*
X12287Y1562311D01*
G01X12057Y1565717D02*
X12287Y1565461D01*
G01X12416Y1546833D02*
X12634Y1546563D01*
G01X12416Y1549983D02*
X12634Y1549713D01*
G01X12416Y1553132D02*
X12634Y1552862D01*
G01X12416Y1556282D02*
X12634Y1556012D01*
G01X12416Y1559431D02*
X12634Y1559161D01*
G01X12416Y1562581D02*
X12634Y1562311D01*
G01X12416Y1565731D02*
X12634Y1565461D01*
G01X12416Y1568880D02*
X12634Y1568610D01*
G01X12416Y1572030D02*
X12634Y1571760D01*
G01X12416Y1575180D02*
X12634Y1574909D01*
G01X12057Y1568866D02*
X12287Y1568610D01*
G01X12057Y1572016D02*
X12287Y1571760D01*
G01X12057Y1575165D02*
X12287Y1574909D01*
G01X13701Y1545894D02*
X12287D01*
G01X13701Y1546563D02*
X12287D01*
G01X13701Y1549043D02*
X12287D01*
G01X13701Y1549713D02*
X12287D01*
G01X13701Y1552193D02*
X12287D01*
G01X13701Y1552862D02*
X12287D01*
G01X13701Y1555343D02*
X12287D01*
G01X13701Y1556012D02*
X12287D01*
G01X13701Y1558492D02*
X12287D01*
G01X13701Y1559161D02*
X12287D01*
G01X13701Y1561642D02*
X12287D01*
G01X13701Y1562311D02*
X12287D01*
G01X13701Y1564791D02*
X12287D01*
G01X13701Y1565461D02*
X12287D01*
G01X13701Y1567941D02*
X12287D01*
G01X13701Y1568610D02*
X12287D01*
G01X13701Y1571091D02*
X12287D01*
G01X13701Y1571760D02*
X12287D01*
G01X13701Y1574240D02*
X12287D01*
G01X13701Y1574909D02*
X12287D01*
G01X12634Y1542744D02*
X12416Y1542474D01*
G01X12634Y1539594D02*
X12416Y1539324D01*
G01X12634Y1536445D02*
X12416Y1536175D01*
G01X12634Y1533295D02*
X12416Y1533025D01*
G01X12634Y1530146D02*
X12416Y1529876D01*
G01X12634Y1526996D02*
X12416Y1526726D01*
G01X12634Y1523846D02*
X12416Y1523576D01*
G01X12634Y1520697D02*
X12416Y1520427D01*
G01X12634Y1517547D02*
X12416Y1517277D01*
G01X12634Y1514398D02*
X12416Y1514128D01*
G01X12634Y1511248D02*
X12416Y1510978D01*
G01X12287Y1542744D02*
X12057Y1542488D01*
G01X12287Y1539594D02*
X12057Y1539339D01*
G01X12287Y1536445D02*
X12057Y1536189D01*
G01X12287Y1533295D02*
X12057Y1533039D01*
G01X12287Y1530146D02*
X12057Y1529890D01*
G01X12287Y1526996D02*
X12057Y1526740D01*
G01X12287Y1523846D02*
X12057Y1523591D01*
G01X12287Y1520697D02*
X12057Y1520441D01*
G01X12287Y1517547D02*
X12057Y1517291D01*
G01X12287Y1514398D02*
X12057Y1514142D01*
G01X12287Y1511248D02*
X12057Y1510992D01*
G01X18071Y1511740D02*
X15945Y1511031D01*
G01Y1511297D02*
X16487Y1511474D01*
G01X17890Y1511917D02*
X16669Y1511519D01*
G01X12057Y1543669D02*
Y1542488D01*
G01Y1537370D02*
Y1536189D01*
G01Y1540520D02*
Y1539339D01*
G01Y1534220D02*
Y1533039D01*
G01Y1527921D02*
Y1526740D01*
G01Y1531071D02*
Y1529890D01*
G01Y1524772D02*
Y1523591D01*
G01Y1518472D02*
Y1517291D01*
G01Y1521622D02*
Y1520441D01*
G01Y1515323D02*
Y1514142D01*
G01Y1512173D02*
Y1510992D01*
G01X12410Y1543669D02*
Y1542488D01*
G01Y1537370D02*
Y1536189D01*
G01Y1540520D02*
Y1539339D01*
G01Y1534220D02*
Y1533039D01*
G01Y1527921D02*
Y1526740D01*
G01Y1531071D02*
Y1529890D01*
G01Y1524772D02*
Y1523591D01*
G01Y1518472D02*
Y1517291D01*
G01Y1521622D02*
Y1520441D01*
G01Y1515323D02*
Y1514142D01*
G01Y1512173D02*
Y1510992D01*
G01X13353Y1543413D02*
Y1542744D01*
G01Y1537114D02*
Y1536445D01*
G01Y1540264D02*
Y1539594D01*
G01Y1533965D02*
Y1533295D01*
G01Y1527665D02*
Y1526996D01*
G01Y1530815D02*
Y1530146D01*
G01Y1524516D02*
Y1523846D01*
G01Y1518217D02*
Y1517547D01*
G01Y1521366D02*
Y1520697D01*
G01Y1515067D02*
Y1514398D01*
G01Y1511917D02*
Y1511248D01*
G01X13701Y1543413D02*
Y1542744D01*
G01Y1537114D02*
Y1536445D01*
G01Y1540264D02*
Y1539594D01*
G01Y1533965D02*
Y1533295D01*
G01Y1527665D02*
Y1526996D01*
G01Y1530815D02*
Y1530146D01*
G01Y1524516D02*
Y1523846D01*
G01Y1518217D02*
Y1517547D01*
G01Y1521366D02*
Y1520697D01*
G01Y1515067D02*
Y1514398D01*
G01Y1511917D02*
Y1511248D01*
G01X13780Y1512567D02*
Y1510598D01*
G01X15945Y1512537D02*
Y1512803D01*
G01Y1511031D02*
Y1511297D01*
G01Y1510146D02*
Y1510411D01*
G01X16487Y1511474D02*
Y1512360D01*
G01X16669Y1511519D02*
Y1512316D01*
G01X18071Y1512094D02*
Y1511740D01*
G01Y1510411D02*
Y1510146D01*
G01X12057Y1512173D02*
X12287Y1511917D01*
G01X12057Y1515323D02*
X12287Y1515067D01*
G01X12057Y1518472D02*
X12287Y1518217D01*
G01X12057Y1521622D02*
X12287Y1521366D01*
G01X12057Y1524772D02*
X12287Y1524516D01*
G01X12057Y1527921D02*
X12287Y1527665D01*
G01X12057Y1531071D02*
X12287Y1530815D01*
G01X12057Y1534220D02*
X12287Y1533965D01*
G01X12057Y1537370D02*
X12287Y1537114D01*
G01X12057Y1540520D02*
X12287Y1540264D01*
G01X12057Y1543669D02*
X12287Y1543413D01*
G01X12416Y1512187D02*
X12634Y1511917D01*
G01X12416Y1515337D02*
X12634Y1515067D01*
G01X12416Y1518487D02*
X12634Y1518217D01*
G01X12416Y1521636D02*
X12634Y1521366D01*
G01X12416Y1524786D02*
X12634Y1524516D01*
G01X12416Y1527935D02*
X12634Y1527665D01*
G01X12416Y1531085D02*
X12634Y1530815D01*
G01X12416Y1534235D02*
X12634Y1533965D01*
G01X12416Y1537384D02*
X12634Y1537114D01*
G01X12416Y1540534D02*
X12634Y1540264D01*
G01X12416Y1543683D02*
X12634Y1543413D01*
G01X17709Y1510411D02*
X17392Y1510677D01*
G01X17754D02*
X18071Y1510411D01*
G01X16487Y1512360D02*
X15945Y1512537D01*
G01X16669Y1512316D02*
X17890Y1511917D01*
G01X15945Y1512803D02*
X18071Y1512094D01*
G01Y1510146D02*
X15945D01*
G01Y1510411D02*
X17709D01*
G01X17392Y1510677D02*
X17754D01*
G01X13701Y1511248D02*
X12287D01*
G01X13701Y1511917D02*
X12287D01*
G01X13701Y1514398D02*
X12287D01*
G01X13701Y1515067D02*
X12287D01*
G01X13701Y1517547D02*
X12287D01*
G01X13701Y1518217D02*
X12287D01*
G01X13701Y1520697D02*
X12287D01*
G01X13701Y1521366D02*
X12287D01*
G01X13701Y1523846D02*
X12287D01*
G01X13701Y1524516D02*
X12287D01*
G01X13701Y1526996D02*
X12287D01*
G01X13701Y1527665D02*
X12287D01*
G01X13701Y1530146D02*
X12287D01*
G01X13701Y1530815D02*
X12287D01*
G01X13701Y1533295D02*
X12287D01*
G01X13701Y1533965D02*
X12287D01*
G01X13701Y1536445D02*
X12287D01*
G01X13701Y1537114D02*
X12287D01*
G01X13701Y1539594D02*
X12287D01*
G01X13701Y1540264D02*
X12287D01*
G01X13701Y1542744D02*
X12287D01*
G01X13701Y1543413D02*
X12287D01*
G01X-14537Y1575155D02*
X-14677Y1575067D01*
G01X-13977Y1575362D02*
X-14449Y1575067D01*
G01X-14537Y1572005D02*
X-14677Y1571917D01*
G01X-13977Y1572213D02*
X-14449Y1571917D01*
G01X-14537Y1568856D02*
X-14677Y1568768D01*
G01X-13977Y1569063D02*
X-14449Y1568768D01*
G01X-14537Y1565706D02*
X-14677Y1565618D01*
G01X-13977Y1565913D02*
X-14449Y1565618D01*
G01X-14537Y1562556D02*
X-14677Y1562469D01*
G01X-13977Y1562764D02*
X-14449Y1562469D01*
G01X-14537Y1559407D02*
X-14677Y1559319D01*
G01X-13977Y1559614D02*
X-14449Y1559319D01*
G01X-14147Y1575362D02*
X-14537Y1575155D01*
G01Y1556257D02*
X-14677Y1556169D01*
G01X-13977Y1556465D02*
X-14449Y1556169D01*
G01X-14537Y1553107D02*
X-14677Y1553020D01*
G01X-13977Y1553315D02*
X-14449Y1553020D01*
G01X-14537Y1549958D02*
X-14677Y1549870D01*
G01X-13977Y1550165D02*
X-14449Y1549870D01*
G01X-14537Y1546808D02*
X-14677Y1546720D01*
G01X-13977Y1547016D02*
X-14449Y1546720D01*
G01X-14147Y1572213D02*
X-14537Y1572005D01*
G01X-14147Y1569063D02*
X-14537Y1568856D01*
G01X-14147Y1565913D02*
X-14537Y1565706D01*
G01X-14147Y1562764D02*
X-14537Y1562556D01*
G01X-14147Y1559614D02*
X-14537Y1559407D01*
G01X-14147Y1556465D02*
X-14537Y1556257D01*
G01X-14147Y1553315D02*
X-14537Y1553107D01*
G01X-14147Y1550165D02*
X-14537Y1549958D01*
G01X-14147Y1547016D02*
X-14537Y1546808D01*
G01X-20801Y1575003D02*
Y1574147D01*
G01Y1571853D02*
Y1570997D01*
G01Y1565554D02*
Y1564698D01*
G01Y1568704D02*
Y1567848D01*
G01Y1562404D02*
Y1561548D01*
G01Y1556105D02*
Y1555249D01*
G01Y1559255D02*
Y1558399D01*
G01Y1552956D02*
Y1552100D01*
G01Y1546656D02*
Y1545800D01*
G01Y1549806D02*
Y1548950D01*
G01X-19469Y1575009D02*
Y1574141D01*
G01Y1571859D02*
Y1570991D01*
G01Y1565560D02*
Y1564692D01*
G01Y1568709D02*
Y1567842D01*
G01Y1562410D02*
Y1561543D01*
G01Y1556111D02*
Y1555243D01*
G01Y1559261D02*
Y1558393D01*
G01Y1552961D02*
Y1552094D01*
G01Y1546662D02*
Y1545794D01*
G01Y1549812D02*
Y1548944D01*
G01X-18435Y1575029D02*
Y1574120D01*
G01Y1571879D02*
Y1570971D01*
G01Y1565580D02*
Y1564672D01*
G01Y1568730D02*
Y1567821D01*
G01Y1562430D02*
Y1561522D01*
G01Y1556131D02*
Y1555223D01*
G01Y1559281D02*
Y1558372D01*
G01Y1552981D02*
Y1552073D01*
G01Y1546682D02*
Y1545774D01*
G01Y1549832D02*
Y1548924D01*
G01X-18174Y1575029D02*
Y1574120D01*
G01Y1571879D02*
Y1570971D01*
G01Y1565580D02*
Y1564672D01*
G01Y1568730D02*
Y1567821D01*
G01Y1562430D02*
Y1561522D01*
G01Y1556131D02*
Y1555223D01*
G01Y1559281D02*
Y1558372D01*
G01Y1552981D02*
Y1552073D01*
G01Y1546682D02*
Y1545774D01*
G01Y1549832D02*
Y1548924D01*
G01X-16213Y1575050D02*
Y1574099D01*
G01Y1571901D02*
Y1570949D01*
G01Y1565602D02*
Y1564650D01*
G01Y1568751D02*
Y1567800D01*
G01Y1562452D02*
Y1561500D01*
G01Y1556153D02*
Y1555201D01*
G01Y1559302D02*
Y1558351D01*
G01Y1553003D02*
Y1552052D01*
G01Y1546704D02*
Y1545752D01*
G01Y1549854D02*
Y1548902D01*
G01X-15985Y1575050D02*
Y1574099D01*
G01Y1571901D02*
Y1570949D01*
G01Y1565602D02*
Y1564650D01*
G01Y1568751D02*
Y1567800D01*
G01Y1562452D02*
Y1561500D01*
G01Y1556153D02*
Y1555201D01*
G01Y1559302D02*
Y1558351D01*
G01Y1553003D02*
Y1552052D01*
G01Y1546704D02*
Y1545752D01*
G01Y1549854D02*
Y1548902D01*
G01X-14537Y1575155D02*
Y1573995D01*
G01Y1572005D02*
Y1570845D01*
G01Y1565706D02*
Y1564546D01*
G01Y1568856D02*
Y1567696D01*
G01Y1562556D02*
Y1561396D01*
G01Y1556257D02*
Y1555097D01*
G01Y1559407D02*
Y1558247D01*
G01Y1553107D02*
Y1551948D01*
G01Y1546808D02*
Y1545648D01*
G01Y1549958D02*
Y1548798D01*
G01X-13009Y1575362D02*
Y1573787D01*
G01Y1572213D02*
Y1570638D01*
G01Y1565913D02*
Y1564339D01*
G01Y1569063D02*
Y1567488D01*
G01Y1562764D02*
Y1561189D01*
G01Y1556465D02*
Y1554890D01*
G01Y1559614D02*
Y1558039D01*
G01Y1553315D02*
Y1551740D01*
G01Y1547016D02*
Y1545441D01*
G01Y1550165D02*
Y1548591D01*
G01X315Y1575756D02*
Y1575165D01*
G01Y1573984D02*
Y1573394D01*
G01Y1569457D02*
Y1568866D01*
G01Y1572606D02*
Y1572016D01*
G01Y1570835D02*
Y1570244D01*
G01Y1566307D02*
Y1565717D01*
G01Y1564535D02*
Y1563945D01*
G01Y1567685D02*
Y1567094D01*
G01Y1560008D02*
Y1559417D01*
G01Y1563157D02*
Y1562567D01*
G01Y1561386D02*
Y1560795D01*
G01Y1556858D02*
Y1556268D01*
G01Y1558236D02*
Y1557646D01*
G01Y1550559D02*
Y1549969D01*
G01Y1553709D02*
Y1553118D01*
G01Y1551937D02*
Y1551346D01*
G01Y1555087D02*
Y1554496D01*
G01Y1547409D02*
Y1546819D01*
G01Y1548787D02*
Y1548197D01*
G01X512Y1575756D02*
Y1575165D01*
G01Y1573984D02*
Y1573394D01*
G01Y1569457D02*
Y1568866D01*
G01Y1572606D02*
Y1572016D01*
G01Y1570835D02*
Y1570244D01*
G01Y1566307D02*
Y1565717D01*
G01Y1564535D02*
Y1563945D01*
G01Y1567685D02*
Y1567094D01*
G01Y1560008D02*
Y1559417D01*
G01Y1563157D02*
Y1562567D01*
G01Y1561386D02*
Y1560795D01*
G01Y1556858D02*
Y1556268D01*
G01Y1558236D02*
Y1557646D01*
G01Y1550559D02*
Y1549969D01*
G01Y1553709D02*
Y1553118D01*
G01Y1551937D02*
Y1551346D01*
G01Y1555087D02*
Y1554496D01*
G01Y1547409D02*
Y1546819D01*
G01Y1548787D02*
Y1548197D01*
G01X709Y1575165D02*
Y1573984D01*
G01Y1572016D02*
Y1570835D01*
G01Y1565717D02*
Y1564535D01*
G01Y1568866D02*
Y1567685D01*
G01Y1562567D02*
Y1561386D01*
G01Y1556268D02*
Y1555087D01*
G01Y1559417D02*
Y1558236D01*
G01Y1553118D02*
Y1551937D01*
G01Y1546819D02*
Y1545638D01*
G01Y1549969D02*
Y1548787D01*
G01X1074Y1575165D02*
Y1573984D01*
G01Y1572016D02*
Y1570835D01*
G01Y1565717D02*
Y1564535D01*
G01Y1568866D02*
Y1567685D01*
G01Y1562567D02*
Y1561386D01*
G01Y1556268D02*
Y1555087D01*
G01Y1559417D02*
Y1558236D01*
G01Y1553118D02*
Y1551937D01*
G01Y1546819D02*
Y1545638D01*
G01Y1549969D02*
Y1548787D01*
G01X1184Y1575165D02*
Y1573984D01*
G01Y1572016D02*
Y1570835D01*
G01Y1565717D02*
Y1564535D01*
G01Y1568866D02*
Y1567685D01*
G01Y1562567D02*
Y1561386D01*
G01Y1556268D02*
Y1555087D01*
G01Y1559417D02*
Y1558236D01*
G01Y1553118D02*
Y1551937D01*
G01Y1546819D02*
Y1545638D01*
G01Y1549969D02*
Y1548787D01*
G01X9965Y1575165D02*
Y1573984D01*
G01Y1572016D02*
Y1570835D01*
G01Y1565717D02*
Y1564535D01*
G01Y1568866D02*
Y1567685D01*
G01Y1562567D02*
Y1561386D01*
G01Y1556268D02*
Y1555087D01*
G01Y1559417D02*
Y1558236D01*
G01Y1553118D02*
Y1551937D01*
G01Y1546819D02*
Y1545638D01*
G01Y1549969D02*
Y1548787D01*
G01X10075Y1575165D02*
Y1573984D01*
G01Y1572016D02*
Y1570835D01*
G01Y1565717D02*
Y1564535D01*
G01Y1568866D02*
Y1567685D01*
G01Y1562567D02*
Y1561386D01*
G01Y1556268D02*
Y1555087D01*
G01Y1559417D02*
Y1558236D01*
G01Y1553118D02*
Y1551937D01*
G01Y1546819D02*
Y1545638D01*
G01Y1549969D02*
Y1548787D01*
G01X-14537Y1545648D02*
X-14147Y1545441D01*
G01X-14677Y1545736D02*
X-14537Y1545648D01*
G01X-14449Y1545736D02*
X-13977Y1545441D01*
G01X-14677Y1548886D02*
X-14537Y1548798D01*
G01X-14449Y1548886D02*
X-13977Y1548591D01*
G01X-14677Y1552035D02*
X-14537Y1551948D01*
G01X-14449Y1552035D02*
X-13977Y1551740D01*
G01X-14677Y1555185D02*
X-14537Y1555097D01*
G01X-14449Y1555185D02*
X-13977Y1554890D01*
G01X-14677Y1558335D02*
X-14537Y1558247D01*
G01X-14449Y1558335D02*
X-13977Y1558039D01*
G01X-14677Y1561484D02*
X-14537Y1561396D01*
G01X-14449Y1561484D02*
X-13977Y1561189D01*
G01X-14677Y1564634D02*
X-14537Y1564546D01*
G01X-14449Y1564634D02*
X-13977Y1564339D01*
G01X-14677Y1567783D02*
X-14537Y1567696D01*
G01X-14449Y1567783D02*
X-13977Y1567488D01*
G01X-14677Y1570933D02*
X-14537Y1570845D01*
G01X-14449Y1570933D02*
X-13977Y1570638D01*
G01X-14677Y1574083D02*
X-14537Y1573995D01*
G01X-14449Y1574083D02*
X-13977Y1573787D01*
G01X-14537Y1548798D02*
X-14147Y1548591D01*
G01X-14537Y1551948D02*
X-14147Y1551740D01*
G01X-14537Y1555097D02*
X-14147Y1554890D01*
G01X-14537Y1558247D02*
X-14147Y1558039D01*
G01X-14537Y1561396D02*
X-14147Y1561189D01*
G01X-14537Y1564546D02*
X-14147Y1564339D01*
G01X-14537Y1567696D02*
X-14147Y1567488D01*
G01X-14537Y1570845D02*
X-14147Y1570638D01*
G01X-14537Y1573995D02*
X-14147Y1573787D01*
G01X-19469Y1545789D02*
X-20801Y1545800D01*
G01X-15985Y1545752D02*
X-18435Y1545774D01*
G01X-15985Y1545752D02*
X-14449Y1545736D01*
G01X-18435Y1545774D02*
X-20801Y1545800D01*
G01X-19469Y1545789D02*
X-16213Y1545752D01*
G01X-18174Y1545774D02*
X-14677Y1545736D01*
G01X-19469Y1546668D02*
X-18174Y1546682D01*
G01X-18435D02*
X-20801Y1546656D01*
G01X-18174Y1546682D02*
X-17126Y1546694D01*
G01X-19469Y1549818D02*
X-18174Y1549832D01*
G01X-18435D02*
X-20801Y1549806D01*
G01X-18174Y1549832D02*
X-17126Y1549843D01*
G01X-19469Y1552967D02*
X-18174Y1552981D01*
G01X-18435D02*
X-20801Y1552956D01*
G01X-18174Y1552981D02*
X-17126Y1552993D01*
G01X-19469Y1556117D02*
X-18174Y1556131D01*
G01X-18435D02*
X-20801Y1556105D01*
G01X-18174Y1556131D02*
X-17126Y1556143D01*
G01X-19469Y1559267D02*
X-18174Y1559281D01*
G01X-18435D02*
X-20801Y1559255D01*
G01X-18174Y1559281D02*
X-17126Y1559292D01*
G01X-19469Y1562416D02*
X-18174Y1562430D01*
G01X-18435D02*
X-20801Y1562404D01*
G01X-18174Y1562430D02*
X-17126Y1562442D01*
G01X-19469Y1565566D02*
X-18174Y1565580D01*
G01X-18435D02*
X-20801Y1565554D01*
G01X-18174Y1565580D02*
X-17126Y1565591D01*
G01X-19469Y1568715D02*
X-18174Y1568730D01*
G01X-18435D02*
X-20801Y1568704D01*
G01X-18174Y1568730D02*
X-17126Y1568741D01*
G01X-19469Y1571865D02*
X-18174Y1571879D01*
G01X-18435D02*
X-20801Y1571853D01*
G01X-18174Y1571879D02*
X-17126Y1571891D01*
G01X-19469Y1575015D02*
X-18174Y1575029D01*
G01X-18435D02*
X-20801Y1575003D01*
G01X-18174Y1575029D02*
X-17126Y1575040D01*
G01X-15985Y1546704D02*
X-14449Y1546720D01*
G01X-14677D02*
X-18174Y1546682D01*
G01X-14677Y1546720D02*
X-16213Y1546704D01*
G01X-15985Y1549854D02*
X-14449Y1549870D01*
G01X-14677D02*
X-18174Y1549832D01*
G01X-14677Y1549870D02*
X-16213Y1549854D01*
G01X-15985Y1553003D02*
X-14449Y1553020D01*
G01X-14677D02*
X-18174Y1552981D01*
G01X-14677Y1553020D02*
X-16213Y1553003D01*
G01X-15985Y1556153D02*
X-14449Y1556169D01*
G01X-14677D02*
X-18174Y1556131D01*
G01X-14677Y1556169D02*
X-16213Y1556153D01*
G01X-15985Y1559302D02*
X-14449Y1559319D01*
G01X-14677D02*
X-18174Y1559281D01*
G01X-14677Y1559319D02*
X-16213Y1559302D01*
G01X-15985Y1562452D02*
X-14449Y1562469D01*
G01X-14677D02*
X-18174Y1562430D01*
G01X-14677Y1562469D02*
X-16213Y1562452D01*
G01X-15985Y1565602D02*
X-14449Y1565618D01*
G01X-14677D02*
X-18174Y1565580D01*
G01X-14677Y1565618D02*
X-16213Y1565602D01*
G01X-15985Y1568751D02*
X-14449Y1568768D01*
G01X-14677D02*
X-18174Y1568730D01*
G01X-14677Y1568768D02*
X-16213Y1568751D01*
G01X-15985Y1571901D02*
X-14449Y1571917D01*
G01X-14677D02*
X-18174Y1571879D01*
G01X-14677Y1571917D02*
X-16213Y1571901D01*
G01X-15985Y1575050D02*
X-14449Y1575067D01*
G01X-14677D02*
X-18174Y1575029D01*
G01X-14677Y1575067D02*
X-16213Y1575050D01*
G01X-19469Y1546668D02*
X-20801Y1546656D01*
G01X-19469Y1549818D02*
X-20801Y1549806D01*
G01X-19469Y1552967D02*
X-20801Y1552956D01*
G01X-19469Y1556117D02*
X-20801Y1556105D01*
G01X-19469Y1559267D02*
X-20801Y1559255D01*
G01X-19469Y1562416D02*
X-20801Y1562404D01*
G01X-19469Y1565566D02*
X-20801Y1565554D01*
G01X-19469Y1568715D02*
X-20801Y1568704D01*
G01X-19469Y1571865D02*
X-20801Y1571853D01*
G01X-19469Y1575015D02*
X-20801Y1575003D01*
G01X-15985Y1546704D02*
X-17126Y1546694D01*
G01D02*
X-18435Y1546682D01*
G01X-15985Y1549854D02*
X-17126Y1549843D01*
G01D02*
X-18435Y1549832D01*
G01X-15985Y1553003D02*
X-17126Y1552993D01*
G01D02*
X-18435Y1552981D01*
G01X-15985Y1556153D02*
X-17126Y1556143D01*
G01D02*
X-18435Y1556131D01*
G01X-15985Y1559302D02*
X-17126Y1559292D01*
G01D02*
X-18435Y1559281D01*
G01X-15985Y1562452D02*
X-17126Y1562442D01*
G01D02*
X-18435Y1562430D01*
G01X-15985Y1565602D02*
X-17126Y1565591D01*
G01D02*
X-18435Y1565580D01*
G01X-15985Y1568751D02*
X-17126Y1568741D01*
G01D02*
X-18435Y1568730D01*
G01X-15985Y1571901D02*
X-17126Y1571891D01*
G01D02*
X-18435Y1571879D01*
G01X-15985Y1575050D02*
X-17126Y1575040D01*
G01D02*
X-18435Y1575029D01*
G01X-13009Y1545441D02*
X-14147D01*
G01X12410Y1545638D02*
X315D01*
G01X-14449Y1545736D02*
X-14677D01*
G01X-15985Y1545752D02*
X-16213D01*
G01X-18174Y1545774D02*
X-18435D01*
G01X-18174Y1546682D02*
X-18435D01*
G01X-15985Y1546704D02*
X-16213D01*
G01X-14449Y1546720D02*
X-14677D01*
G01X12410Y1546819D02*
X315D01*
G01X-13009Y1547016D02*
X-14147D01*
G01X512Y1547409D02*
X0D01*
G01X512Y1548197D02*
X0D01*
G01X-13009Y1548591D02*
X-14147D01*
G01X12410Y1548787D02*
X315D01*
G01X-14449Y1548886D02*
X-14677D01*
G01X-15985Y1548902D02*
X-16213D01*
G01X-18174Y1548924D02*
X-18435D01*
G01X-18174Y1549832D02*
X-18435D01*
G01X-15985Y1549854D02*
X-16213D01*
G01X-14449Y1549870D02*
X-14677D01*
G01X12410Y1549969D02*
X315D01*
G01X-13009Y1550165D02*
X-14147D01*
G01X512Y1550559D02*
X0D01*
G01X512Y1551346D02*
X0D01*
G01X-13009Y1551740D02*
X-14147D01*
G01X12410Y1551937D02*
X315D01*
G01X-14449Y1552035D02*
X-14677D01*
G01X-15985Y1552052D02*
X-16213D01*
G01X-18174Y1552073D02*
X-18435D01*
G01X-18174Y1552981D02*
X-18435D01*
G01X-16213Y1553003D02*
X-15985D01*
G01X-14449Y1553020D02*
X-14677D01*
G01X12410Y1553118D02*
X315D01*
G01X-13009Y1553315D02*
X-14147D01*
G01X512Y1553709D02*
X0D01*
G01X512Y1554496D02*
X0D01*
G01X-13009Y1554890D02*
X-14147D01*
G01X12410Y1555087D02*
X315D01*
G01X-14449Y1555185D02*
X-14677D01*
G01X-15985Y1555201D02*
X-16213D01*
G01X-18174Y1555223D02*
X-18435D01*
G01X-18174Y1556131D02*
X-18435D01*
G01X-15985Y1556153D02*
X-16213D01*
G01X-14449Y1556169D02*
X-14677D01*
G01X12410Y1556268D02*
X315D01*
G01X-13009Y1556465D02*
X-14147D01*
G01X512Y1556858D02*
X0D01*
G01X512Y1557646D02*
X0D01*
G01X-13009Y1558039D02*
X-14147D01*
G01X12410Y1558236D02*
X315D01*
G01X-14449Y1558335D02*
X-14677D01*
G01X-15985Y1558351D02*
X-16213D01*
G01X-18174Y1558372D02*
X-18435D01*
G01X-18174Y1559281D02*
X-18435D01*
G01X-15985Y1559302D02*
X-16213D01*
G01X-14449Y1559319D02*
X-14677D01*
G01X12410Y1559417D02*
X315D01*
G01X-13009Y1559614D02*
X-14147D01*
G01X512Y1560008D02*
X0D01*
G01X512Y1560795D02*
X0D01*
G01X-13009Y1561189D02*
X-14147D01*
G01X12410Y1561386D02*
X315D01*
G01X-14449Y1561484D02*
X-14677D01*
G01X-15985Y1561500D02*
X-16213D01*
G01X-18174Y1561522D02*
X-18435D01*
G01X-18174Y1562430D02*
X-18435D01*
G01X-15985Y1562452D02*
X-16213D01*
G01X-14449Y1562469D02*
X-14677D01*
G01X12410Y1562567D02*
X315D01*
G01X-13009Y1562764D02*
X-14147D01*
G01X512Y1563157D02*
X0D01*
G01X512Y1563945D02*
X0D01*
G01X-13009Y1564339D02*
X-14147D01*
G01X12410Y1564535D02*
X315D01*
G01X-14449Y1564634D02*
X-14677D01*
G01X-15985Y1564650D02*
X-16213D01*
G01X-18174Y1564672D02*
X-18435D01*
G01X-18174Y1565580D02*
X-18435D01*
G01X-15985Y1565602D02*
X-16213D01*
G01X-14449Y1565618D02*
X-14677D01*
G01X12410Y1565717D02*
X315D01*
G01X-13009Y1565913D02*
X-14147D01*
G01X512Y1566307D02*
X0D01*
G01X512Y1567094D02*
X0D01*
G01X-13009Y1567488D02*
X-14147D01*
G01X12410Y1567685D02*
X315D01*
G01X-14449Y1567783D02*
X-14677D01*
G01X-15985Y1567800D02*
X-16213D01*
G01X-18174Y1567821D02*
X-18435D01*
G01X-18174Y1568730D02*
X-18435D01*
G01X-15985Y1568751D02*
X-16213D01*
G01X-14449Y1568768D02*
X-14677D01*
G01X12410Y1568866D02*
X315D01*
G01X-13009Y1569063D02*
X-14147D01*
G01X512Y1569457D02*
X0D01*
G01X512Y1570244D02*
X0D01*
G01X-13009Y1570638D02*
X-14147D01*
G01X12410Y1570835D02*
X315D01*
G01X-14449Y1570933D02*
X-14677D01*
G01X-15985Y1570949D02*
X-16213D01*
G01X-18174Y1570971D02*
X-18435D01*
G01X-18174Y1571879D02*
X-18435D01*
G01X-15985Y1571901D02*
X-16213D01*
G01X-14449Y1571917D02*
X-14677D01*
G01X12410Y1572016D02*
X315D01*
G01X-13009Y1572213D02*
X-14147D01*
G01X512Y1572606D02*
X0D01*
G01X512Y1573394D02*
X0D01*
G01X-13009Y1573787D02*
X-14147D01*
G01X12410Y1573984D02*
X315D01*
G01X-14449Y1574083D02*
X-14677D01*
G01X-15985Y1574099D02*
X-16213D01*
G01X-18174Y1574120D02*
X-18435D01*
G01X-18174Y1575029D02*
X-18435D01*
G01X-15985Y1575050D02*
X-16213D01*
G01X-14449Y1575067D02*
X-14677D01*
G01X12410Y1575165D02*
X315D01*
G01X-13009Y1575362D02*
X-14147D01*
G01X-19469Y1548938D02*
X-20801Y1548950D01*
G01X-15985Y1548902D02*
X-18435Y1548924D01*
G01X-19469Y1552088D02*
X-20801Y1552100D01*
G01X-15985Y1552052D02*
X-18435Y1552073D01*
G01X-19469Y1555237D02*
X-20801Y1555249D01*
G01X-15985Y1555201D02*
X-18435Y1555223D01*
G01X-19469Y1558387D02*
X-20801Y1558399D01*
G01X-15985Y1558351D02*
X-18435Y1558372D01*
G01X-19469Y1561537D02*
X-20801Y1561548D01*
G01X-15985Y1561500D02*
X-18435Y1561522D01*
G01X-19469Y1564686D02*
X-20801Y1564698D01*
G01X-15985Y1564650D02*
X-18435Y1564672D01*
G01X-19469Y1567836D02*
X-20801Y1567848D01*
G01X-15985Y1567800D02*
X-18435Y1567821D01*
G01X-19469Y1570985D02*
X-20801Y1570997D01*
G01X-15985Y1570949D02*
X-18435Y1570971D01*
G01X-19469Y1574135D02*
X-20801Y1574147D01*
G01X-15985Y1574099D02*
X-18435Y1574120D01*
G01X-15985Y1548902D02*
X-14449Y1548886D01*
G01X-15985Y1552052D02*
X-14449Y1552035D01*
G01X-15985Y1555201D02*
X-14449Y1555185D01*
G01X-15985Y1558351D02*
X-14449Y1558335D01*
G01X-15985Y1561500D02*
X-14449Y1561484D01*
G01X-15985Y1564650D02*
X-14449Y1564634D01*
G01X-15985Y1567800D02*
X-14449Y1567783D01*
G01X-15985Y1570949D02*
X-14449Y1570933D01*
G01X-15985Y1574099D02*
X-14449Y1574083D01*
G01X-18435Y1548924D02*
X-20801Y1548950D01*
G01X-18435Y1552073D02*
X-20801Y1552100D01*
G01X-18435Y1555223D02*
X-20801Y1555249D01*
G01X-18435Y1558372D02*
X-20801Y1558399D01*
G01X-18435Y1561522D02*
X-20801Y1561548D01*
G01X-18435Y1564672D02*
X-20801Y1564698D01*
G01X-18435Y1567821D02*
X-20801Y1567848D01*
G01X-18435Y1570971D02*
X-20801Y1570997D01*
G01X-18435Y1574120D02*
X-20801Y1574147D01*
G01X-19469Y1548938D02*
X-16213Y1548902D01*
G01X-18174Y1548924D02*
X-14677Y1548886D01*
G01X-19469Y1552088D02*
X-16213Y1552052D01*
G01X-18174Y1552073D02*
X-14677Y1552035D01*
G01X-19469Y1555237D02*
X-16213Y1555201D01*
G01X-18174Y1555223D02*
X-14677Y1555185D01*
G01X-19469Y1558387D02*
X-16213Y1558351D01*
G01X-18174Y1558372D02*
X-14677Y1558335D01*
G01X-19469Y1561537D02*
X-16213Y1561500D01*
G01X-18174Y1561522D02*
X-14677Y1561484D01*
G01X-19469Y1564686D02*
X-16213Y1564650D01*
G01X-18174Y1564672D02*
X-14677Y1564634D01*
G01X-19469Y1567836D02*
X-16213Y1567800D01*
G01X-18174Y1567821D02*
X-14677Y1567783D01*
G01X-19469Y1570985D02*
X-16213Y1570949D01*
G01X-18174Y1570971D02*
X-14677Y1570933D01*
G01X-19469Y1574135D02*
X-16213Y1574099D01*
G01X-18174Y1574120D02*
X-14677Y1574083D01*
G01X-14537Y1543659D02*
X-14677Y1543571D01*
G01X-13977Y1543866D02*
X-14449Y1543571D01*
G01X-14537Y1540509D02*
X-14677Y1540421D01*
G01X-13977Y1540717D02*
X-14449Y1540421D01*
G01X-14537Y1537359D02*
X-14677Y1537272D01*
G01X-13977Y1537567D02*
X-14449Y1537272D01*
G01X-14537Y1534210D02*
X-14677Y1534122D01*
G01X-13977Y1534417D02*
X-14449Y1534122D01*
G01X-14537Y1531060D02*
X-14677Y1530972D01*
G01X-13977Y1531268D02*
X-14449Y1530972D01*
G01X-14537Y1527911D02*
X-14677Y1527823D01*
G01X-13977Y1528118D02*
X-14449Y1527823D01*
G01X-14537Y1524761D02*
X-14677Y1524673D01*
G01X-13977Y1524969D02*
X-14449Y1524673D01*
G01X-14537Y1521611D02*
X-14677Y1521524D01*
G01X-13977Y1521819D02*
X-14449Y1521524D01*
G01X-14537Y1518462D02*
X-14677Y1518374D01*
G01X-13977Y1518669D02*
X-14449Y1518374D01*
G01X-14537Y1515312D02*
X-14677Y1515224D01*
G01X-13977Y1515520D02*
X-14449Y1515224D01*
G01X-14537Y1512163D02*
X-14677Y1512075D01*
G01X-13977Y1512370D02*
X-14449Y1512075D01*
G01X-27981Y1511583D02*
X-30709Y1510008D01*
G01X-14147Y1543866D02*
X-14537Y1543659D01*
G01X-14147Y1540717D02*
X-14537Y1540509D01*
G01X-14147Y1537567D02*
X-14537Y1537359D01*
G01X-14147Y1534417D02*
X-14537Y1534210D01*
G01X-14147Y1531268D02*
X-14537Y1531060D01*
G01X-14147Y1528118D02*
X-14537Y1527911D01*
G01X-14147Y1524969D02*
X-14537Y1524761D01*
G01X-14147Y1521819D02*
X-14537Y1521611D01*
G01X-14147Y1518669D02*
X-14537Y1518462D01*
G01X-14147Y1515520D02*
X-14537Y1515312D01*
G01X-14147Y1512370D02*
X-14537Y1512163D01*
G01X-26772Y1507646D02*
X-30709Y1505677D01*
G01Y1837961D02*
Y1509614D01*
G01X-26772Y1650953D02*
Y1509614D01*
G01X-20801Y1543507D02*
Y1542651D01*
G01Y1537207D02*
Y1536352D01*
G01Y1540357D02*
Y1539501D01*
G01Y1534058D02*
Y1533202D01*
G01Y1527759D02*
Y1526903D01*
G01Y1530908D02*
Y1530052D01*
G01Y1524609D02*
Y1523753D01*
G01Y1518310D02*
Y1517454D01*
G01Y1521459D02*
Y1520604D01*
G01Y1515160D02*
Y1514304D01*
G01Y1512011D02*
Y1511155D01*
G01X-19469Y1543513D02*
Y1542645D01*
G01Y1537213D02*
Y1536346D01*
G01Y1540363D02*
Y1539495D01*
G01Y1534064D02*
Y1533196D01*
G01Y1527765D02*
Y1526897D01*
G01Y1530914D02*
Y1530046D01*
G01Y1524615D02*
Y1523747D01*
G01Y1518316D02*
Y1517448D01*
G01Y1521465D02*
Y1520598D01*
G01Y1515166D02*
Y1514298D01*
G01Y1512017D02*
Y1511149D01*
G01X-18435Y1543533D02*
Y1542624D01*
G01Y1537233D02*
Y1536325D01*
G01Y1540383D02*
Y1539475D01*
G01Y1534084D02*
Y1533176D01*
G01Y1527785D02*
Y1526876D01*
G01Y1530934D02*
Y1530026D01*
G01Y1524635D02*
Y1523727D01*
G01Y1518336D02*
Y1517428D01*
G01Y1521485D02*
Y1520577D01*
G01Y1515186D02*
Y1514278D01*
G01Y1512037D02*
Y1511128D01*
G01X-18174Y1543533D02*
Y1542624D01*
G01Y1537233D02*
Y1536325D01*
G01Y1540383D02*
Y1539475D01*
G01Y1534084D02*
Y1533176D01*
G01Y1527785D02*
Y1526876D01*
G01Y1530934D02*
Y1530026D01*
G01Y1524635D02*
Y1523727D01*
G01Y1518336D02*
Y1517428D01*
G01Y1521485D02*
Y1520577D01*
G01Y1515186D02*
Y1514278D01*
G01Y1512037D02*
Y1511128D01*
G01X-16213Y1543554D02*
Y1542603D01*
G01Y1537255D02*
Y1536304D01*
G01Y1540405D02*
Y1539453D01*
G01Y1534106D02*
Y1533154D01*
G01Y1527806D02*
Y1526855D01*
G01Y1530956D02*
Y1530004D01*
G01Y1524657D02*
Y1523705D01*
G01Y1518357D02*
Y1517406D01*
G01Y1521507D02*
Y1520556D01*
G01Y1515208D02*
Y1514256D01*
G01Y1512058D02*
Y1511107D01*
G01X-15985Y1543554D02*
Y1542603D01*
G01Y1537255D02*
Y1536304D01*
G01Y1540405D02*
Y1539453D01*
G01Y1534106D02*
Y1533154D01*
G01Y1527806D02*
Y1526855D01*
G01Y1530956D02*
Y1530004D01*
G01Y1524657D02*
Y1523705D01*
G01Y1518357D02*
Y1517406D01*
G01Y1521507D02*
Y1520556D01*
G01Y1515208D02*
Y1514256D01*
G01Y1512058D02*
Y1511107D01*
G01X-14537Y1543659D02*
Y1542499D01*
G01Y1537359D02*
Y1536200D01*
G01Y1540509D02*
Y1539349D01*
G01Y1534210D02*
Y1533050D01*
G01Y1527911D02*
Y1526751D01*
G01Y1531060D02*
Y1529900D01*
G01Y1524761D02*
Y1523601D01*
G01Y1518462D02*
Y1517302D01*
G01Y1521611D02*
Y1520452D01*
G01Y1515312D02*
Y1514152D01*
G01Y1512163D02*
Y1511003D01*
G01X-13009Y1543866D02*
Y1542291D01*
G01Y1537567D02*
Y1535992D01*
G01Y1540717D02*
Y1539142D01*
G01Y1534417D02*
Y1532843D01*
G01Y1528118D02*
Y1526543D01*
G01Y1531268D02*
Y1529693D01*
G01Y1524969D02*
Y1523394D01*
G01Y1518669D02*
Y1517094D01*
G01Y1521819D02*
Y1520244D01*
G01Y1515520D02*
Y1513945D01*
G01Y1512370D02*
Y1510795D01*
G01X-7283Y1650953D02*
Y1507646D01*
G01X315Y1544260D02*
Y1543669D01*
G01Y1542488D02*
Y1541898D01*
G01Y1545638D02*
Y1545047D01*
G01Y1537961D02*
Y1537370D01*
G01Y1541110D02*
Y1540520D01*
G01Y1539339D02*
Y1538748D01*
G01Y1534811D02*
Y1534220D01*
G01Y1533039D02*
Y1532449D01*
G01Y1536189D02*
Y1535598D01*
G01Y1528512D02*
Y1527921D01*
G01Y1531661D02*
Y1531071D01*
G01Y1529890D02*
Y1529299D01*
G01Y1525362D02*
Y1524772D01*
G01Y1523591D02*
Y1523000D01*
G01Y1526740D02*
Y1526150D01*
G01Y1519063D02*
Y1518472D01*
G01Y1522213D02*
Y1521622D01*
G01Y1520441D02*
Y1519850D01*
G01Y1515913D02*
Y1515323D01*
G01Y1514142D02*
Y1513551D01*
G01Y1517291D02*
Y1516701D01*
G01Y1512764D02*
Y1512173D01*
G01Y1510992D02*
Y1510402D01*
G01X512Y1544260D02*
Y1543669D01*
G01Y1542488D02*
Y1541898D01*
G01Y1545638D02*
Y1545047D01*
G01Y1537961D02*
Y1537370D01*
G01Y1541110D02*
Y1540520D01*
G01Y1539339D02*
Y1538748D01*
G01Y1534811D02*
Y1534220D01*
G01Y1533039D02*
Y1532449D01*
G01Y1536189D02*
Y1535598D01*
G01Y1528512D02*
Y1527921D01*
G01Y1531661D02*
Y1531071D01*
G01Y1529890D02*
Y1529299D01*
G01Y1525362D02*
Y1524772D01*
G01Y1523591D02*
Y1523000D01*
G01Y1526740D02*
Y1526150D01*
G01Y1519063D02*
Y1518472D01*
G01Y1522213D02*
Y1521622D01*
G01Y1520441D02*
Y1519850D01*
G01Y1515913D02*
Y1515323D01*
G01Y1514142D02*
Y1513551D01*
G01Y1517291D02*
Y1516701D01*
G01Y1512764D02*
Y1512173D01*
G01Y1510992D02*
Y1510402D01*
G01X709Y1543669D02*
Y1542488D01*
G01Y1537370D02*
Y1536189D01*
G01Y1540520D02*
Y1539339D01*
G01Y1534220D02*
Y1533039D01*
G01Y1527921D02*
Y1526740D01*
G01Y1531071D02*
Y1529890D01*
G01Y1524772D02*
Y1523591D01*
G01Y1518472D02*
Y1517291D01*
G01Y1521622D02*
Y1520441D01*
G01Y1515323D02*
Y1514142D01*
G01Y1512173D02*
Y1510992D01*
G01X1074Y1543669D02*
Y1542488D01*
G01Y1537370D02*
Y1536189D01*
G01Y1540520D02*
Y1539339D01*
G01Y1534220D02*
Y1533039D01*
G01Y1527921D02*
Y1526740D01*
G01Y1531071D02*
Y1529890D01*
G01Y1524772D02*
Y1523591D01*
G01Y1518472D02*
Y1517291D01*
G01Y1521622D02*
Y1520441D01*
G01Y1515323D02*
Y1514142D01*
G01Y1512173D02*
Y1510992D01*
G01X1184Y1543669D02*
Y1542488D01*
G01Y1537370D02*
Y1536189D01*
G01Y1540520D02*
Y1539339D01*
G01Y1534220D02*
Y1533039D01*
G01Y1527921D02*
Y1526740D01*
G01Y1531071D02*
Y1529890D01*
G01Y1524772D02*
Y1523591D01*
G01Y1518472D02*
Y1517291D01*
G01Y1521622D02*
Y1520441D01*
G01Y1515323D02*
Y1514142D01*
G01Y1512173D02*
Y1510992D01*
G01X3937Y1510598D02*
Y1512567D01*
G01X9965Y1543669D02*
Y1542488D01*
G01Y1537370D02*
Y1536189D01*
G01Y1540520D02*
Y1539339D01*
G01Y1534220D02*
Y1533039D01*
G01Y1527921D02*
Y1526740D01*
G01Y1531071D02*
Y1529890D01*
G01Y1524772D02*
Y1523591D01*
G01Y1518472D02*
Y1517291D01*
G01Y1521622D02*
Y1520441D01*
G01Y1515323D02*
Y1514142D01*
G01Y1512173D02*
Y1510992D01*
G01X10075Y1543669D02*
Y1542488D01*
G01Y1537370D02*
Y1536189D01*
G01Y1540520D02*
Y1539339D01*
G01Y1534220D02*
Y1533039D01*
G01Y1527921D02*
Y1526740D01*
G01Y1531071D02*
Y1529890D01*
G01Y1524772D02*
Y1523591D01*
G01Y1518472D02*
Y1517291D01*
G01Y1521622D02*
Y1520441D01*
G01Y1515323D02*
Y1514142D01*
G01Y1512173D02*
Y1510992D01*
G01X-14677Y1511091D02*
X-14537Y1511003D01*
G01X-14449Y1511091D02*
X-13977Y1510795D01*
G01X-14677Y1514240D02*
X-14537Y1514152D01*
G01X-14449Y1514240D02*
X-13977Y1513945D01*
G01X-14677Y1517390D02*
X-14537Y1517302D01*
G01X-14449Y1517390D02*
X-13977Y1517094D01*
G01X-14537Y1511003D02*
X-14147Y1510795D01*
G01X-14537Y1514152D02*
X-14147Y1513945D01*
G01X-14537Y1517302D02*
X-14147Y1517094D01*
G01X-14537Y1520452D02*
X-14147Y1520244D01*
G01X-14537Y1523601D02*
X-14147Y1523394D01*
G01X-14537Y1526751D02*
X-14147Y1526543D01*
G01X-14537Y1529900D02*
X-14147Y1529693D01*
G01X-14537Y1533050D02*
X-14147Y1532843D01*
G01X-14537Y1536200D02*
X-14147Y1535992D01*
G01X-14537Y1539349D02*
X-14147Y1539142D01*
G01X-14537Y1542499D02*
X-14147Y1542291D01*
G01X-30709Y1513157D02*
X-27981Y1511583D01*
G01X-14677Y1520539D02*
X-14537Y1520452D01*
G01X-14449Y1520539D02*
X-13977Y1520244D01*
G01X-14677Y1523689D02*
X-14537Y1523601D01*
G01X-14449Y1523689D02*
X-13977Y1523394D01*
G01X-14677Y1526839D02*
X-14537Y1526751D01*
G01X-14449Y1526839D02*
X-13977Y1526543D01*
G01X-14677Y1529988D02*
X-14537Y1529900D01*
G01X-14449Y1529988D02*
X-13977Y1529693D01*
G01X-14677Y1533138D02*
X-14537Y1533050D01*
G01X-14449Y1533138D02*
X-13977Y1532843D01*
G01X-14677Y1536287D02*
X-14537Y1536200D01*
G01X-14449Y1536287D02*
X-13977Y1535992D01*
G01X-14677Y1539437D02*
X-14537Y1539349D01*
G01X-14449Y1539437D02*
X-13977Y1539142D01*
G01X-14677Y1542587D02*
X-14537Y1542499D01*
G01X-14449Y1542587D02*
X-13977Y1542291D01*
G01X-19469Y1512022D02*
X-18174Y1512037D01*
G01X-18435D02*
X-20801Y1512011D01*
G01X-18174Y1512037D02*
X-17126Y1512048D01*
G01X-19469Y1515172D02*
X-18174Y1515186D01*
G01X-18435D02*
X-20801Y1515160D01*
G01X-18174Y1515186D02*
X-17126Y1515198D01*
G01X-19469Y1518322D02*
X-18174Y1518336D01*
G01X-18435D02*
X-20801Y1518310D01*
G01X-18174Y1518336D02*
X-17126Y1518347D01*
G01X-19469Y1521471D02*
X-18174Y1521485D01*
G01X-18435D02*
X-20801Y1521459D01*
G01X-18174Y1521485D02*
X-17126Y1521497D01*
G01X-19469Y1524621D02*
X-18174Y1524635D01*
G01X-18435D02*
X-20801Y1524609D01*
G01X-18174Y1524635D02*
X-17126Y1524646D01*
G01X-19469Y1527770D02*
X-18174Y1527785D01*
G01X-18435D02*
X-20801Y1527759D01*
G01X-18174Y1527785D02*
X-17126Y1527796D01*
G01X-19469Y1530920D02*
X-18174Y1530934D01*
G01X-18435D02*
X-20801Y1530908D01*
G01X-18174Y1530934D02*
X-17126Y1530946D01*
G01X-19469Y1534070D02*
X-18174Y1534084D01*
G01X-18435D02*
X-20801Y1534058D01*
G01X-18174Y1534084D02*
X-17126Y1534095D01*
G01X-15985Y1512058D02*
X-14449Y1512075D01*
G01X-14677D02*
X-18174Y1512037D01*
G01X-14677Y1512075D02*
X-16213Y1512058D01*
G01X-15985Y1515208D02*
X-14449Y1515224D01*
G01X-14677D02*
X-18174Y1515186D01*
G01X-14677Y1515224D02*
X-16213Y1515208D01*
G01X-15985Y1518357D02*
X-14449Y1518374D01*
G01X-14677D02*
X-18174Y1518336D01*
G01X-14677Y1518374D02*
X-16213Y1518357D01*
G01X-15985Y1521507D02*
X-14449Y1521524D01*
G01X-14677D02*
X-18174Y1521485D01*
G01X-14677Y1521524D02*
X-16213Y1521507D01*
G01X-15985Y1524657D02*
X-14449Y1524673D01*
G01X-14677D02*
X-18174Y1524635D01*
G01X-14677Y1524673D02*
X-16213Y1524657D01*
G01X-15985Y1527806D02*
X-14449Y1527823D01*
G01X-14677D02*
X-18174Y1527785D01*
G01X-14677Y1527823D02*
X-16213Y1527806D01*
G01X-15985Y1530956D02*
X-14449Y1530972D01*
G01X-14677D02*
X-18174Y1530934D01*
G01X-14677Y1530972D02*
X-16213Y1530956D01*
G01X-15985Y1534106D02*
X-14449Y1534122D01*
G01X-14677D02*
X-18174Y1534084D01*
G01X-14677Y1534122D02*
X-16213Y1534106D01*
G01X-19469Y1512022D02*
X-20801Y1512011D01*
G01X-19469Y1515172D02*
X-20801Y1515160D01*
G01X-19469Y1518322D02*
X-20801Y1518310D01*
G01X-19469Y1521471D02*
X-20801Y1521459D01*
G01X-19469Y1524621D02*
X-20801Y1524609D01*
G01X-19469Y1527770D02*
X-20801Y1527759D01*
G01X-19469Y1530920D02*
X-20801Y1530908D01*
G01X-19469Y1534070D02*
X-20801Y1534058D01*
G01X-19469Y1537219D02*
X-20801Y1537207D01*
G01X-15985Y1512058D02*
X-17126Y1512048D01*
G01D02*
X-18435Y1512037D01*
G01X-15985Y1515208D02*
X-17126Y1515198D01*
G01D02*
X-18435Y1515186D01*
G01X-15985Y1518357D02*
X-17126Y1518347D01*
G01D02*
X-18435Y1518336D01*
G01X-15985Y1521507D02*
X-17126Y1521497D01*
G01D02*
X-18435Y1521485D01*
G01X-15985Y1524657D02*
X-17126Y1524646D01*
G01D02*
X-18435Y1524635D01*
G01X-15985Y1527806D02*
X-17126Y1527796D01*
G01D02*
X-18435Y1527785D01*
G01X-15985Y1530956D02*
X-17126Y1530946D01*
G01D02*
X-18435Y1530934D01*
G01X-15985Y1534106D02*
X-17126Y1534095D01*
G01D02*
X-18435Y1534084D01*
G01X-15985Y1537255D02*
X-17126Y1537245D01*
G01D02*
X-18435Y1537233D01*
G01X-7283Y1507646D02*
X-26772D01*
G01X512Y1510402D02*
X0D01*
G01X13780Y1510598D02*
X3937D01*
G01X-13009Y1510795D02*
X-14147D01*
G01X12410Y1510992D02*
X315D01*
G01X-14449Y1511091D02*
X-14677D01*
G01X-15985Y1511107D02*
X-16213D01*
G01X-18174Y1511128D02*
X-18435D01*
G01X-18174Y1512037D02*
X-18435D01*
G01X-15985Y1512058D02*
X-16213D01*
G01X-14449Y1512075D02*
X-14677D01*
G01X12410Y1512173D02*
X315D01*
G01X-13009Y1512370D02*
X-14147D01*
G01X3937Y1512567D02*
X13780D01*
G01X512Y1512764D02*
X0D01*
G01X512Y1513551D02*
X0D01*
G01X-13009Y1513945D02*
X-14147D01*
G01X12410Y1514142D02*
X315D01*
G01X-14449Y1514240D02*
X-14677D01*
G01X-15985Y1514256D02*
X-16213D01*
G01X-18174Y1514278D02*
X-18435D01*
G01X-18174Y1515186D02*
X-18435D01*
G01X-15985Y1515208D02*
X-16213D01*
G01X-14449Y1515224D02*
X-14677D01*
G01X12410Y1515323D02*
X315D01*
G01X-13009Y1515520D02*
X-14147D01*
G01X512Y1515913D02*
X0D01*
G01X512Y1516701D02*
X0D01*
G01X-13009Y1517094D02*
X-14147D01*
G01X12410Y1517291D02*
X315D01*
G01X-14449Y1517390D02*
X-14677D01*
G01X-15985Y1517406D02*
X-16213D01*
G01X-18174Y1517428D02*
X-18435D01*
G01X-18174Y1518336D02*
X-18435D01*
G01X-15985Y1518357D02*
X-16213D01*
G01X-14449Y1518374D02*
X-14677D01*
G01X12410Y1518472D02*
X315D01*
G01X-13009Y1518669D02*
X-14147D01*
G01X512Y1519063D02*
X0D01*
G01X512Y1519850D02*
X0D01*
G01X-13009Y1520244D02*
X-14147D01*
G01X12410Y1520441D02*
X315D01*
G01X-14449Y1520539D02*
X-14677D01*
G01X-15985Y1520556D02*
X-16213D01*
G01X-18174Y1520577D02*
X-18435D01*
G01X-18174Y1521485D02*
X-18435D01*
G01X-15985Y1521507D02*
X-16213D01*
G01X-14449Y1521524D02*
X-14677D01*
G01X12410Y1521622D02*
X315D01*
G01X-13009Y1521819D02*
X-14147D01*
G01X512Y1522213D02*
X0D01*
G01X512Y1523000D02*
X0D01*
G01X-13009Y1523394D02*
X-14147D01*
G01X12410Y1523591D02*
X315D01*
G01X-14449Y1523689D02*
X-14677D01*
G01X-15985Y1523705D02*
X-16213D01*
G01X-18174Y1523727D02*
X-18435D01*
G01X-18174Y1524635D02*
X-18435D01*
G01X-15985Y1524657D02*
X-16213D01*
G01X-14449Y1524673D02*
X-14677D01*
G01X12410Y1524772D02*
X315D01*
G01X-13009Y1524969D02*
X-14147D01*
G01X512Y1525362D02*
X0D01*
G01X512Y1526150D02*
X0D01*
G01X-13009Y1526543D02*
X-14147D01*
G01X12410Y1526740D02*
X315D01*
G01X-14449Y1526839D02*
X-14677D01*
G01X-15985Y1526855D02*
X-16213D01*
G01X-18174Y1526876D02*
X-18435D01*
G01X-18174Y1527785D02*
X-18435D01*
G01X-15985Y1527806D02*
X-16213D01*
G01X-14449Y1527823D02*
X-14677D01*
G01X12410Y1527921D02*
X315D01*
G01X-13009Y1528118D02*
X-14147D01*
G01X512Y1528512D02*
X0D01*
G01X512Y1529299D02*
X0D01*
G01X-13009Y1529693D02*
X-14147D01*
G01X12410Y1529890D02*
X315D01*
G01X-14449Y1529988D02*
X-14677D01*
G01X-15985Y1530004D02*
X-16213D01*
G01X-18174Y1530026D02*
X-18435D01*
G01X-18174Y1530934D02*
X-18435D01*
G01X-15985Y1530956D02*
X-16213D01*
G01X-14449Y1530972D02*
X-14677D01*
G01X12410Y1531071D02*
X315D01*
G01X-13009Y1531268D02*
X-14147D01*
G01X512Y1531661D02*
X0D01*
G01X512Y1532449D02*
X0D01*
G01X-13009Y1532843D02*
X-14147D01*
G01X12410Y1533039D02*
X315D01*
G01X-14449Y1533138D02*
X-14677D01*
G01X-15985Y1533154D02*
X-16213D01*
G01X-18174Y1533176D02*
X-18435D01*
G01X-18174Y1534084D02*
X-18435D01*
G01X-15985Y1534106D02*
X-16213D01*
G01X-14449Y1534122D02*
X-14677D01*
G01X12410Y1534220D02*
X315D01*
G01X-13009Y1534417D02*
X-14147D01*
G01X512Y1534811D02*
X0D01*
G01X512Y1535598D02*
X0D01*
G01X-13009Y1535992D02*
X-14147D01*
G01X12410Y1536189D02*
X315D01*
G01X-14449Y1536287D02*
X-14677D01*
G01X-15985Y1536304D02*
X-16213D01*
G01X-18174Y1536325D02*
X-18435D01*
G01X-18174Y1537233D02*
X-18435D01*
G01X-15985Y1537255D02*
X-16213D01*
G01X-14449Y1537272D02*
X-14677D01*
G01X12410Y1537370D02*
X315D01*
G01X-13009Y1537567D02*
X-14147D01*
G01X512Y1537961D02*
X0D01*
G01X512Y1538748D02*
X0D01*
G01X-13009Y1539142D02*
X-14147D01*
G01X12410Y1539339D02*
X315D01*
G01X-14449Y1539437D02*
X-14677D01*
G01X-15985Y1539453D02*
X-16213D01*
G01X-18174Y1539475D02*
X-18435D01*
G01X-18174Y1540383D02*
X-18435D01*
G01X-15985Y1540405D02*
X-16213D01*
G01X-14449Y1540421D02*
X-14677D01*
G01X12410Y1540520D02*
X315D01*
G01X-13009Y1540717D02*
X-14147D01*
G01X512Y1541110D02*
X0D01*
G01X512Y1541898D02*
X0D01*
G01X-13009Y1542291D02*
X-14147D01*
G01X12410Y1542488D02*
X315D01*
G01X-19469Y1511143D02*
X-20801Y1511155D01*
G01X-15985Y1511107D02*
X-18435Y1511128D01*
G01X-19469Y1514293D02*
X-20801Y1514304D01*
G01X-15985Y1514256D02*
X-18435Y1514278D01*
G01X-19469Y1517442D02*
X-20801Y1517454D01*
G01X-15985Y1517406D02*
X-18435Y1517428D01*
G01X-19469Y1520592D02*
X-20801Y1520604D01*
G01X-15985Y1520556D02*
X-18435Y1520577D01*
G01X-19469Y1523741D02*
X-20801Y1523753D01*
G01X-15985Y1523705D02*
X-18435Y1523727D01*
G01X-19469Y1526891D02*
X-20801Y1526903D01*
G01X-15985Y1526855D02*
X-18435Y1526876D01*
G01X-19469Y1530041D02*
X-20801Y1530052D01*
G01X-15985Y1530004D02*
X-18435Y1530026D01*
G01X-19469Y1533190D02*
X-20801Y1533202D01*
G01X-15985Y1533154D02*
X-18435Y1533176D01*
G01X-19469Y1536340D02*
X-20801Y1536352D01*
G01X-15985Y1536304D02*
X-18435Y1536325D01*
G01X-19469Y1539489D02*
X-20801Y1539501D01*
G01X-15985Y1539453D02*
X-18435Y1539475D01*
G01X-19469Y1542639D02*
X-20801Y1542651D01*
G01X-15985Y1542603D02*
X-18435Y1542624D01*
G01X-15985Y1511107D02*
X-14449Y1511091D01*
G01X-15985Y1514256D02*
X-14449Y1514240D01*
G01X-15985Y1517406D02*
X-14449Y1517390D01*
G01X-15985Y1520556D02*
X-14449Y1520539D01*
G01X-15985Y1523705D02*
X-14449Y1523689D01*
G01X-15985Y1526855D02*
X-14449Y1526839D01*
G01X-15985Y1530004D02*
X-14449Y1529988D01*
G01X-15985Y1533154D02*
X-14449Y1533138D01*
G01X-15985Y1536304D02*
X-14449Y1536287D01*
G01X-15985Y1539453D02*
X-14449Y1539437D01*
G01X-15985Y1542603D02*
X-14449Y1542587D01*
G01X-18435Y1511128D02*
X-20801Y1511155D01*
G01X-18435Y1514278D02*
X-20801Y1514304D01*
G01X-18435Y1517428D02*
X-20801Y1517454D01*
G01X-18435Y1520577D02*
X-20801Y1520604D01*
G01X-18435Y1523727D02*
X-20801Y1523753D01*
G01X-18435Y1526876D02*
X-20801Y1526903D01*
G01X-18435Y1530026D02*
X-20801Y1530052D01*
G01X-18435Y1533176D02*
X-20801Y1533202D01*
G01X-18435Y1536325D02*
X-20801Y1536352D01*
G01X-18435Y1539475D02*
X-20801Y1539501D01*
G01X-18435Y1542624D02*
X-20801Y1542651D01*
G01X-19469Y1511143D02*
X-16213Y1511107D01*
G01X-18174Y1511128D02*
X-14677Y1511091D01*
G01X-19469Y1514293D02*
X-16213Y1514256D01*
G01X-18174Y1514278D02*
X-14677Y1514240D01*
G01X-19469Y1517442D02*
X-16213Y1517406D01*
G01X-18174Y1517428D02*
X-14677Y1517390D01*
G01X-19469Y1520592D02*
X-16213Y1520556D01*
G01X-18174Y1520577D02*
X-14677Y1520539D01*
G01X-19469Y1523741D02*
X-16213Y1523705D01*
G01X-18174Y1523727D02*
X-14677Y1523689D01*
G01X-19469Y1526891D02*
X-16213Y1526855D01*
G01X-18174Y1526876D02*
X-14677Y1526839D01*
G01X-19469Y1530041D02*
X-16213Y1530004D01*
G01X-18174Y1530026D02*
X-14677Y1529988D01*
G01X-19469Y1533190D02*
X-16213Y1533154D01*
G01X-18174Y1533176D02*
X-14677Y1533138D01*
G01X-19469Y1536340D02*
X-16213Y1536304D01*
G01X-18174Y1536325D02*
X-14677Y1536287D01*
G01X-19469Y1539489D02*
X-16213Y1539453D01*
G01X-18174Y1539475D02*
X-14677Y1539437D01*
G01X-19469Y1542639D02*
X-16213Y1542603D01*
G01X-18174Y1542624D02*
X-14677Y1542587D01*
G01X-19469Y1537219D02*
X-18174Y1537233D01*
G01X-18435D02*
X-20801Y1537207D01*
G01X-18174Y1537233D02*
X-17126Y1537245D01*
G01X-19469Y1540369D02*
X-18174Y1540383D01*
G01X-18435D02*
X-20801Y1540357D01*
G01X-18174Y1540383D02*
X-17126Y1540394D01*
G01X-19469Y1543519D02*
X-18174Y1543533D01*
G01X-18435D02*
X-20801Y1543507D01*
G01X-18174Y1543533D02*
X-17126Y1543544D01*
G01X-15985Y1537255D02*
X-14449Y1537272D01*
G01X-14677D02*
X-18174Y1537233D01*
G01X-14677Y1537272D02*
X-16213Y1537255D01*
G01X-15985Y1540405D02*
X-14449Y1540421D01*
G01X-14677D02*
X-18174Y1540383D01*
G01X-14677Y1540421D02*
X-16213Y1540405D01*
G01X-15985Y1543554D02*
X-14449Y1543571D01*
G01X-14677D02*
X-18174Y1543533D01*
G01X-14677Y1543571D02*
X-16213Y1543554D01*
G01X-19469Y1540369D02*
X-20801Y1540357D01*
G01X-19469Y1543519D02*
X-20801Y1543507D01*
G01X-15985Y1540405D02*
X-17126Y1540394D01*
G01D02*
X-18435Y1540383D01*
G01X-15985Y1543554D02*
X-17126Y1543544D01*
G01D02*
X-18435Y1543533D01*
G01X-14449Y1542587D02*
X-14677D01*
G01X-15985Y1542603D02*
X-16213D01*
G01X-18174Y1542624D02*
X-18435D01*
G01X-18174Y1543533D02*
X-18435D01*
G01X-15985Y1543554D02*
X-16213D01*
G01X-14449Y1543571D02*
X-14677D01*
G01X12410Y1543669D02*
X315D01*
G01X-13009Y1543866D02*
X-14147D01*
G01X512Y1544260D02*
X0D01*
G01X512Y1545047D02*
X0D01*
G01X12634Y1583689D02*
X12416Y1583419D01*
G01X12287Y1583689D02*
X12057Y1583433D01*
G01X12287Y1580539D02*
X12057Y1580283D01*
G01X12287Y1577390D02*
X12057Y1577134D01*
G01X12634Y1580539D02*
X12416Y1580269D01*
G01X12634Y1577390D02*
X12416Y1577120D01*
G01X12057Y1584614D02*
Y1583433D01*
G01Y1581465D02*
Y1580283D01*
G01Y1578315D02*
Y1577134D01*
G01X12410Y1584614D02*
Y1583433D01*
G01Y1581465D02*
Y1580283D01*
G01Y1578315D02*
Y1577134D01*
G01X13353Y1584358D02*
Y1583689D01*
G01Y1581209D02*
Y1580539D01*
G01Y1578059D02*
Y1577390D01*
G01X13701Y1584358D02*
Y1583689D01*
G01Y1581209D02*
Y1580539D01*
G01Y1578059D02*
Y1577390D01*
G01X12416Y1578329D02*
X12634Y1578059D01*
G01X12416Y1581479D02*
X12634Y1581209D01*
G01X12416Y1584628D02*
X12634Y1584358D01*
G01X12057Y1578315D02*
X12287Y1578059D01*
G01X12057Y1581465D02*
X12287Y1581209D01*
G01X12057Y1584614D02*
X12287Y1584358D01*
G01X13701Y1577390D02*
X12287D01*
G01X13701Y1578059D02*
X12287D01*
G01X13701Y1580539D02*
X12287D01*
G01X13701Y1581209D02*
X12287D01*
G01X13701Y1583689D02*
X12287D01*
G01X13701Y1584358D02*
X12287D01*
G01X12634Y1646681D02*
X12416Y1646411D01*
G01X12634Y1643531D02*
X12416Y1643261D01*
G01X12634Y1640382D02*
X12416Y1640112D01*
G01X12634Y1637232D02*
X12416Y1636962D01*
G01X12634Y1634083D02*
X12416Y1633813D01*
G01X12634Y1630933D02*
X12416Y1630663D01*
G01X12634Y1627783D02*
X12416Y1627513D01*
G01X12634Y1624634D02*
X12416Y1624364D01*
G01X12634Y1621484D02*
X12416Y1621214D01*
G01X12634Y1618335D02*
X12416Y1618065D01*
G01X12634Y1615185D02*
X12416Y1614915D01*
G01X12634Y1612035D02*
X12416Y1611765D01*
G01X12634Y1608886D02*
X12416Y1608616D01*
G01X12634Y1605736D02*
X12416Y1605466D01*
G01X12287Y1646681D02*
X12057Y1646425D01*
G01X12287Y1643531D02*
X12057Y1643276D01*
G01X12287Y1640382D02*
X12057Y1640126D01*
G01X12287Y1637232D02*
X12057Y1636976D01*
G01X12287Y1634083D02*
X12057Y1633827D01*
G01X12287Y1630933D02*
X12057Y1630677D01*
G01X12287Y1627783D02*
X12057Y1627528D01*
G01X12287Y1624634D02*
X12057Y1624378D01*
G01X12287Y1621484D02*
X12057Y1621228D01*
G01X12287Y1618335D02*
X12057Y1618079D01*
G01X12287Y1615185D02*
X12057Y1614929D01*
G01X12287Y1612035D02*
X12057Y1611780D01*
G01X12287Y1608886D02*
X12057Y1608630D01*
G01X12287Y1605736D02*
X12057Y1605480D01*
G01Y1644457D02*
Y1643276D01*
G01Y1647606D02*
Y1646425D01*
G01Y1641307D02*
Y1640126D01*
G01Y1635008D02*
Y1633827D01*
G01Y1638157D02*
Y1636976D01*
G01Y1631858D02*
Y1630677D01*
G01Y1625559D02*
Y1624378D01*
G01Y1628709D02*
Y1627528D01*
G01Y1622409D02*
Y1621228D01*
G01Y1616110D02*
Y1614929D01*
G01Y1619260D02*
Y1618079D01*
G01Y1612961D02*
Y1611780D01*
G01Y1606661D02*
Y1605480D01*
G01Y1609811D02*
Y1608630D01*
G01X12410Y1644457D02*
Y1643276D01*
G01Y1647606D02*
Y1646425D01*
G01Y1641307D02*
Y1640126D01*
G01Y1635008D02*
Y1633827D01*
G01Y1638157D02*
Y1636976D01*
G01Y1631858D02*
Y1630677D01*
G01Y1625559D02*
Y1624378D01*
G01Y1628709D02*
Y1627528D01*
G01Y1622409D02*
Y1621228D01*
G01Y1616110D02*
Y1614929D01*
G01Y1619260D02*
Y1618079D01*
G01Y1612961D02*
Y1611780D01*
G01Y1606661D02*
Y1605480D01*
G01Y1609811D02*
Y1608630D01*
G01X13353Y1644201D02*
Y1643531D01*
G01Y1647350D02*
Y1646681D01*
G01Y1641051D02*
Y1640382D01*
G01Y1634752D02*
Y1634083D01*
G01Y1637902D02*
Y1637232D01*
G01Y1631602D02*
Y1630933D01*
G01Y1628453D02*
Y1627783D01*
G01Y1622154D02*
Y1621484D01*
G01Y1625303D02*
Y1624634D01*
G01Y1619004D02*
Y1618335D01*
G01Y1612705D02*
Y1612035D01*
G01Y1615854D02*
Y1615185D01*
G01Y1609555D02*
Y1608886D01*
G01Y1606406D02*
Y1605736D01*
G01X13701Y1644201D02*
Y1643531D01*
G01Y1647350D02*
Y1646681D01*
G01Y1641051D02*
Y1640382D01*
G01Y1634752D02*
Y1634083D01*
G01Y1637902D02*
Y1637232D01*
G01Y1631602D02*
Y1630933D01*
G01Y1628453D02*
Y1627783D01*
G01Y1622154D02*
Y1621484D01*
G01Y1625303D02*
Y1624634D01*
G01Y1619004D02*
Y1618335D01*
G01Y1612705D02*
Y1612035D01*
G01Y1615854D02*
Y1615185D01*
G01Y1609555D02*
Y1608886D01*
G01Y1606406D02*
Y1605736D01*
G01X12416Y1606676D02*
X12634Y1606406D01*
G01X12416Y1609825D02*
X12634Y1609555D01*
G01X12416Y1612975D02*
X12634Y1612705D01*
G01X12416Y1616124D02*
X12634Y1615854D01*
G01X12416Y1619274D02*
X12634Y1619004D01*
G01X12416Y1622424D02*
X12634Y1622154D01*
G01X12416Y1625573D02*
X12634Y1625303D01*
G01X12057Y1606661D02*
X12287Y1606406D01*
G01X12057Y1609811D02*
X12287Y1609555D01*
G01X12057Y1612961D02*
X12287Y1612705D01*
G01X12057Y1616110D02*
X12287Y1615854D01*
G01X12057Y1619260D02*
X12287Y1619004D01*
G01X12057Y1622409D02*
X12287Y1622154D01*
G01X12057Y1625559D02*
X12287Y1625303D01*
G01X12057Y1628709D02*
X12287Y1628453D01*
G01X12057Y1631858D02*
X12287Y1631602D01*
G01X12057Y1635008D02*
X12287Y1634752D01*
G01X12057Y1638157D02*
X12287Y1637902D01*
G01X12057Y1641307D02*
X12287Y1641051D01*
G01X12057Y1644457D02*
X12287Y1644201D01*
G01X12057Y1647606D02*
X12287Y1647350D01*
G01X12416Y1628723D02*
X12634Y1628453D01*
G01X12416Y1631872D02*
X12634Y1631602D01*
G01X12416Y1635022D02*
X12634Y1634752D01*
G01X12416Y1638172D02*
X12634Y1637902D01*
G01X12416Y1641321D02*
X12634Y1641051D01*
G01X12416Y1644471D02*
X12634Y1644201D01*
G01X12416Y1647620D02*
X12634Y1647350D01*
G01X13701Y1605736D02*
X12287D01*
G01X13701Y1606406D02*
X12287D01*
G01X13701Y1608886D02*
X12287D01*
G01X13701Y1609555D02*
X12287D01*
G01X13701Y1612035D02*
X12287D01*
G01X13701Y1612705D02*
X12287D01*
G01X13701Y1615185D02*
X12287D01*
G01X13701Y1615854D02*
X12287D01*
G01X13701Y1618335D02*
X12287D01*
G01X13701Y1619004D02*
X12287D01*
G01X13701Y1621484D02*
X12287D01*
G01X13701Y1622154D02*
X12287D01*
G01X13701Y1624634D02*
X12287D01*
G01X13701Y1625303D02*
X12287D01*
G01X13701Y1627783D02*
X12287D01*
G01X13701Y1628453D02*
X12287D01*
G01X13701Y1630933D02*
X12287D01*
G01X13701Y1631602D02*
X12287D01*
G01X13701Y1634083D02*
X12287D01*
G01X13701Y1634752D02*
X12287D01*
G01X13701Y1637232D02*
X12287D01*
G01X13701Y1637902D02*
X12287D01*
G01X13701Y1640382D02*
X12287D01*
G01X13701Y1641051D02*
X12287D01*
G01X13701Y1643531D02*
X12287D01*
G01X13701Y1644201D02*
X12287D01*
G01X13701Y1646681D02*
X12287D01*
G01X13701Y1647350D02*
X12287D01*
G01X12634Y1602587D02*
X12416Y1602317D01*
G01X12634Y1599437D02*
X12416Y1599167D01*
G01X12634Y1596287D02*
X12416Y1596017D01*
G01X12634Y1593138D02*
X12416Y1592868D01*
G01X12634Y1589988D02*
X12416Y1589718D01*
G01X12634Y1586839D02*
X12416Y1586569D01*
G01X12287Y1602587D02*
X12057Y1602331D01*
G01X12287Y1599437D02*
X12057Y1599181D01*
G01X12287Y1596287D02*
X12057Y1596031D01*
G01X12287Y1593138D02*
X12057Y1592882D01*
G01X12287Y1589988D02*
X12057Y1589732D01*
G01X12287Y1586839D02*
X12057Y1586583D01*
G01Y1603512D02*
Y1602331D01*
G01Y1600362D02*
Y1599181D01*
G01Y1594063D02*
Y1592882D01*
G01Y1597213D02*
Y1596031D01*
G01Y1590913D02*
Y1589732D01*
G01Y1587764D02*
Y1586583D01*
G01X12410Y1603512D02*
Y1602331D01*
G01Y1600362D02*
Y1599181D01*
G01Y1594063D02*
Y1592882D01*
G01Y1597213D02*
Y1596031D01*
G01Y1590913D02*
Y1589732D01*
G01Y1587764D02*
Y1586583D01*
G01X13353Y1603256D02*
Y1602587D01*
G01Y1600106D02*
Y1599437D01*
G01Y1593807D02*
Y1593138D01*
G01Y1596957D02*
Y1596287D01*
G01Y1590657D02*
Y1589988D01*
G01Y1587508D02*
Y1586839D01*
G01X13701Y1603256D02*
Y1602587D01*
G01Y1600106D02*
Y1599437D01*
G01Y1593807D02*
Y1593138D01*
G01Y1596957D02*
Y1596287D01*
G01Y1590657D02*
Y1589988D01*
G01Y1587508D02*
Y1586839D01*
G01X12416Y1587778D02*
X12634Y1587508D01*
G01X12416Y1590928D02*
X12634Y1590657D01*
G01X12416Y1594077D02*
X12634Y1593807D01*
G01X12416Y1597227D02*
X12634Y1596957D01*
G01X12416Y1600376D02*
X12634Y1600106D01*
G01X12416Y1603526D02*
X12634Y1603256D01*
G01X12057Y1587764D02*
X12287Y1587508D01*
G01X12057Y1590913D02*
X12287Y1590657D01*
G01X12057Y1594063D02*
X12287Y1593807D01*
G01X12057Y1597213D02*
X12287Y1596957D01*
G01X12057Y1600362D02*
X12287Y1600106D01*
G01X12057Y1603512D02*
X12287Y1603256D01*
G01X13701Y1586839D02*
X12287D01*
G01X13701Y1587508D02*
X12287D01*
G01X13701Y1589988D02*
X12287D01*
G01X13701Y1590657D02*
X12287D01*
G01X13701Y1593138D02*
X12287D01*
G01X13701Y1593807D02*
X12287D01*
G01X13701Y1596287D02*
X12287D01*
G01X13701Y1596957D02*
X12287D01*
G01X13701Y1599437D02*
X12287D01*
G01X13701Y1600106D02*
X12287D01*
G01X13701Y1602587D02*
X12287D01*
G01X13701Y1603256D02*
X12287D01*
G01X35827Y1650768D02*
X40551Y1646122D01*
G01X-14537Y1584604D02*
X-14677Y1584516D01*
G01X-13977Y1584811D02*
X-14449Y1584516D01*
G01X-14537Y1581454D02*
X-14677Y1581366D01*
G01X-13977Y1581661D02*
X-14449Y1581366D01*
G01X-14537Y1578304D02*
X-14677Y1578217D01*
G01X-13977Y1578512D02*
X-14449Y1578217D01*
G01X-14147Y1584811D02*
X-14537Y1584604D01*
G01X-14147Y1581661D02*
X-14537Y1581454D01*
G01X-14147Y1578512D02*
X-14537Y1578304D01*
G01X-20801Y1584452D02*
Y1583596D01*
G01Y1581302D02*
Y1580446D01*
G01Y1578152D02*
Y1577296D01*
G01X-19469Y1584457D02*
Y1583590D01*
G01Y1581308D02*
Y1580440D01*
G01Y1578158D02*
Y1577291D01*
G01X-18435Y1584478D02*
Y1583569D01*
G01Y1581328D02*
Y1580420D01*
G01Y1578178D02*
Y1577270D01*
G01X-18174Y1584478D02*
Y1583569D01*
G01Y1581328D02*
Y1580420D01*
G01Y1578178D02*
Y1577270D01*
G01X-16213Y1584499D02*
Y1583548D01*
G01Y1581350D02*
Y1580398D01*
G01Y1578200D02*
Y1577248D01*
G01X-15985Y1584499D02*
Y1583548D01*
G01Y1581350D02*
Y1580398D01*
G01Y1578200D02*
Y1577248D01*
G01X-14537Y1584604D02*
Y1583444D01*
G01Y1581454D02*
Y1580294D01*
G01Y1578304D02*
Y1577144D01*
G01X-13009Y1584811D02*
Y1583236D01*
G01Y1581661D02*
Y1580087D01*
G01Y1578512D02*
Y1576937D01*
G01X315Y1585205D02*
Y1584614D01*
G01Y1583433D02*
Y1582843D01*
G01Y1578906D02*
Y1578315D01*
G01Y1582055D02*
Y1581465D01*
G01Y1580283D02*
Y1579693D01*
G01Y1577134D02*
Y1576543D01*
G01X512Y1585205D02*
Y1584614D01*
G01Y1583433D02*
Y1582843D01*
G01Y1578906D02*
Y1578315D01*
G01Y1582055D02*
Y1581465D01*
G01Y1580283D02*
Y1579693D01*
G01Y1577134D02*
Y1576543D01*
G01X709Y1584614D02*
Y1583433D01*
G01Y1581465D02*
Y1580283D01*
G01Y1578315D02*
Y1577134D01*
G01X1074Y1584614D02*
Y1583433D01*
G01Y1581465D02*
Y1580283D01*
G01Y1578315D02*
Y1577134D01*
G01X1184Y1584614D02*
Y1583433D01*
G01Y1581465D02*
Y1580283D01*
G01Y1578315D02*
Y1577134D01*
G01X9965Y1584614D02*
Y1583433D01*
G01Y1581465D02*
Y1580283D01*
G01Y1578315D02*
Y1577134D01*
G01X10075Y1584614D02*
Y1583433D01*
G01Y1581465D02*
Y1580283D01*
G01Y1578315D02*
Y1577134D01*
G01X-14677Y1577232D02*
X-14537Y1577144D01*
G01X-14449Y1577232D02*
X-13977Y1576937D01*
G01X-14677Y1580382D02*
X-14537Y1580294D01*
G01X-14449Y1580382D02*
X-13977Y1580087D01*
G01X-14677Y1583531D02*
X-14537Y1583444D01*
G01X-14449Y1583531D02*
X-13977Y1583236D01*
G01X-14537Y1577144D02*
X-14147Y1576937D01*
G01X-14537Y1580294D02*
X-14147Y1580087D01*
G01X-14537Y1583444D02*
X-14147Y1583236D01*
G01X-19469Y1578164D02*
X-18174Y1578178D01*
G01X-18435D02*
X-20801Y1578152D01*
G01X-18174Y1578178D02*
X-17126Y1578190D01*
G01X-19469Y1581314D02*
X-18174Y1581328D01*
G01X-18435D02*
X-20801Y1581302D01*
G01X-18174Y1581328D02*
X-17126Y1581339D01*
G01X-19469Y1584463D02*
X-18174Y1584478D01*
G01X-18435D02*
X-20801Y1584452D01*
G01X-18174Y1584478D02*
X-17126Y1584489D01*
G01X-15985Y1578200D02*
X-14449Y1578217D01*
G01X-14677D02*
X-18174Y1578178D01*
G01X-14677Y1578217D02*
X-16213Y1578200D01*
G01X-15985Y1581350D02*
X-14449Y1581366D01*
G01X-14677D02*
X-18174Y1581328D01*
G01X-14677Y1581366D02*
X-16213Y1581350D01*
G01X-15985Y1584499D02*
X-14449Y1584516D01*
G01X-14677D02*
X-18174Y1584478D01*
G01X-14677Y1584516D02*
X-16213Y1584499D01*
G01X-19469Y1578164D02*
X-20801Y1578152D01*
G01X-19469Y1581314D02*
X-20801Y1581302D01*
G01X-19469Y1584463D02*
X-20801Y1584452D01*
G01X-15985Y1578200D02*
X-17126Y1578190D01*
G01D02*
X-18435Y1578178D01*
G01X-15985Y1581350D02*
X-17126Y1581339D01*
G01D02*
X-18435Y1581328D01*
G01X-15985Y1584499D02*
X-17126Y1584489D01*
G01D02*
X-18435Y1584478D01*
G01X512Y1575756D02*
X0D01*
G01X512Y1576543D02*
X0D01*
G01X-13009Y1576937D02*
X-14147D01*
G01X12410Y1577134D02*
X315D01*
G01X-14449Y1577232D02*
X-14677D01*
G01X-15985Y1577248D02*
X-16213D01*
G01X-18174Y1577270D02*
X-18435D01*
G01X-18174Y1578178D02*
X-18435D01*
G01X-15985Y1578200D02*
X-16213D01*
G01X-14449Y1578217D02*
X-14677D01*
G01X12410Y1578315D02*
X315D01*
G01X-13009Y1578512D02*
X-14147D01*
G01X512Y1578906D02*
X0D01*
G01X512Y1579693D02*
X0D01*
G01X-13009Y1580087D02*
X-14147D01*
G01X12410Y1580283D02*
X315D01*
G01X-14449Y1580382D02*
X-14677D01*
G01X-15985Y1580398D02*
X-16213D01*
G01X-18174Y1580420D02*
X-18435D01*
G01X-18174Y1581328D02*
X-18435D01*
G01X-15985Y1581350D02*
X-16213D01*
G01X-14449Y1581366D02*
X-14677D01*
G01X12410Y1581465D02*
X315D01*
G01X-13009Y1581661D02*
X-14147D01*
G01X512Y1582055D02*
X0D01*
G01X512Y1582843D02*
X0D01*
G01X-13009Y1583236D02*
X-14147D01*
G01X12410Y1583433D02*
X315D01*
G01X-14449Y1583531D02*
X-14677D01*
G01X-15985Y1583548D02*
X-16213D01*
G01X-18174Y1583569D02*
X-18435D01*
G01X-18174Y1584478D02*
X-18435D01*
G01X-15985Y1584499D02*
X-16213D01*
G01X-14449Y1584516D02*
X-14677D01*
G01X12410Y1584614D02*
X315D01*
G01X-13009Y1584811D02*
X-14147D01*
G01X512Y1585205D02*
X0D01*
G01X-19469Y1577285D02*
X-20801Y1577296D01*
G01X-15985Y1577248D02*
X-18435Y1577270D01*
G01X-19469Y1580434D02*
X-20801Y1580446D01*
G01X-15985Y1580398D02*
X-18435Y1580420D01*
G01X-19469Y1583584D02*
X-20801Y1583596D01*
G01X-15985Y1583548D02*
X-18435Y1583569D01*
G01X-15985Y1577248D02*
X-14449Y1577232D01*
G01X-15985Y1580398D02*
X-14449Y1580382D01*
G01X-15985Y1583548D02*
X-14449Y1583531D01*
G01X-18435Y1577270D02*
X-20801Y1577296D01*
G01X-18435Y1580420D02*
X-20801Y1580446D01*
G01X-18435Y1583569D02*
X-20801Y1583596D01*
G01X-19469Y1577285D02*
X-16213Y1577248D01*
G01X-18174Y1577270D02*
X-14677Y1577232D01*
G01X-19469Y1580434D02*
X-16213Y1580398D01*
G01X-18174Y1580420D02*
X-14677Y1580382D01*
G01X-19469Y1583584D02*
X-16213Y1583548D01*
G01X-18174Y1583569D02*
X-14677Y1583531D01*
G01X-14537Y1647596D02*
X-14677Y1647508D01*
G01X-13977Y1647803D02*
X-14449Y1647508D01*
G01X-14537Y1644446D02*
X-14677Y1644358D01*
G01X-13977Y1644654D02*
X-14449Y1644358D01*
G01X-14537Y1641296D02*
X-14677Y1641209D01*
G01X-13977Y1641504D02*
X-14449Y1641209D01*
G01X-14537Y1638147D02*
X-14677Y1638059D01*
G01X-13977Y1638354D02*
X-14449Y1638059D01*
G01X-14537Y1634997D02*
X-14677Y1634909D01*
G01X-13977Y1635205D02*
X-14449Y1634909D01*
G01X-14537Y1631848D02*
X-14677Y1631760D01*
G01X-13977Y1632055D02*
X-14449Y1631760D01*
G01X-14537Y1628698D02*
X-14677Y1628610D01*
G01X-13977Y1628906D02*
X-14449Y1628610D01*
G01X-14537Y1625548D02*
X-14677Y1625461D01*
G01X-13977Y1625756D02*
X-14449Y1625461D01*
G01X-14537Y1622399D02*
X-14677Y1622311D01*
G01X-13977Y1622606D02*
X-14449Y1622311D01*
G01X-14537Y1619249D02*
X-14677Y1619161D01*
G01X-13977Y1619457D02*
X-14449Y1619161D01*
G01X-14537Y1616100D02*
X-14677Y1616012D01*
G01X-13977Y1616307D02*
X-14449Y1616012D01*
G01X-14537Y1612950D02*
X-14677Y1612862D01*
G01X-13977Y1613157D02*
X-14449Y1612862D01*
G01X-14537Y1609800D02*
X-14677Y1609713D01*
G01X-13977Y1610008D02*
X-14449Y1609713D01*
G01X-14537Y1606651D02*
X-14677Y1606563D01*
G01X-13977Y1606858D02*
X-14449Y1606563D01*
G01X-14147Y1647803D02*
X-14537Y1647596D01*
G01X-14147Y1644654D02*
X-14537Y1644446D01*
G01X-14147Y1641504D02*
X-14537Y1641296D01*
G01X-14147Y1638354D02*
X-14537Y1638147D01*
G01X-14147Y1635205D02*
X-14537Y1634997D01*
G01X-14147Y1632055D02*
X-14537Y1631848D01*
G01X-14147Y1628906D02*
X-14537Y1628698D01*
G01X-14147Y1625756D02*
X-14537Y1625548D01*
G01X-14147Y1622606D02*
X-14537Y1622399D01*
G01X-14147Y1619457D02*
X-14537Y1619249D01*
G01X-14147Y1616307D02*
X-14537Y1616100D01*
G01X-14147Y1613157D02*
X-14537Y1612950D01*
G01X-14147Y1610008D02*
X-14537Y1609800D01*
G01X-14147Y1606858D02*
X-14537Y1606651D01*
G01X-20801Y1644294D02*
Y1643438D01*
G01Y1647444D02*
Y1646588D01*
G01Y1641144D02*
Y1640289D01*
G01Y1634845D02*
Y1633989D01*
G01Y1637995D02*
Y1637139D01*
G01Y1631696D02*
Y1630840D01*
G01Y1625396D02*
Y1624541D01*
G01Y1628546D02*
Y1627690D01*
G01Y1622247D02*
Y1621391D01*
G01Y1619097D02*
Y1618241D01*
G01Y1612798D02*
Y1611942D01*
G01Y1615948D02*
Y1615092D01*
G01Y1609648D02*
Y1608793D01*
G01Y1606499D02*
Y1605643D01*
G01X-19469Y1644300D02*
Y1643432D01*
G01Y1647450D02*
Y1646582D01*
G01Y1641150D02*
Y1640283D01*
G01Y1634851D02*
Y1633983D01*
G01Y1638001D02*
Y1637133D01*
G01Y1631702D02*
Y1630834D01*
G01Y1625402D02*
Y1624535D01*
G01Y1628552D02*
Y1627684D01*
G01Y1622253D02*
Y1621385D01*
G01Y1619103D02*
Y1618235D01*
G01Y1612804D02*
Y1611936D01*
G01Y1615954D02*
Y1615086D01*
G01Y1609654D02*
Y1608787D01*
G01Y1606505D02*
Y1605637D01*
G01X-18435Y1644320D02*
Y1643412D01*
G01Y1647470D02*
Y1646561D01*
G01Y1641170D02*
Y1640262D01*
G01Y1634871D02*
Y1633963D01*
G01Y1638021D02*
Y1637113D01*
G01Y1631722D02*
Y1630813D01*
G01Y1625422D02*
Y1624514D01*
G01Y1628572D02*
Y1627664D01*
G01Y1622273D02*
Y1621365D01*
G01Y1619123D02*
Y1618215D01*
G01Y1612824D02*
Y1611916D01*
G01Y1615974D02*
Y1615065D01*
G01Y1609674D02*
Y1608766D01*
G01Y1606525D02*
Y1605617D01*
G01X-18174Y1644320D02*
Y1643412D01*
G01Y1647470D02*
Y1646561D01*
G01Y1641170D02*
Y1640262D01*
G01Y1634871D02*
Y1633963D01*
G01Y1638021D02*
Y1637113D01*
G01Y1631722D02*
Y1630813D01*
G01Y1625422D02*
Y1624514D01*
G01Y1628572D02*
Y1627664D01*
G01Y1622273D02*
Y1621365D01*
G01Y1619123D02*
Y1618215D01*
G01Y1612824D02*
Y1611916D01*
G01Y1615974D02*
Y1615065D01*
G01Y1609674D02*
Y1608766D01*
G01Y1606525D02*
Y1605617D01*
G01X-16213Y1644342D02*
Y1643390D01*
G01Y1647491D02*
Y1646540D01*
G01Y1641192D02*
Y1640241D01*
G01Y1634893D02*
Y1633941D01*
G01Y1638043D02*
Y1637091D01*
G01Y1631743D02*
Y1630792D01*
G01Y1625444D02*
Y1624493D01*
G01Y1628594D02*
Y1627642D01*
G01Y1622294D02*
Y1621343D01*
G01Y1619145D02*
Y1618193D01*
G01Y1612846D02*
Y1611894D01*
G01Y1615995D02*
Y1615044D01*
G01Y1609696D02*
Y1608744D01*
G01Y1606546D02*
Y1605595D01*
G01X-15985Y1644342D02*
Y1643390D01*
G01Y1647491D02*
Y1646540D01*
G01Y1641192D02*
Y1640241D01*
G01Y1634893D02*
Y1633941D01*
G01Y1638043D02*
Y1637091D01*
G01Y1631743D02*
Y1630792D01*
G01Y1625444D02*
Y1624493D01*
G01Y1628594D02*
Y1627642D01*
G01Y1622294D02*
Y1621343D01*
G01Y1619145D02*
Y1618193D01*
G01Y1612846D02*
Y1611894D01*
G01Y1615995D02*
Y1615044D01*
G01Y1609696D02*
Y1608744D01*
G01Y1606546D02*
Y1605595D01*
G01X-14537Y1644446D02*
Y1643286D01*
G01Y1647596D02*
Y1646436D01*
G01Y1641296D02*
Y1640137D01*
G01Y1634997D02*
Y1633837D01*
G01Y1638147D02*
Y1636987D01*
G01Y1631848D02*
Y1630688D01*
G01Y1625548D02*
Y1624389D01*
G01Y1628698D02*
Y1627538D01*
G01Y1622399D02*
Y1621239D01*
G01Y1616100D02*
Y1614940D01*
G01Y1619249D02*
Y1618089D01*
G01Y1612950D02*
Y1611790D01*
G01Y1609800D02*
Y1608641D01*
G01Y1606651D02*
Y1605491D01*
G01X-13009Y1644654D02*
Y1643079D01*
G01Y1647803D02*
Y1646228D01*
G01Y1641504D02*
Y1639929D01*
G01Y1635205D02*
Y1633630D01*
G01Y1638354D02*
Y1636780D01*
G01Y1632055D02*
Y1630480D01*
G01Y1625756D02*
Y1624181D01*
G01Y1628906D02*
Y1627331D01*
G01Y1622606D02*
Y1621031D01*
G01Y1616307D02*
Y1614732D01*
G01Y1619457D02*
Y1617882D01*
G01Y1613157D02*
Y1611583D01*
G01Y1606858D02*
Y1605283D01*
G01Y1610008D02*
Y1608433D01*
G01X315Y1645047D02*
Y1644457D01*
G01Y1648197D02*
Y1647606D01*
G01Y1646425D02*
Y1645835D01*
G01Y1641898D02*
Y1641307D01*
G01Y1640126D02*
Y1639535D01*
G01Y1643276D02*
Y1642685D01*
G01Y1635598D02*
Y1635008D01*
G01Y1638748D02*
Y1638157D01*
G01Y1636976D02*
Y1636386D01*
G01Y1632449D02*
Y1631858D01*
G01Y1630677D02*
Y1630087D01*
G01Y1633827D02*
Y1633236D01*
G01Y1626150D02*
Y1625559D01*
G01Y1629299D02*
Y1628709D01*
G01Y1627528D02*
Y1626937D01*
G01Y1623000D02*
Y1622409D01*
G01Y1621228D02*
Y1620638D01*
G01Y1624378D02*
Y1623787D01*
G01Y1616701D02*
Y1616110D01*
G01Y1619850D02*
Y1619260D01*
G01Y1618079D02*
Y1617488D01*
G01Y1613551D02*
Y1612961D01*
G01Y1611780D02*
Y1611189D01*
G01Y1614929D02*
Y1614339D01*
G01Y1607252D02*
Y1606661D01*
G01Y1610402D02*
Y1609811D01*
G01Y1608630D02*
Y1608039D01*
G01X512Y1645047D02*
Y1644457D01*
G01Y1648197D02*
Y1647606D01*
G01Y1646425D02*
Y1645835D01*
G01Y1641898D02*
Y1641307D01*
G01Y1640126D02*
Y1639535D01*
G01Y1643276D02*
Y1642685D01*
G01Y1635598D02*
Y1635008D01*
G01Y1638748D02*
Y1638157D01*
G01Y1636976D02*
Y1636386D01*
G01Y1632449D02*
Y1631858D01*
G01Y1630677D02*
Y1630087D01*
G01Y1633827D02*
Y1633236D01*
G01Y1626150D02*
Y1625559D01*
G01Y1629299D02*
Y1628709D01*
G01Y1627528D02*
Y1626937D01*
G01Y1623000D02*
Y1622409D01*
G01Y1621228D02*
Y1620638D01*
G01Y1624378D02*
Y1623787D01*
G01Y1616701D02*
Y1616110D01*
G01Y1619850D02*
Y1619260D01*
G01Y1618079D02*
Y1617488D01*
G01Y1613551D02*
Y1612961D01*
G01Y1611780D02*
Y1611189D01*
G01Y1614929D02*
Y1614339D01*
G01Y1607252D02*
Y1606661D01*
G01Y1610402D02*
Y1609811D01*
G01Y1608630D02*
Y1608039D01*
G01X709Y1644457D02*
Y1643276D01*
G01Y1647606D02*
Y1646425D01*
G01Y1641307D02*
Y1640126D01*
G01Y1635008D02*
Y1633827D01*
G01Y1638157D02*
Y1636976D01*
G01Y1631858D02*
Y1630677D01*
G01Y1625559D02*
Y1624378D01*
G01Y1628709D02*
Y1627528D01*
G01Y1622409D02*
Y1621228D01*
G01Y1616110D02*
Y1614929D01*
G01Y1619260D02*
Y1618079D01*
G01Y1612961D02*
Y1611780D01*
G01Y1606661D02*
Y1605480D01*
G01Y1609811D02*
Y1608630D01*
G01X1074Y1644457D02*
Y1643276D01*
G01Y1647606D02*
Y1646425D01*
G01Y1641307D02*
Y1640126D01*
G01Y1635008D02*
Y1633827D01*
G01Y1638157D02*
Y1636976D01*
G01Y1631858D02*
Y1630677D01*
G01Y1625559D02*
Y1624378D01*
G01Y1628709D02*
Y1627528D01*
G01Y1622409D02*
Y1621228D01*
G01Y1616110D02*
Y1614929D01*
G01Y1619260D02*
Y1618079D01*
G01Y1612961D02*
Y1611780D01*
G01Y1606661D02*
Y1605480D01*
G01Y1609811D02*
Y1608630D01*
G01X1184Y1644457D02*
Y1643276D01*
G01Y1647606D02*
Y1646425D01*
G01Y1641307D02*
Y1640126D01*
G01Y1635008D02*
Y1633827D01*
G01Y1638157D02*
Y1636976D01*
G01Y1631858D02*
Y1630677D01*
G01Y1625559D02*
Y1624378D01*
G01Y1628709D02*
Y1627528D01*
G01Y1622409D02*
Y1621228D01*
G01Y1616110D02*
Y1614929D01*
G01Y1619260D02*
Y1618079D01*
G01Y1612961D02*
Y1611780D01*
G01Y1606661D02*
Y1605480D01*
G01Y1609811D02*
Y1608630D01*
G01X9965Y1644457D02*
Y1643276D01*
G01Y1647606D02*
Y1646425D01*
G01Y1641307D02*
Y1640126D01*
G01Y1635008D02*
Y1633827D01*
G01Y1638157D02*
Y1636976D01*
G01Y1631858D02*
Y1630677D01*
G01Y1625559D02*
Y1624378D01*
G01Y1628709D02*
Y1627528D01*
G01Y1622409D02*
Y1621228D01*
G01Y1616110D02*
Y1614929D01*
G01Y1619260D02*
Y1618079D01*
G01Y1612961D02*
Y1611780D01*
G01Y1606661D02*
Y1605480D01*
G01Y1609811D02*
Y1608630D01*
G01X10075Y1644457D02*
Y1643276D01*
G01Y1647606D02*
Y1646425D01*
G01Y1641307D02*
Y1640126D01*
G01Y1635008D02*
Y1633827D01*
G01Y1638157D02*
Y1636976D01*
G01Y1631858D02*
Y1630677D01*
G01Y1625559D02*
Y1624378D01*
G01Y1628709D02*
Y1627528D01*
G01Y1622409D02*
Y1621228D01*
G01Y1616110D02*
Y1614929D01*
G01Y1619260D02*
Y1618079D01*
G01Y1612961D02*
Y1611780D01*
G01Y1606661D02*
Y1605480D01*
G01Y1609811D02*
Y1608630D01*
G01X-14677Y1605579D02*
X-14537Y1605491D01*
G01X-14449Y1605579D02*
X-13977Y1605283D01*
G01X-14537Y1605491D02*
X-14147Y1605283D01*
G01X-14537Y1608641D02*
X-14147Y1608433D01*
G01X-14537Y1611790D02*
X-14147Y1611583D01*
G01X-14537Y1614940D02*
X-14147Y1614732D01*
G01X-14537Y1618089D02*
X-14147Y1617882D01*
G01X-14537Y1621239D02*
X-14147Y1621031D01*
G01X-14537Y1624389D02*
X-14147Y1624181D01*
G01X-14537Y1627538D02*
X-14147Y1627331D01*
G01X-14537Y1630688D02*
X-14147Y1630480D01*
G01X-14537Y1633837D02*
X-14147Y1633630D01*
G01X-14677Y1608728D02*
X-14537Y1608641D01*
G01X-14449Y1608728D02*
X-13977Y1608433D01*
G01X-14677Y1611878D02*
X-14537Y1611790D01*
G01X-14449Y1611878D02*
X-13977Y1611583D01*
G01X-14677Y1615028D02*
X-14537Y1614940D01*
G01X-14449Y1615028D02*
X-13977Y1614732D01*
G01X-14677Y1618177D02*
X-14537Y1618089D01*
G01X-14449Y1618177D02*
X-13977Y1617882D01*
G01X-14677Y1621327D02*
X-14537Y1621239D01*
G01X-14449Y1621327D02*
X-13977Y1621031D01*
G01X-14677Y1624476D02*
X-14537Y1624389D01*
G01X-14449Y1624476D02*
X-13977Y1624181D01*
G01X-14677Y1627626D02*
X-14537Y1627538D01*
G01X-14449Y1627626D02*
X-13977Y1627331D01*
G01X-14677Y1630776D02*
X-14537Y1630688D01*
G01X-14449Y1630776D02*
X-13977Y1630480D01*
G01X-14677Y1633925D02*
X-14537Y1633837D01*
G01X-14449Y1633925D02*
X-13977Y1633630D01*
G01X-14677Y1637075D02*
X-14537Y1636987D01*
G01X-14449Y1637075D02*
X-13977Y1636780D01*
G01X-14677Y1640224D02*
X-14537Y1640137D01*
G01X-14449Y1640224D02*
X-13977Y1639929D01*
G01X-14677Y1643374D02*
X-14537Y1643286D01*
G01X-14449Y1643374D02*
X-13977Y1643079D01*
G01X-14677Y1646524D02*
X-14537Y1646436D01*
G01X-14449Y1646524D02*
X-13977Y1646228D01*
G01X-14537Y1636987D02*
X-14147Y1636780D01*
G01X-14537Y1640137D02*
X-14147Y1639929D01*
G01X-14537Y1643286D02*
X-14147Y1643079D01*
G01X-14537Y1646436D02*
X-14147Y1646228D01*
G01X-19469Y1606511D02*
X-18174Y1606525D01*
G01X-18435D02*
X-20801Y1606499D01*
G01X-18174Y1606525D02*
X-17126Y1606536D01*
G01X-19469Y1609660D02*
X-18174Y1609674D01*
G01X-18435D02*
X-20801Y1609648D01*
G01X-18174Y1609674D02*
X-17126Y1609686D01*
G01X-19469Y1612810D02*
X-18174Y1612824D01*
G01X-18435D02*
X-20801Y1612798D01*
G01X-18174Y1612824D02*
X-17126Y1612835D01*
G01X-15985Y1606546D02*
X-14449Y1606563D01*
G01X-14677D02*
X-18174Y1606525D01*
G01X-14677Y1606563D02*
X-16213Y1606546D01*
G01X-15985Y1609696D02*
X-14449Y1609713D01*
G01X-14677D02*
X-18174Y1609674D01*
G01X-14677Y1609713D02*
X-16213Y1609696D01*
G01X-15985Y1612846D02*
X-14449Y1612862D01*
G01X-14677D02*
X-18174Y1612824D01*
G01X-14677Y1612862D02*
X-16213Y1612846D01*
G01X-19469Y1606511D02*
X-20801Y1606499D01*
G01X-19469Y1609660D02*
X-20801Y1609648D01*
G01X-19469Y1612810D02*
X-20801Y1612798D01*
G01X-15985Y1606546D02*
X-17126Y1606536D01*
G01D02*
X-18435Y1606525D01*
G01X-15985Y1609696D02*
X-17126Y1609686D01*
G01D02*
X-18435Y1609674D01*
G01X-15985Y1612846D02*
X-17126Y1612835D01*
G01D02*
X-18435Y1612824D01*
G01X-13009Y1605283D02*
X-14147D01*
G01X12410Y1605480D02*
X315D01*
G01X-14449Y1605579D02*
X-14677D01*
G01X-15985Y1605595D02*
X-16213D01*
G01X-18174Y1605617D02*
X-18435D01*
G01X-18174Y1606525D02*
X-18435D01*
G01X-15985Y1606546D02*
X-16213D01*
G01X-14449Y1606563D02*
X-14677D01*
G01X12410Y1606661D02*
X315D01*
G01X-13009Y1606858D02*
X-14147D01*
G01X512Y1607252D02*
X0D01*
G01X512Y1608039D02*
X0D01*
G01X-13009Y1608433D02*
X-14147D01*
G01X12410Y1608630D02*
X315D01*
G01X-14449Y1608728D02*
X-14677D01*
G01X-15985Y1608744D02*
X-16213D01*
G01X-18174Y1608766D02*
X-18435D01*
G01X-18174Y1609674D02*
X-18435D01*
G01X-15985Y1609696D02*
X-16213D01*
G01X-14449Y1609713D02*
X-14677D01*
G01X12410Y1609811D02*
X315D01*
G01X-13009Y1610008D02*
X-14147D01*
G01X512Y1610402D02*
X0D01*
G01X512Y1611189D02*
X0D01*
G01X-13009Y1611583D02*
X-14147D01*
G01X12410Y1611780D02*
X315D01*
G01X-14449Y1611878D02*
X-14677D01*
G01X-15985Y1611894D02*
X-16213D01*
G01X-18174Y1611916D02*
X-18435D01*
G01X-18174Y1612824D02*
X-18435D01*
G01X-15985Y1612846D02*
X-16213D01*
G01X-14449Y1612862D02*
X-14677D01*
G01X12410Y1612961D02*
X315D01*
G01X-13009Y1613157D02*
X-14147D01*
G01X512Y1613551D02*
X0D01*
G01X512Y1614339D02*
X0D01*
G01X-13009Y1614732D02*
X-14147D01*
G01X12410Y1614929D02*
X315D01*
G01X-14449Y1615028D02*
X-14677D01*
G01X-15985Y1615044D02*
X-16213D01*
G01X-18174Y1615065D02*
X-18435D01*
G01X-18174Y1615974D02*
X-18435D01*
G01X-15985Y1615995D02*
X-16213D01*
G01X-14449Y1616012D02*
X-14677D01*
G01X12410Y1616110D02*
X315D01*
G01X-13009Y1616307D02*
X-14147D01*
G01X512Y1616701D02*
X0D01*
G01X512Y1617488D02*
X0D01*
G01X-13009Y1617882D02*
X-14147D01*
G01X12410Y1618079D02*
X315D01*
G01X-14449Y1618177D02*
X-14677D01*
G01X-15985Y1618193D02*
X-16213D01*
G01X-18174Y1618215D02*
X-18435D01*
G01X-18174Y1619123D02*
X-18435D01*
G01X-19469Y1605631D02*
X-20801Y1605643D01*
G01X-15985Y1605595D02*
X-18435Y1605617D01*
G01X-19469Y1608781D02*
X-20801Y1608793D01*
G01X-15985Y1608744D02*
X-18435Y1608766D01*
G01X-19469Y1611930D02*
X-20801Y1611942D01*
G01X-15985Y1611894D02*
X-18435Y1611916D01*
G01X-19469Y1615080D02*
X-20801Y1615092D01*
G01X-15985Y1615044D02*
X-18435Y1615065D01*
G01X-19469Y1618230D02*
X-20801Y1618241D01*
G01X-15985Y1618193D02*
X-18435Y1618215D01*
G01X-19469Y1621379D02*
X-20801Y1621391D01*
G01X-15985Y1621343D02*
X-18435Y1621365D01*
G01X-15985Y1605595D02*
X-14449Y1605579D01*
G01X-15985Y1608744D02*
X-14449Y1608728D01*
G01X-15985Y1611894D02*
X-14449Y1611878D01*
G01X-15985Y1615044D02*
X-14449Y1615028D01*
G01X-15985Y1618193D02*
X-14449Y1618177D01*
G01X-15985Y1621343D02*
X-14449Y1621327D01*
G01X-15985Y1624493D02*
X-14449Y1624476D01*
G01X-18435Y1605617D02*
X-20801Y1605643D01*
G01X-18435Y1608766D02*
X-20801Y1608793D01*
G01X-18435Y1611916D02*
X-20801Y1611942D01*
G01X-18435Y1615065D02*
X-20801Y1615092D01*
G01X-18435Y1618215D02*
X-20801Y1618241D01*
G01X-18435Y1621365D02*
X-20801Y1621391D01*
G01X-18435Y1624514D02*
X-20801Y1624541D01*
G01X-19469Y1605631D02*
X-16213Y1605595D01*
G01X-18174Y1605617D02*
X-14677Y1605579D01*
G01X-19469Y1608781D02*
X-16213Y1608744D01*
G01X-18174Y1608766D02*
X-14677Y1608728D01*
G01X-19469Y1611930D02*
X-16213Y1611894D01*
G01X-18174Y1611916D02*
X-14677Y1611878D01*
G01X-19469Y1615080D02*
X-16213Y1615044D01*
G01X-18174Y1615065D02*
X-14677Y1615028D01*
G01X-19469Y1618230D02*
X-16213Y1618193D01*
G01X-18174Y1618215D02*
X-14677Y1618177D01*
G01X-19469Y1621379D02*
X-16213Y1621343D01*
G01X-18174Y1621365D02*
X-14677Y1621327D01*
G01X-19469Y1624529D02*
X-16213Y1624493D01*
G01X-18174Y1624514D02*
X-14677Y1624476D01*
G01X-19469Y1615959D02*
X-18174Y1615974D01*
G01X-18435D02*
X-20801Y1615948D01*
G01X-18174Y1615974D02*
X-17126Y1615985D01*
G01X-19469Y1619109D02*
X-18174Y1619123D01*
G01X-18435D02*
X-20801Y1619097D01*
G01X-18174Y1619123D02*
X-17126Y1619135D01*
G01X-19469Y1622259D02*
X-18174Y1622273D01*
G01X-18435D02*
X-20801Y1622247D01*
G01X-18174Y1622273D02*
X-17126Y1622284D01*
G01X-19469Y1625408D02*
X-18174Y1625422D01*
G01X-18435D02*
X-20801Y1625396D01*
G01X-18174Y1625422D02*
X-17126Y1625434D01*
G01X-19469Y1628558D02*
X-18174Y1628572D01*
G01X-18435D02*
X-20801Y1628546D01*
G01X-18174Y1628572D02*
X-17126Y1628583D01*
G01X-19469Y1631707D02*
X-18174Y1631722D01*
G01X-18435D02*
X-20801Y1631696D01*
G01X-18174Y1631722D02*
X-17126Y1631733D01*
G01X-19469Y1634857D02*
X-18174Y1634871D01*
G01X-18435D02*
X-20801Y1634845D01*
G01X-18174Y1634871D02*
X-17126Y1634883D01*
G01X-19469Y1638007D02*
X-18174Y1638021D01*
G01X-18435D02*
X-20801Y1637995D01*
G01X-18174Y1638021D02*
X-17126Y1638032D01*
G01X-19469Y1641156D02*
X-18174Y1641170D01*
G01X-18435D02*
X-20801Y1641144D01*
G01X-18174Y1641170D02*
X-17126Y1641182D01*
G01X-19469Y1644306D02*
X-18174Y1644320D01*
G01X-18435D02*
X-20801Y1644294D01*
G01X-18174Y1644320D02*
X-17126Y1644331D01*
G01X-19469Y1647456D02*
X-18174Y1647470D01*
G01X-18435D02*
X-20801Y1647444D01*
G01X-18174Y1647470D02*
X-17126Y1647481D01*
G01X-15985Y1615995D02*
X-14449Y1616012D01*
G01X-14677D02*
X-18174Y1615974D01*
G01X-14677Y1616012D02*
X-16213Y1615995D01*
G01X-15985Y1619145D02*
X-14449Y1619161D01*
G01X-14677D02*
X-18174Y1619123D01*
G01X-14677Y1619161D02*
X-16213Y1619145D01*
G01X-15985Y1622294D02*
X-14449Y1622311D01*
G01X-14677D02*
X-18174Y1622273D01*
G01X-14677Y1622311D02*
X-16213Y1622294D01*
G01X-15985Y1625444D02*
X-14449Y1625461D01*
G01X-14677D02*
X-18174Y1625422D01*
G01X-14677Y1625461D02*
X-16213Y1625444D01*
G01X-15985Y1628594D02*
X-14449Y1628610D01*
G01X-14677D02*
X-18174Y1628572D01*
G01X-14677Y1628610D02*
X-16213Y1628594D01*
G01X-15985Y1631743D02*
X-14449Y1631760D01*
G01X-14677D02*
X-18174Y1631722D01*
G01X-14677Y1631760D02*
X-16213Y1631743D01*
G01X-15985Y1634893D02*
X-14449Y1634909D01*
G01X-14677D02*
X-18174Y1634871D01*
G01X-14677Y1634909D02*
X-16213Y1634893D01*
G01X-15985Y1638043D02*
X-14449Y1638059D01*
G01X-14677D02*
X-18174Y1638021D01*
G01X-14677Y1638059D02*
X-16213Y1638043D01*
G01X-15985Y1641192D02*
X-14449Y1641209D01*
G01X-14677D02*
X-18174Y1641170D01*
G01X-14677Y1641209D02*
X-16213Y1641192D01*
G01X-15985Y1644342D02*
X-14449Y1644358D01*
G01X-14677D02*
X-18174Y1644320D01*
G01X-14677Y1644358D02*
X-16213Y1644342D01*
G01X-15985Y1647491D02*
X-14449Y1647508D01*
G01X-14677D02*
X-18174Y1647470D01*
G01X-14677Y1647508D02*
X-16213Y1647491D01*
G01X-19469Y1615959D02*
X-20801Y1615948D01*
G01X-19469Y1619109D02*
X-20801Y1619097D01*
G01X-19469Y1622259D02*
X-20801Y1622247D01*
G01X-19469Y1625408D02*
X-20801Y1625396D01*
G01X-19469Y1628558D02*
X-20801Y1628546D01*
G01X-19469Y1631707D02*
X-20801Y1631696D01*
G01X-19469Y1634857D02*
X-20801Y1634845D01*
G01X-19469Y1638007D02*
X-20801Y1637995D01*
G01X-19469Y1641156D02*
X-20801Y1641144D01*
G01X-19469Y1644306D02*
X-20801Y1644294D01*
G01X-19469Y1647456D02*
X-20801Y1647444D01*
G01X-15985Y1615995D02*
X-17126Y1615985D01*
G01D02*
X-18435Y1615974D01*
G01X-15985Y1619145D02*
X-17126Y1619135D01*
G01D02*
X-18435Y1619123D01*
G01X-15985Y1622294D02*
X-17126Y1622284D01*
G01D02*
X-18435Y1622273D01*
G01X-15985Y1625444D02*
X-17126Y1625434D01*
G01D02*
X-18435Y1625422D01*
G01X-15985Y1628594D02*
X-17126Y1628583D01*
G01D02*
X-18435Y1628572D01*
G01X-15985Y1631743D02*
X-17126Y1631733D01*
G01D02*
X-18435Y1631722D01*
G01X-15985Y1634893D02*
X-17126Y1634883D01*
G01D02*
X-18435Y1634871D01*
G01X-15985Y1638043D02*
X-17126Y1638032D01*
G01D02*
X-18435Y1638021D01*
G01X-15985Y1641192D02*
X-17126Y1641182D01*
G01D02*
X-18435Y1641170D01*
G01X-15985Y1644342D02*
X-17126Y1644331D01*
G01D02*
X-18435Y1644320D01*
G01X-15985Y1647491D02*
X-17126Y1647481D01*
G01D02*
X-18435Y1647470D01*
G01X-15985Y1619145D02*
X-16213D01*
G01X-14449Y1619161D02*
X-14677D01*
G01X12410Y1619260D02*
X315D01*
G01X-13009Y1619457D02*
X-14147D01*
G01X512Y1619850D02*
X0D01*
G01X512Y1620638D02*
X0D01*
G01X-13009Y1621031D02*
X-14147D01*
G01X12410Y1621228D02*
X315D01*
G01X-14449Y1621327D02*
X-14677D01*
G01X-15985Y1621343D02*
X-16213D01*
G01X-18174Y1621365D02*
X-18435D01*
G01X-18174Y1622273D02*
X-18435D01*
G01X-15985Y1622294D02*
X-16213D01*
G01X-14449Y1622311D02*
X-14677D01*
G01X12410Y1622409D02*
X315D01*
G01X-13009Y1622606D02*
X-14147D01*
G01X512Y1623000D02*
X0D01*
G01X512Y1623787D02*
X0D01*
G01X-13009Y1624181D02*
X-14147D01*
G01X12410Y1624378D02*
X315D01*
G01X-14449Y1624476D02*
X-14677D01*
G01X-15985Y1624493D02*
X-16213D01*
G01X-18174Y1624514D02*
X-18435D01*
G01X-18174Y1625422D02*
X-18435D01*
G01X-15985Y1625444D02*
X-16213D01*
G01X-14449Y1625461D02*
X-14677D01*
G01X12410Y1625559D02*
X315D01*
G01X-13009Y1625756D02*
X-14147D01*
G01X512Y1626150D02*
X0D01*
G01X512Y1626937D02*
X0D01*
G01X-13009Y1627331D02*
X-14147D01*
G01X12410Y1627528D02*
X315D01*
G01X-14449Y1627626D02*
X-14677D01*
G01X-15985Y1627642D02*
X-16213D01*
G01X-18174Y1627664D02*
X-18435D01*
G01X-18174Y1628572D02*
X-18435D01*
G01X-15985Y1628594D02*
X-16213D01*
G01X-14449Y1628610D02*
X-14677D01*
G01X12410Y1628709D02*
X315D01*
G01X-13009Y1628906D02*
X-14147D01*
G01X512Y1629299D02*
X0D01*
G01X512Y1630087D02*
X0D01*
G01X-13009Y1630480D02*
X-14147D01*
G01X12410Y1630677D02*
X315D01*
G01X-14449Y1630776D02*
X-14677D01*
G01X-15985Y1630792D02*
X-16213D01*
G01X-18174Y1630813D02*
X-18435D01*
G01X-18174Y1631722D02*
X-18435D01*
G01X-15985Y1631743D02*
X-16213D01*
G01X-14449Y1631760D02*
X-14677D01*
G01X12410Y1631858D02*
X315D01*
G01X-13009Y1632055D02*
X-14147D01*
G01X512Y1632449D02*
X0D01*
G01X512Y1633236D02*
X0D01*
G01X-13009Y1633630D02*
X-14147D01*
G01X12410Y1633827D02*
X315D01*
G01X-14449Y1633925D02*
X-14677D01*
G01X-15985Y1633941D02*
X-16213D01*
G01X-18174Y1633963D02*
X-18435D01*
G01X-18174Y1634871D02*
X-18435D01*
G01X-15985Y1634893D02*
X-16213D01*
G01X-14449Y1634909D02*
X-14677D01*
G01X12410Y1635008D02*
X315D01*
G01X-13009Y1635205D02*
X-14147D01*
G01X512Y1635598D02*
X0D01*
G01X512Y1636386D02*
X0D01*
G01X-13009Y1636780D02*
X-14147D01*
G01X12410Y1636976D02*
X315D01*
G01X-14449Y1637075D02*
X-14677D01*
G01X-15985Y1637091D02*
X-16213D01*
G01X-18174Y1637113D02*
X-18435D01*
G01X-18174Y1638021D02*
X-18435D01*
G01X-15985Y1638043D02*
X-16213D01*
G01X-14449Y1638059D02*
X-14677D01*
G01X12410Y1638157D02*
X315D01*
G01X-13009Y1638354D02*
X-14147D01*
G01X512Y1638748D02*
X0D01*
G01X512Y1639535D02*
X0D01*
G01X-13009Y1639929D02*
X-14147D01*
G01X12410Y1640126D02*
X315D01*
G01X-14449Y1640224D02*
X-14677D01*
G01X-15985Y1640241D02*
X-16213D01*
G01X-18174Y1640262D02*
X-18435D01*
G01X-18174Y1641170D02*
X-18435D01*
G01X-15985Y1641192D02*
X-16213D01*
G01X-14449Y1641209D02*
X-14677D01*
G01X12410Y1641307D02*
X315D01*
G01X-13009Y1641504D02*
X-14147D01*
G01X512Y1641898D02*
X0D01*
G01X512Y1642685D02*
X0D01*
G01X-13009Y1643079D02*
X-14147D01*
G01X12410Y1643276D02*
X315D01*
G01X-14449Y1643374D02*
X-14677D01*
G01X-15985Y1643390D02*
X-16213D01*
G01X-18174Y1643412D02*
X-18435D01*
G01X-18174Y1644320D02*
X-18435D01*
G01X-15985Y1644342D02*
X-16213D01*
G01X-14449Y1644358D02*
X-14677D01*
G01X12410Y1644457D02*
X315D01*
G01X-13009Y1644654D02*
X-14147D01*
G01X512Y1645047D02*
X0D01*
G01X512Y1645835D02*
X0D01*
G01X-13009Y1646228D02*
X-14147D01*
G01X12410Y1646425D02*
X315D01*
G01X-14449Y1646524D02*
X-14677D01*
G01X-15985Y1646540D02*
X-16213D01*
G01X-18174Y1646561D02*
X-18435D01*
G01X-18174Y1647470D02*
X-18435D01*
G01X-15985Y1647491D02*
X-16213D01*
G01X-14449Y1647508D02*
X-14677D01*
G01X12410Y1647606D02*
X315D01*
G01X-13009Y1647803D02*
X-14147D01*
G01X512Y1648197D02*
X0D01*
G01X-19469Y1624529D02*
X-20801Y1624541D01*
G01X-15985Y1624493D02*
X-18435Y1624514D01*
G01X-19469Y1627678D02*
X-20801Y1627690D01*
G01X-15985Y1627642D02*
X-18435Y1627664D01*
G01X-19469Y1630828D02*
X-20801Y1630840D01*
G01X-15985Y1630792D02*
X-18435Y1630813D01*
G01X-19469Y1633978D02*
X-20801Y1633989D01*
G01X-15985Y1633941D02*
X-18435Y1633963D01*
G01X-19469Y1637127D02*
X-20801Y1637139D01*
G01X-15985Y1637091D02*
X-18435Y1637113D01*
G01X-19469Y1640277D02*
X-20801Y1640289D01*
G01X-15985Y1640241D02*
X-18435Y1640262D01*
G01X-19469Y1643426D02*
X-20801Y1643438D01*
G01X-15985Y1643390D02*
X-18435Y1643412D01*
G01X-19469Y1646576D02*
X-20801Y1646588D01*
G01X-15985Y1646540D02*
X-18435Y1646561D01*
G01X-15985Y1627642D02*
X-14449Y1627626D01*
G01X-15985Y1630792D02*
X-14449Y1630776D01*
G01X-15985Y1633941D02*
X-14449Y1633925D01*
G01X-15985Y1637091D02*
X-14449Y1637075D01*
G01X-15985Y1640241D02*
X-14449Y1640224D01*
G01X-15985Y1643390D02*
X-14449Y1643374D01*
G01X-15985Y1646540D02*
X-14449Y1646524D01*
G01X-18435Y1627664D02*
X-20801Y1627690D01*
G01X-18435Y1630813D02*
X-20801Y1630840D01*
G01X-18435Y1633963D02*
X-20801Y1633989D01*
G01X-18435Y1637113D02*
X-20801Y1637139D01*
G01X-18435Y1640262D02*
X-20801Y1640289D01*
G01X-18435Y1643412D02*
X-20801Y1643438D01*
G01X-18435Y1646561D02*
X-20801Y1646588D01*
G01X-19469Y1627678D02*
X-16213Y1627642D01*
G01X-18174Y1627664D02*
X-14677Y1627626D01*
G01X-19469Y1630828D02*
X-16213Y1630792D01*
G01X-18174Y1630813D02*
X-14677Y1630776D01*
G01X-19469Y1633978D02*
X-16213Y1633941D01*
G01X-18174Y1633963D02*
X-14677Y1633925D01*
G01X-19469Y1637127D02*
X-16213Y1637091D01*
G01X-18174Y1637113D02*
X-14677Y1637075D01*
G01X-19469Y1640277D02*
X-16213Y1640241D01*
G01X-18174Y1640262D02*
X-14677Y1640224D01*
G01X-19469Y1643426D02*
X-16213Y1643390D01*
G01X-18174Y1643412D02*
X-14677Y1643374D01*
G01X-19469Y1646576D02*
X-16213Y1646540D01*
G01X-18174Y1646561D02*
X-14677Y1646524D01*
G01X-14537Y1603501D02*
X-14677Y1603413D01*
G01X-13977Y1603709D02*
X-14449Y1603413D01*
G01X-14537Y1600352D02*
X-14677Y1600264D01*
G01X-13977Y1600559D02*
X-14449Y1600264D01*
G01X-14537Y1597202D02*
X-14677Y1597114D01*
G01X-13977Y1597409D02*
X-14449Y1597114D01*
G01X-14537Y1594052D02*
X-14677Y1593965D01*
G01X-13977Y1594260D02*
X-14449Y1593965D01*
G01X-14537Y1590903D02*
X-14677Y1590815D01*
G01X-13977Y1591110D02*
X-14449Y1590815D01*
G01X-14537Y1587753D02*
X-14677Y1587665D01*
G01X-13977Y1587961D02*
X-14449Y1587665D01*
G01X-14147Y1603709D02*
X-14537Y1603501D01*
G01X-14147Y1600559D02*
X-14537Y1600352D01*
G01X-14147Y1597409D02*
X-14537Y1597202D01*
G01X-14147Y1594260D02*
X-14537Y1594052D01*
G01X-14147Y1591110D02*
X-14537Y1590903D01*
G01X-14147Y1587961D02*
X-14537Y1587753D01*
G01X-20801Y1603349D02*
Y1602493D01*
G01Y1600200D02*
Y1599344D01*
G01Y1593900D02*
Y1593044D01*
G01Y1597050D02*
Y1596194D01*
G01Y1590751D02*
Y1589895D01*
G01Y1587601D02*
Y1586745D01*
G01X-19469Y1603355D02*
Y1602487D01*
G01Y1600206D02*
Y1599338D01*
G01Y1593906D02*
Y1593039D01*
G01Y1597056D02*
Y1596188D01*
G01Y1590757D02*
Y1589889D01*
G01Y1587607D02*
Y1586739D01*
G01X-18435Y1603375D02*
Y1602467D01*
G01Y1600226D02*
Y1599317D01*
G01Y1593926D02*
Y1593018D01*
G01Y1597076D02*
Y1596168D01*
G01Y1590777D02*
Y1589869D01*
G01Y1587627D02*
Y1586719D01*
G01X-18174Y1603375D02*
Y1602467D01*
G01Y1600226D02*
Y1599317D01*
G01Y1593926D02*
Y1593018D01*
G01Y1597076D02*
Y1596168D01*
G01Y1590777D02*
Y1589869D01*
G01Y1587627D02*
Y1586719D01*
G01X-16213Y1603397D02*
Y1602445D01*
G01Y1600247D02*
Y1599296D01*
G01Y1593948D02*
Y1592996D01*
G01Y1597098D02*
Y1596146D01*
G01Y1590798D02*
Y1589847D01*
G01Y1587649D02*
Y1586697D01*
G01X-15985Y1603397D02*
Y1602445D01*
G01Y1600247D02*
Y1599296D01*
G01Y1593948D02*
Y1592996D01*
G01Y1597098D02*
Y1596146D01*
G01Y1590798D02*
Y1589847D01*
G01Y1587649D02*
Y1586697D01*
G01X-14537Y1603501D02*
Y1602341D01*
G01Y1600352D02*
Y1599192D01*
G01Y1594052D02*
Y1592893D01*
G01Y1597202D02*
Y1596042D01*
G01Y1590903D02*
Y1589743D01*
G01Y1587753D02*
Y1586593D01*
G01X-13009Y1603709D02*
Y1602134D01*
G01Y1597409D02*
Y1595835D01*
G01Y1600559D02*
Y1598984D01*
G01Y1594260D02*
Y1592685D01*
G01Y1587961D02*
Y1586386D01*
G01Y1591110D02*
Y1589535D01*
G01X315Y1604102D02*
Y1603512D01*
G01Y1602331D02*
Y1601740D01*
G01Y1605480D02*
Y1604890D01*
G01Y1597803D02*
Y1597213D01*
G01Y1600953D02*
Y1600362D01*
G01Y1599181D02*
Y1598591D01*
G01Y1594654D02*
Y1594063D01*
G01Y1592882D02*
Y1592291D01*
G01Y1596031D02*
Y1595441D01*
G01Y1588354D02*
Y1587764D01*
G01Y1591504D02*
Y1590913D01*
G01Y1589732D02*
Y1589142D01*
G01Y1586583D02*
Y1585992D01*
G01X512Y1604102D02*
Y1603512D01*
G01Y1602331D02*
Y1601740D01*
G01Y1605480D02*
Y1604890D01*
G01Y1597803D02*
Y1597213D01*
G01Y1600953D02*
Y1600362D01*
G01Y1599181D02*
Y1598591D01*
G01Y1594654D02*
Y1594063D01*
G01Y1592882D02*
Y1592291D01*
G01Y1596031D02*
Y1595441D01*
G01Y1588354D02*
Y1587764D01*
G01Y1591504D02*
Y1590913D01*
G01Y1589732D02*
Y1589142D01*
G01Y1586583D02*
Y1585992D01*
G01X709Y1603512D02*
Y1602331D01*
G01Y1600362D02*
Y1599181D01*
G01Y1594063D02*
Y1592882D01*
G01Y1597213D02*
Y1596031D01*
G01Y1590913D02*
Y1589732D01*
G01Y1587764D02*
Y1586583D01*
G01X1074Y1603512D02*
Y1602331D01*
G01Y1600362D02*
Y1599181D01*
G01Y1594063D02*
Y1592882D01*
G01Y1597213D02*
Y1596031D01*
G01Y1590913D02*
Y1589732D01*
G01Y1587764D02*
Y1586583D01*
G01X1184Y1603512D02*
Y1602331D01*
G01Y1600362D02*
Y1599181D01*
G01Y1594063D02*
Y1592882D01*
G01Y1597213D02*
Y1596031D01*
G01Y1590913D02*
Y1589732D01*
G01Y1587764D02*
Y1586583D01*
G01X9965Y1603512D02*
Y1602331D01*
G01Y1600362D02*
Y1599181D01*
G01Y1594063D02*
Y1592882D01*
G01Y1597213D02*
Y1596031D01*
G01Y1590913D02*
Y1589732D01*
G01Y1587764D02*
Y1586583D01*
G01X10075Y1603512D02*
Y1602331D01*
G01Y1600362D02*
Y1599181D01*
G01Y1594063D02*
Y1592882D01*
G01Y1597213D02*
Y1596031D01*
G01Y1590913D02*
Y1589732D01*
G01Y1587764D02*
Y1586583D01*
G01X-14677Y1586681D02*
X-14537Y1586593D01*
G01X-14449Y1586681D02*
X-13977Y1586386D01*
G01X-14677Y1589831D02*
X-14537Y1589743D01*
G01X-14449Y1589831D02*
X-13977Y1589535D01*
G01X-14677Y1592980D02*
X-14537Y1592893D01*
G01X-14449Y1592980D02*
X-13977Y1592685D01*
G01X-14677Y1596130D02*
X-14537Y1596042D01*
G01X-14449Y1596130D02*
X-13977Y1595835D01*
G01X-14677Y1599280D02*
X-14537Y1599192D01*
G01X-14449Y1599280D02*
X-13977Y1598984D01*
G01X-14677Y1602429D02*
X-14537Y1602341D01*
G01X-14449Y1602429D02*
X-13977Y1602134D01*
G01X-14537Y1586593D02*
X-14147Y1586386D01*
G01X-14537Y1589743D02*
X-14147Y1589535D01*
G01X-14537Y1592893D02*
X-14147Y1592685D01*
G01X-14537Y1596042D02*
X-14147Y1595835D01*
G01X-14537Y1599192D02*
X-14147Y1598984D01*
G01X-14537Y1602341D02*
X-14147Y1602134D01*
G01X-19469Y1587613D02*
X-18174Y1587627D01*
G01X-18435D02*
X-20801Y1587601D01*
G01X-18174Y1587627D02*
X-17126Y1587639D01*
G01X-19469Y1590763D02*
X-18174Y1590777D01*
G01X-18435D02*
X-20801Y1590751D01*
G01X-18174Y1590777D02*
X-17126Y1590788D01*
G01X-19469Y1593912D02*
X-18174Y1593926D01*
G01X-18435D02*
X-20801Y1593900D01*
G01X-18174Y1593926D02*
X-17126Y1593938D01*
G01X-19469Y1597062D02*
X-18174Y1597076D01*
G01X-18435D02*
X-20801Y1597050D01*
G01X-18174Y1597076D02*
X-17126Y1597087D01*
G01X-19469Y1600211D02*
X-18174Y1600226D01*
G01X-18435D02*
X-20801Y1600200D01*
G01X-18174Y1600226D02*
X-17126Y1600237D01*
G01X-19469Y1603361D02*
X-18174Y1603375D01*
G01X-18435D02*
X-20801Y1603349D01*
G01X-18174Y1603375D02*
X-17126Y1603387D01*
G01X-15985Y1587649D02*
X-14449Y1587665D01*
G01X-14677D02*
X-18174Y1587627D01*
G01X-14677Y1587665D02*
X-16213Y1587649D01*
G01X-15985Y1590798D02*
X-14449Y1590815D01*
G01X-14677D02*
X-18174Y1590777D01*
G01X-14677Y1590815D02*
X-16213Y1590798D01*
G01X-15985Y1593948D02*
X-14449Y1593965D01*
G01X-14677D02*
X-18174Y1593926D01*
G01X-14677Y1593965D02*
X-16213Y1593948D01*
G01X-15985Y1597098D02*
X-14449Y1597114D01*
G01X-14677D02*
X-18174Y1597076D01*
G01X-14677Y1597114D02*
X-16213Y1597098D01*
G01X-15985Y1600247D02*
X-14449Y1600264D01*
G01X-14677D02*
X-18174Y1600226D01*
G01X-14677Y1600264D02*
X-16213Y1600247D01*
G01X-15985Y1603397D02*
X-14449Y1603413D01*
G01X-14677D02*
X-18174Y1603375D01*
G01X-14677Y1603413D02*
X-16213Y1603397D01*
G01X-19469Y1587613D02*
X-20801Y1587601D01*
G01X-19469Y1590763D02*
X-20801Y1590751D01*
G01X-19469Y1593912D02*
X-20801Y1593900D01*
G01X-19469Y1597062D02*
X-20801Y1597050D01*
G01X-19469Y1600211D02*
X-20801Y1600200D01*
G01X-19469Y1603361D02*
X-20801Y1603349D01*
G01X-15985Y1587649D02*
X-17126Y1587639D01*
G01X-18435Y1587627D02*
X-17126Y1587639D01*
G01X-15985Y1590798D02*
X-17126Y1590788D01*
G01D02*
X-18435Y1590777D01*
G01X-15985Y1593948D02*
X-17126Y1593938D01*
G01D02*
X-18435Y1593926D01*
G01X-15985Y1597098D02*
X-17126Y1597087D01*
G01D02*
X-18435Y1597076D01*
G01X-15985Y1600247D02*
X-17126Y1600237D01*
G01D02*
X-18435Y1600226D01*
G01X-15985Y1603397D02*
X-17126Y1603387D01*
G01D02*
X-18435Y1603375D01*
G01X512Y1585992D02*
X0D01*
G01X-13009Y1586386D02*
X-14147D01*
G01X12410Y1586583D02*
X315D01*
G01X-14449Y1586681D02*
X-14677D01*
G01X-15985Y1586697D02*
X-16213D01*
G01X-18174Y1586719D02*
X-18435D01*
G01X-18174Y1587627D02*
X-18435D01*
G01X-15985Y1587649D02*
X-16213D01*
G01X-14449Y1587665D02*
X-14677D01*
G01X12410Y1587764D02*
X315D01*
G01X-13009Y1587961D02*
X-14147D01*
G01X512Y1588354D02*
X0D01*
G01X512Y1589142D02*
X0D01*
G01X-13009Y1589535D02*
X-14147D01*
G01X12410Y1589732D02*
X315D01*
G01X-14449Y1589831D02*
X-14677D01*
G01X-15985Y1589847D02*
X-16213D01*
G01X-18174Y1589869D02*
X-18435D01*
G01X-18174Y1590777D02*
X-18435D01*
G01X-15985Y1590798D02*
X-16213D01*
G01X-14449Y1590815D02*
X-14677D01*
G01X12410Y1590913D02*
X315D01*
G01X-13009Y1591110D02*
X-14147D01*
G01X512Y1591504D02*
X0D01*
G01X512Y1592291D02*
X0D01*
G01X-13009Y1592685D02*
X-14147D01*
G01X12410Y1592882D02*
X315D01*
G01X-14449Y1592980D02*
X-14677D01*
G01X-15985Y1592996D02*
X-16213D01*
G01X-18174Y1593018D02*
X-18435D01*
G01X-18174Y1593926D02*
X-18435D01*
G01X-15985Y1593948D02*
X-16213D01*
G01X-14449Y1593965D02*
X-14677D01*
G01X12410Y1594063D02*
X315D01*
G01X-13009Y1594260D02*
X-14147D01*
G01X512Y1594654D02*
X0D01*
G01X512Y1595441D02*
X0D01*
G01X-13009Y1595835D02*
X-14147D01*
G01X12410Y1596031D02*
X315D01*
G01X-14449Y1596130D02*
X-14677D01*
G01X-15985Y1596146D02*
X-16213D01*
G01X-18174Y1596168D02*
X-18435D01*
G01X-18174Y1597076D02*
X-18435D01*
G01X-15985Y1597098D02*
X-16213D01*
G01X-14449Y1597114D02*
X-14677D01*
G01X12410Y1597213D02*
X315D01*
G01X-13009Y1597409D02*
X-14147D01*
G01X512Y1597803D02*
X0D01*
G01X512Y1598591D02*
X0D01*
G01X-13009Y1598984D02*
X-14147D01*
G01X12410Y1599181D02*
X315D01*
G01X-14449Y1599280D02*
X-14677D01*
G01X-15985Y1599296D02*
X-16213D01*
G01X-18174Y1599317D02*
X-18435D01*
G01X-18174Y1600226D02*
X-18435D01*
G01X-15985Y1600247D02*
X-16213D01*
G01X-14449Y1600264D02*
X-14677D01*
G01X12410Y1600362D02*
X315D01*
G01X-13009Y1600559D02*
X-14147D01*
G01X512Y1600953D02*
X0D01*
G01X512Y1601740D02*
X0D01*
G01X-13009Y1602134D02*
X-14147D01*
G01X12410Y1602331D02*
X315D01*
G01X-14449Y1602429D02*
X-14677D01*
G01X-15985Y1602445D02*
X-16213D01*
G01X-18174Y1602467D02*
X-18435D01*
G01X-18174Y1603375D02*
X-18435D01*
G01X-15985Y1603397D02*
X-16213D01*
G01X-14449Y1603413D02*
X-14677D01*
G01X12410Y1603512D02*
X315D01*
G01X-13009Y1603709D02*
X-14147D01*
G01X512Y1604102D02*
X0D01*
G01X512Y1604890D02*
X0D01*
G01X-19469Y1586733D02*
X-20801Y1586745D01*
G01X-15985Y1586697D02*
X-18435Y1586719D01*
G01X-19469Y1589883D02*
X-20801Y1589895D01*
G01X-15985Y1589847D02*
X-18435Y1589869D01*
G01X-19469Y1593033D02*
X-20801Y1593044D01*
G01X-15985Y1592996D02*
X-18435Y1593018D01*
G01X-19469Y1596182D02*
X-20801Y1596194D01*
G01X-15985Y1596146D02*
X-18435Y1596168D01*
G01X-19469Y1599332D02*
X-20801Y1599344D01*
G01X-15985Y1599296D02*
X-18435Y1599317D01*
G01X-19469Y1602481D02*
X-20801Y1602493D01*
G01X-15985Y1602445D02*
X-18435Y1602467D01*
G01X-15985Y1586697D02*
X-14449Y1586681D01*
G01X-15985Y1589847D02*
X-14449Y1589831D01*
G01X-15985Y1592996D02*
X-14449Y1592980D01*
G01X-15985Y1596146D02*
X-14449Y1596130D01*
G01X-15985Y1599296D02*
X-14449Y1599280D01*
G01X-15985Y1602445D02*
X-14449Y1602429D01*
G01X-18435Y1586719D02*
X-20801Y1586745D01*
G01X-18435Y1589869D02*
X-20801Y1589895D01*
G01X-18435Y1593018D02*
X-20801Y1593044D01*
G01X-18435Y1596168D02*
X-20801Y1596194D01*
G01X-18435Y1599317D02*
X-20801Y1599344D01*
G01X-18435Y1602467D02*
X-20801Y1602493D01*
G01X-19469Y1586733D02*
X-16213Y1586697D01*
G01X-18174Y1586719D02*
X-14677Y1586681D01*
G01X-19469Y1589883D02*
X-16213Y1589847D01*
G01X-18174Y1589869D02*
X-14677Y1589831D01*
G01X-19469Y1593033D02*
X-16213Y1592996D01*
G01X-18174Y1593018D02*
X-14677Y1592980D01*
G01X-19469Y1596182D02*
X-16213Y1596146D01*
G01X-18174Y1596168D02*
X-14677Y1596130D01*
G01X-19469Y1599332D02*
X-16213Y1599296D01*
G01X-18174Y1599317D02*
X-14677Y1599280D01*
G01X-19469Y1602481D02*
X-16213Y1602445D01*
G01X-18174Y1602467D02*
X-14677Y1602429D01*
G01X12287Y1703374D02*
X12057Y1703118D01*
G01X12287Y1700224D02*
X12057Y1699969D01*
G01X12287Y1697075D02*
X12057Y1696819D01*
G01X12287Y1693925D02*
X12057Y1693669D01*
G01X12287Y1690776D02*
X12057Y1690520D01*
G01X12287Y1687626D02*
X12057Y1687370D01*
G01X12634Y1703374D02*
X12416Y1703104D01*
G01X12634Y1700224D02*
X12416Y1699954D01*
G01X12634Y1697075D02*
X12416Y1696805D01*
G01X12634Y1693925D02*
X12416Y1693655D01*
G01X12634Y1690776D02*
X12416Y1690506D01*
G01X12634Y1687626D02*
X12416Y1687356D01*
G01X12634Y1684476D02*
X12416Y1684206D01*
G01X12634Y1681327D02*
X12416Y1681057D01*
G01X12634Y1678177D02*
X12416Y1677907D01*
G01X12634Y1675028D02*
X12416Y1674757D01*
G01X12634Y1671878D02*
X12416Y1671608D01*
G01X12634Y1668728D02*
X12416Y1668458D01*
G01X12634Y1665579D02*
X12416Y1665309D01*
G01X12287Y1684476D02*
X12057Y1684220D01*
G01X12287Y1681327D02*
X12057Y1681071D01*
G01X12287Y1678177D02*
X12057Y1677921D01*
G01X12287Y1675028D02*
X12057Y1674772D01*
G01X12287Y1671878D02*
X12057Y1671622D01*
G01X12287Y1668728D02*
X12057Y1668472D01*
G01X12287Y1665579D02*
X12057Y1665323D01*
G01Y1701150D02*
Y1699969D01*
G01Y1704299D02*
Y1703118D01*
G01Y1698000D02*
Y1696819D01*
G01Y1691701D02*
Y1690520D01*
G01Y1694850D02*
Y1693669D01*
G01Y1688551D02*
Y1687370D01*
G01Y1682252D02*
Y1681071D01*
G01Y1685402D02*
Y1684220D01*
G01Y1679102D02*
Y1677921D01*
G01Y1672803D02*
Y1671622D01*
G01Y1675953D02*
Y1674772D01*
G01Y1669654D02*
Y1668472D01*
G01Y1666504D02*
Y1665323D01*
G01X12410Y1701150D02*
Y1699969D01*
G01Y1704299D02*
Y1703118D01*
G01Y1698000D02*
Y1696819D01*
G01Y1691701D02*
Y1690520D01*
G01Y1694850D02*
Y1693669D01*
G01Y1688551D02*
Y1687370D01*
G01Y1682252D02*
Y1681071D01*
G01Y1685402D02*
Y1684220D01*
G01Y1679102D02*
Y1677921D01*
G01Y1672803D02*
Y1671622D01*
G01Y1675953D02*
Y1674772D01*
G01Y1669654D02*
Y1668472D01*
G01Y1666504D02*
Y1665323D01*
G01X13353Y1700894D02*
Y1700224D01*
G01Y1704043D02*
Y1703374D01*
G01Y1697744D02*
Y1697075D01*
G01Y1691445D02*
Y1690776D01*
G01Y1694594D02*
Y1693925D01*
G01Y1688295D02*
Y1687626D01*
G01Y1681996D02*
Y1681327D01*
G01Y1685146D02*
Y1684476D01*
G01Y1678846D02*
Y1678177D01*
G01Y1672547D02*
Y1671878D01*
G01Y1675697D02*
Y1675028D01*
G01Y1669398D02*
Y1668728D01*
G01Y1666248D02*
Y1665579D01*
G01X13701Y1700894D02*
Y1700224D01*
G01Y1704043D02*
Y1703374D01*
G01Y1697744D02*
Y1697075D01*
G01Y1691445D02*
Y1690776D01*
G01Y1694594D02*
Y1693925D01*
G01Y1688295D02*
Y1687626D01*
G01Y1681996D02*
Y1681327D01*
G01Y1685146D02*
Y1684476D01*
G01Y1678846D02*
Y1678177D01*
G01Y1672547D02*
Y1671878D01*
G01Y1675697D02*
Y1675028D01*
G01Y1669398D02*
Y1668728D01*
G01Y1666248D02*
Y1665579D01*
G01X12057Y1666504D02*
X12287Y1666248D01*
G01X12057Y1669654D02*
X12287Y1669398D01*
G01X12057Y1672803D02*
X12287Y1672547D01*
G01X12057Y1675953D02*
X12287Y1675697D01*
G01X12057Y1679102D02*
X12287Y1678846D01*
G01X12416Y1666518D02*
X12634Y1666248D01*
G01X12416Y1669668D02*
X12634Y1669398D01*
G01X12416Y1672817D02*
X12634Y1672547D01*
G01X12416Y1675967D02*
X12634Y1675697D01*
G01X12416Y1679117D02*
X12634Y1678846D01*
G01X12416Y1682266D02*
X12634Y1681996D01*
G01X12416Y1685416D02*
X12634Y1685146D01*
G01X12416Y1688565D02*
X12634Y1688295D01*
G01X12416Y1691715D02*
X12634Y1691445D01*
G01X12416Y1694865D02*
X12634Y1694594D01*
G01X12416Y1698014D02*
X12634Y1697744D01*
G01X12416Y1701164D02*
X12634Y1700894D01*
G01X12416Y1704313D02*
X12634Y1704043D01*
G01X12057Y1682252D02*
X12287Y1681996D01*
G01X12057Y1685402D02*
X12287Y1685146D01*
G01X12057Y1688551D02*
X12287Y1688295D01*
G01X12057Y1691701D02*
X12287Y1691445D01*
G01X12057Y1694850D02*
X12287Y1694594D01*
G01X12057Y1698000D02*
X12287Y1697744D01*
G01X12057Y1701150D02*
X12287Y1700894D01*
G01X12057Y1704299D02*
X12287Y1704043D01*
G01X13701Y1665579D02*
X12287D01*
G01X13701Y1666248D02*
X12287D01*
G01X13701Y1668728D02*
X12287D01*
G01X13701Y1669398D02*
X12287D01*
G01X13701Y1671878D02*
X12287D01*
G01X13701Y1672547D02*
X12287D01*
G01X13701Y1675028D02*
X12287D01*
G01X13701Y1675697D02*
X12287D01*
G01X13701Y1678177D02*
X12287D01*
G01X13701Y1678846D02*
X12287D01*
G01X13701Y1681327D02*
X12287D01*
G01X13701Y1681996D02*
X12287D01*
G01X13701Y1684476D02*
X12287D01*
G01X13701Y1685146D02*
X12287D01*
G01X13701Y1687626D02*
X12287D01*
G01X13701Y1688295D02*
X12287D01*
G01X13701Y1690776D02*
X12287D01*
G01X13701Y1691445D02*
X12287D01*
G01X13701Y1693925D02*
X12287D01*
G01X13701Y1694594D02*
X12287D01*
G01X13701Y1697075D02*
X12287D01*
G01X13701Y1697744D02*
X12287D01*
G01X13701Y1700224D02*
X12287D01*
G01X13701Y1700894D02*
X12287D01*
G01X13701Y1703374D02*
X12287D01*
G01X13701Y1704043D02*
X12287D01*
G01X12634Y1719122D02*
X12416Y1718852D01*
G01X12634Y1715972D02*
X12416Y1715702D01*
G01X12634Y1712823D02*
X12416Y1712553D01*
G01X12634Y1709673D02*
X12416Y1709403D01*
G01X12634Y1706524D02*
X12416Y1706254D01*
G01X12287Y1719122D02*
X12057Y1718866D01*
G01X12287Y1715972D02*
X12057Y1715717D01*
G01X12287Y1712823D02*
X12057Y1712567D01*
G01X12287Y1709673D02*
X12057Y1709417D01*
G01X12287Y1706524D02*
X12057Y1706268D01*
G01Y1720047D02*
Y1718866D01*
G01Y1716898D02*
Y1715717D01*
G01Y1710598D02*
Y1709417D01*
G01Y1713748D02*
Y1712567D01*
G01Y1707449D02*
Y1706268D01*
G01X12410Y1720047D02*
Y1718866D01*
G01Y1716898D02*
Y1715717D01*
G01Y1710598D02*
Y1709417D01*
G01Y1713748D02*
Y1712567D01*
G01Y1707449D02*
Y1706268D01*
G01X13353Y1719791D02*
Y1719122D01*
G01Y1716642D02*
Y1715972D01*
G01Y1710343D02*
Y1709673D01*
G01Y1713492D02*
Y1712823D01*
G01Y1707193D02*
Y1706524D01*
G01X13701Y1719791D02*
Y1719122D01*
G01Y1716642D02*
Y1715972D01*
G01Y1710343D02*
Y1709673D01*
G01Y1713492D02*
Y1712823D01*
G01Y1707193D02*
Y1706524D01*
G01X12416Y1707463D02*
X12634Y1707193D01*
G01X12416Y1710613D02*
X12634Y1710343D01*
G01X12416Y1713762D02*
X12634Y1713492D01*
G01X12416Y1716912D02*
X12634Y1716642D01*
G01X12416Y1720061D02*
X12634Y1719791D01*
G01X12057Y1707449D02*
X12287Y1707193D01*
G01X12057Y1710598D02*
X12287Y1710343D01*
G01X12057Y1713748D02*
X12287Y1713492D01*
G01X12057Y1716898D02*
X12287Y1716642D01*
G01X12057Y1720047D02*
X12287Y1719791D01*
G01X13701Y1706524D02*
X12287D01*
G01X13701Y1707193D02*
X12287D01*
G01X13701Y1709673D02*
X12287D01*
G01X13701Y1710343D02*
X12287D01*
G01X13701Y1712823D02*
X12287D01*
G01X13701Y1713492D02*
X12287D01*
G01X13701Y1715972D02*
X12287D01*
G01X13701Y1716642D02*
X12287D01*
G01X13701Y1719122D02*
X12287D01*
G01X13701Y1719791D02*
X12287D01*
G01X12634Y1662429D02*
X12416Y1662159D01*
G01X12287Y1662429D02*
X12057Y1662173D01*
G01X19685Y1652921D02*
X17717Y1650953D01*
G01X12057Y1663354D02*
Y1662173D01*
G01X12410Y1663354D02*
Y1662173D01*
G01X13353Y1663098D02*
Y1662429D01*
G01X13701Y1663098D02*
Y1662429D01*
G01X19685Y1656858D02*
Y1652921D01*
G01X12057Y1663354D02*
X12287Y1663098D01*
G01X12416Y1663369D02*
X12634Y1663098D01*
G01X17717Y1658827D02*
X19685Y1656858D01*
G01X13701Y1662429D02*
X12287D01*
G01X13701Y1663098D02*
X12287D01*
G01X17323Y1650559D02*
G03Y1659220I0J4331D01*
G01X39236Y1654469D02*
X35827Y1652500D01*
G01Y1650768D02*
Y1652500D01*
G01Y1651871D02*
X40547Y1647230D01*
G01X-14537Y1704289D02*
X-14677Y1704201D01*
G01X-13977Y1704496D02*
X-14449Y1704201D01*
G01X-14537Y1701139D02*
X-14677Y1701051D01*
G01X-13977Y1701346D02*
X-14449Y1701051D01*
G01X-14537Y1697989D02*
X-14677Y1697902D01*
G01X-13977Y1698197D02*
X-14449Y1697902D01*
G01X-14537Y1694840D02*
X-14677Y1694752D01*
G01X-13977Y1695047D02*
X-14449Y1694752D01*
G01X-14537Y1691690D02*
X-14677Y1691602D01*
G01X-13977Y1691898D02*
X-14449Y1691602D01*
G01X-14537Y1688541D02*
X-14677Y1688453D01*
G01X-13977Y1688748D02*
X-14449Y1688453D01*
G01X-14537Y1685391D02*
X-14677Y1685303D01*
G01X-13977Y1685598D02*
X-14449Y1685303D01*
G01X-14537Y1682241D02*
X-14677Y1682154D01*
G01X-13977Y1682449D02*
X-14449Y1682154D01*
G01X-14537Y1679092D02*
X-14677Y1679004D01*
G01X-13977Y1679299D02*
X-14449Y1679004D01*
G01X-14537Y1675942D02*
X-14677Y1675854D01*
G01X-13977Y1676150D02*
X-14449Y1675854D01*
G01X-14537Y1672793D02*
X-14677Y1672705D01*
G01X-13977Y1673000D02*
X-14449Y1672705D01*
G01X-14537Y1669643D02*
X-14677Y1669555D01*
G01X-13977Y1669850D02*
X-14449Y1669555D01*
G01X-14537Y1666493D02*
X-14677Y1666406D01*
G01X-13977Y1666701D02*
X-14449Y1666406D01*
G01X-14147Y1704496D02*
X-14537Y1704289D01*
G01X-14147Y1701346D02*
X-14537Y1701139D01*
G01X-14147Y1698197D02*
X-14537Y1697989D01*
G01X-14147Y1695047D02*
X-14537Y1694840D01*
G01X-14147Y1691898D02*
X-14537Y1691690D01*
G01X-14147Y1688748D02*
X-14537Y1688541D01*
G01X-14147Y1685598D02*
X-14537Y1685391D01*
G01X-14147Y1682449D02*
X-14537Y1682241D01*
G01X-14147Y1679299D02*
X-14537Y1679092D01*
G01X-14147Y1676150D02*
X-14537Y1675942D01*
G01X-14147Y1673000D02*
X-14537Y1672793D01*
G01X-14147Y1669850D02*
X-14537Y1669643D01*
G01X-14147Y1666701D02*
X-14537Y1666493D01*
G01X-20801Y1700987D02*
Y1700131D01*
G01Y1704137D02*
Y1703281D01*
G01Y1697837D02*
Y1696981D01*
G01Y1691538D02*
Y1690682D01*
G01Y1694688D02*
Y1693832D01*
G01Y1688389D02*
Y1687533D01*
G01Y1682089D02*
Y1681233D01*
G01Y1685239D02*
Y1684383D01*
G01Y1678940D02*
Y1678084D01*
G01Y1672641D02*
Y1671785D01*
G01Y1675790D02*
Y1674934D01*
G01Y1669491D02*
Y1668635D01*
G01Y1666341D02*
Y1665485D01*
G01X-19469Y1700993D02*
Y1700125D01*
G01Y1704143D02*
Y1703275D01*
G01Y1697843D02*
Y1696976D01*
G01Y1691544D02*
Y1690676D01*
G01Y1694694D02*
Y1693826D01*
G01Y1688394D02*
Y1687527D01*
G01Y1682095D02*
Y1681228D01*
G01Y1685245D02*
Y1684377D01*
G01Y1678946D02*
Y1678078D01*
G01Y1672646D02*
Y1671779D01*
G01Y1675796D02*
Y1674928D01*
G01Y1669497D02*
Y1668629D01*
G01Y1666347D02*
Y1665480D01*
G01X-18435Y1701013D02*
Y1700105D01*
G01Y1704163D02*
Y1703254D01*
G01Y1697863D02*
Y1696955D01*
G01Y1691564D02*
Y1690656D01*
G01Y1694714D02*
Y1693806D01*
G01Y1688415D02*
Y1687506D01*
G01Y1682115D02*
Y1681207D01*
G01Y1685265D02*
Y1684357D01*
G01Y1678966D02*
Y1678057D01*
G01Y1672667D02*
Y1671758D01*
G01Y1675816D02*
Y1674908D01*
G01Y1669517D02*
Y1668609D01*
G01Y1666367D02*
Y1665459D01*
G01X-18174Y1701013D02*
Y1700105D01*
G01Y1704163D02*
Y1703254D01*
G01Y1697863D02*
Y1696955D01*
G01Y1691564D02*
Y1690656D01*
G01Y1694714D02*
Y1693806D01*
G01Y1688415D02*
Y1687506D01*
G01Y1682115D02*
Y1681207D01*
G01Y1685265D02*
Y1684357D01*
G01Y1678966D02*
Y1678057D01*
G01Y1672667D02*
Y1671758D01*
G01Y1675816D02*
Y1674908D01*
G01Y1669517D02*
Y1668609D01*
G01Y1666367D02*
Y1665459D01*
G01X-16213Y1701035D02*
Y1700083D01*
G01Y1704184D02*
Y1703233D01*
G01Y1697885D02*
Y1696933D01*
G01Y1691586D02*
Y1690634D01*
G01Y1694735D02*
Y1693784D01*
G01Y1688436D02*
Y1687485D01*
G01Y1682137D02*
Y1681185D01*
G01Y1685287D02*
Y1684335D01*
G01Y1678987D02*
Y1678036D01*
G01Y1672688D02*
Y1671737D01*
G01Y1675838D02*
Y1674886D01*
G01Y1669539D02*
Y1668587D01*
G01Y1666389D02*
Y1665437D01*
G01X-15985Y1701035D02*
Y1700083D01*
G01Y1704184D02*
Y1703233D01*
G01Y1697885D02*
Y1696933D01*
G01Y1691586D02*
Y1690634D01*
G01Y1694735D02*
Y1693784D01*
G01Y1688436D02*
Y1687485D01*
G01Y1682137D02*
Y1681185D01*
G01Y1685287D02*
Y1684335D01*
G01Y1678987D02*
Y1678036D01*
G01Y1672688D02*
Y1671737D01*
G01Y1675838D02*
Y1674886D01*
G01Y1669539D02*
Y1668587D01*
G01Y1666389D02*
Y1665437D01*
G01X-14537Y1701139D02*
Y1699979D01*
G01Y1704289D02*
Y1703129D01*
G01Y1697989D02*
Y1696830D01*
G01Y1691690D02*
Y1690530D01*
G01Y1694840D02*
Y1693680D01*
G01Y1688541D02*
Y1687381D01*
G01Y1682241D02*
Y1681081D01*
G01Y1685391D02*
Y1684231D01*
G01Y1679092D02*
Y1677932D01*
G01Y1672793D02*
Y1671633D01*
G01Y1675942D02*
Y1674782D01*
G01Y1669643D02*
Y1668483D01*
G01Y1666493D02*
Y1665333D01*
G01X-13009Y1701346D02*
Y1699772D01*
G01Y1704496D02*
Y1702921D01*
G01Y1698197D02*
Y1696622D01*
G01Y1691898D02*
Y1690323D01*
G01Y1695047D02*
Y1693472D01*
G01Y1688748D02*
Y1687173D01*
G01Y1682449D02*
Y1680874D01*
G01Y1685598D02*
Y1684024D01*
G01Y1679299D02*
Y1677724D01*
G01Y1673000D02*
Y1671425D01*
G01Y1676150D02*
Y1674575D01*
G01Y1669850D02*
Y1668276D01*
G01X315Y1701740D02*
Y1701150D01*
G01Y1704890D02*
Y1704299D01*
G01Y1703118D02*
Y1702528D01*
G01Y1698591D02*
Y1698000D01*
G01Y1696819D02*
Y1696228D01*
G01Y1699969D02*
Y1699378D01*
G01Y1692291D02*
Y1691701D01*
G01Y1695441D02*
Y1694850D01*
G01Y1693669D02*
Y1693079D01*
G01Y1689142D02*
Y1688551D01*
G01Y1687370D02*
Y1686780D01*
G01Y1690520D02*
Y1689929D01*
G01Y1682843D02*
Y1682252D01*
G01Y1685992D02*
Y1685402D01*
G01Y1684220D02*
Y1683630D01*
G01Y1679693D02*
Y1679102D01*
G01Y1677921D02*
Y1677331D01*
G01Y1681071D02*
Y1680480D01*
G01Y1673394D02*
Y1672803D01*
G01Y1676543D02*
Y1675953D01*
G01Y1674772D02*
Y1674181D01*
G01Y1670244D02*
Y1669654D01*
G01Y1668472D02*
Y1667882D01*
G01Y1671622D02*
Y1671031D01*
G01Y1667094D02*
Y1666504D01*
G01X512Y1701740D02*
Y1701150D01*
G01Y1704890D02*
Y1704299D01*
G01Y1703118D02*
Y1702528D01*
G01Y1698591D02*
Y1698000D01*
G01Y1696819D02*
Y1696228D01*
G01Y1699969D02*
Y1699378D01*
G01Y1692291D02*
Y1691701D01*
G01Y1695441D02*
Y1694850D01*
G01Y1693669D02*
Y1693079D01*
G01Y1689142D02*
Y1688551D01*
G01Y1687370D02*
Y1686780D01*
G01Y1690520D02*
Y1689929D01*
G01Y1682843D02*
Y1682252D01*
G01Y1685992D02*
Y1685402D01*
G01Y1684220D02*
Y1683630D01*
G01Y1679693D02*
Y1679102D01*
G01Y1677921D02*
Y1677331D01*
G01Y1681071D02*
Y1680480D01*
G01Y1673394D02*
Y1672803D01*
G01Y1676543D02*
Y1675953D01*
G01Y1674772D02*
Y1674181D01*
G01Y1670244D02*
Y1669654D01*
G01Y1668472D02*
Y1667882D01*
G01Y1671622D02*
Y1671031D01*
G01Y1667094D02*
Y1666504D01*
G01X709Y1701150D02*
Y1699969D01*
G01Y1704299D02*
Y1703118D01*
G01Y1698000D02*
Y1696819D01*
G01Y1691701D02*
Y1690520D01*
G01Y1694850D02*
Y1693669D01*
G01Y1688551D02*
Y1687370D01*
G01Y1682252D02*
Y1681071D01*
G01Y1685402D02*
Y1684220D01*
G01Y1679102D02*
Y1677921D01*
G01Y1672803D02*
Y1671622D01*
G01Y1675953D02*
Y1674772D01*
G01Y1669654D02*
Y1668472D01*
G01Y1666504D02*
Y1665323D01*
G01X1074Y1701150D02*
Y1699969D01*
G01Y1704299D02*
Y1703118D01*
G01Y1698000D02*
Y1696819D01*
G01Y1691701D02*
Y1690520D01*
G01Y1694850D02*
Y1693669D01*
G01Y1688551D02*
Y1687370D01*
G01Y1682252D02*
Y1681071D01*
G01Y1685402D02*
Y1684220D01*
G01Y1679102D02*
Y1677921D01*
G01Y1672803D02*
Y1671622D01*
G01Y1675953D02*
Y1674772D01*
G01Y1669654D02*
Y1668472D01*
G01Y1666504D02*
Y1665323D01*
G01X1184Y1701150D02*
Y1699969D01*
G01Y1704299D02*
Y1703118D01*
G01Y1698000D02*
Y1696819D01*
G01Y1691701D02*
Y1690520D01*
G01Y1694850D02*
Y1693669D01*
G01Y1688551D02*
Y1687370D01*
G01Y1682252D02*
Y1681071D01*
G01Y1685402D02*
Y1684220D01*
G01Y1679102D02*
Y1677921D01*
G01Y1672803D02*
Y1671622D01*
G01Y1675953D02*
Y1674772D01*
G01Y1669654D02*
Y1668472D01*
G01Y1666504D02*
Y1665323D01*
G01X9965Y1701150D02*
Y1699969D01*
G01Y1704299D02*
Y1703118D01*
G01Y1698000D02*
Y1696819D01*
G01Y1691701D02*
Y1690520D01*
G01Y1694850D02*
Y1693669D01*
G01Y1688551D02*
Y1687370D01*
G01Y1682252D02*
Y1681071D01*
G01Y1685402D02*
Y1684220D01*
G01Y1679102D02*
Y1677921D01*
G01Y1672803D02*
Y1671622D01*
G01Y1675953D02*
Y1674772D01*
G01Y1669654D02*
Y1668472D01*
G01Y1666504D02*
Y1665323D01*
G01X10075Y1701150D02*
Y1699969D01*
G01Y1704299D02*
Y1703118D01*
G01Y1698000D02*
Y1696819D01*
G01Y1691701D02*
Y1690520D01*
G01Y1694850D02*
Y1693669D01*
G01Y1688551D02*
Y1687370D01*
G01Y1682252D02*
Y1681071D01*
G01Y1685402D02*
Y1684220D01*
G01Y1679102D02*
Y1677921D01*
G01Y1672803D02*
Y1671622D01*
G01Y1675953D02*
Y1674772D01*
G01Y1669654D02*
Y1668472D01*
G01Y1666504D02*
Y1665323D01*
G01X-14677Y1665421D02*
X-14537Y1665333D01*
G01X-14677Y1668571D02*
X-14537Y1668483D01*
G01X-14449Y1668571D02*
X-13977Y1668276D01*
G01X-14677Y1671720D02*
X-14537Y1671633D01*
G01X-14449Y1671720D02*
X-13977Y1671425D01*
G01X-14677Y1674870D02*
X-14537Y1674782D01*
G01X-14449Y1674870D02*
X-13977Y1674575D01*
G01X-14677Y1678020D02*
X-14537Y1677932D01*
G01X-14449Y1678020D02*
X-13977Y1677724D01*
G01X-14677Y1681169D02*
X-14537Y1681081D01*
G01X-14449Y1681169D02*
X-13977Y1680874D01*
G01X-14677Y1684319D02*
X-14537Y1684231D01*
G01X-14449Y1684319D02*
X-13977Y1684024D01*
G01X-14677Y1687469D02*
X-14537Y1687381D01*
G01X-14449Y1687469D02*
X-13977Y1687173D01*
G01X-14677Y1690618D02*
X-14537Y1690530D01*
G01X-14449Y1690618D02*
X-13977Y1690323D01*
G01X-14677Y1693768D02*
X-14537Y1693680D01*
G01X-14449Y1693768D02*
X-13977Y1693472D01*
G01X-14677Y1696917D02*
X-14537Y1696830D01*
G01X-14449Y1696917D02*
X-13977Y1696622D01*
G01X-14537Y1668483D02*
X-14147Y1668276D01*
G01X-14537Y1671633D02*
X-14147Y1671425D01*
G01X-14537Y1674782D02*
X-14147Y1674575D01*
G01X-14537Y1677932D02*
X-14147Y1677724D01*
G01X-14537Y1681081D02*
X-14147Y1680874D01*
G01X-14537Y1684231D02*
X-14147Y1684024D01*
G01X-14537Y1687381D02*
X-14147Y1687173D01*
G01X-14537Y1690530D02*
X-14147Y1690323D01*
G01X-14537Y1693680D02*
X-14147Y1693472D01*
G01X-14537Y1696830D02*
X-14147Y1696622D01*
G01X-14537Y1699979D02*
X-14147Y1699772D01*
G01X-14537Y1703129D02*
X-14147Y1702921D01*
G01X-14677Y1700067D02*
X-14537Y1699979D01*
G01X-14449Y1700067D02*
X-13977Y1699772D01*
G01X-14677Y1703217D02*
X-14537Y1703129D01*
G01X-14449Y1703217D02*
X-13977Y1702921D01*
G01X-19469Y1666353D02*
X-18174Y1666367D01*
G01X-18435D02*
X-20801Y1666341D01*
G01X-18174Y1666367D02*
X-17126Y1666379D01*
G01X-19469Y1669503D02*
X-18174Y1669517D01*
G01X-18435D02*
X-20801Y1669491D01*
G01X-18174Y1669517D02*
X-17126Y1669528D01*
G01X-19469Y1672652D02*
X-18174Y1672667D01*
G01X-18435D02*
X-20801Y1672641D01*
G01X-18174Y1672667D02*
X-17126Y1672678D01*
G01X-19469Y1675802D02*
X-18174Y1675816D01*
G01X-18435D02*
X-20801Y1675790D01*
G01X-18174Y1675816D02*
X-17126Y1675828D01*
G01X-19469Y1678952D02*
X-18174Y1678966D01*
G01X-18435D02*
X-20801Y1678940D01*
G01X-18174Y1678966D02*
X-17126Y1678977D01*
G01X-19469Y1682101D02*
X-18174Y1682115D01*
G01X-18435D02*
X-20801Y1682089D01*
G01X-18174Y1682115D02*
X-17126Y1682127D01*
G01X-19469Y1685251D02*
X-18174Y1685265D01*
G01X-18435D02*
X-20801Y1685239D01*
G01X-18174Y1685265D02*
X-17126Y1685276D01*
G01X-19469Y1688400D02*
X-18174Y1688415D01*
G01X-18435D02*
X-20801Y1688389D01*
G01X-18174Y1688415D02*
X-17126Y1688426D01*
G01X-15985Y1666389D02*
X-14449Y1666406D01*
G01X-14677D02*
X-18174Y1666367D01*
G01X-14677Y1666406D02*
X-16213Y1666389D01*
G01X-15985Y1669539D02*
X-14449Y1669555D01*
G01X-14677D02*
X-18174Y1669517D01*
G01X-14677Y1669555D02*
X-16213Y1669539D01*
G01X-15985Y1672688D02*
X-14449Y1672705D01*
G01X-14677D02*
X-18174Y1672667D01*
G01X-14677Y1672705D02*
X-16213Y1672688D01*
G01X-15985Y1675838D02*
X-14449Y1675854D01*
G01X-14677D02*
X-18174Y1675816D01*
G01X-14677Y1675854D02*
X-16213Y1675838D01*
G01X-15985Y1678987D02*
X-14449Y1679004D01*
G01X-14677D02*
X-18174Y1678966D01*
G01X-14677Y1679004D02*
X-16213Y1678987D01*
G01X-15985Y1682137D02*
X-14449Y1682154D01*
G01X-14677D02*
X-18174Y1682115D01*
G01X-14677Y1682154D02*
X-16213Y1682137D01*
G01X-15985Y1685287D02*
X-14449Y1685303D01*
G01X-14677D02*
X-18174Y1685265D01*
G01X-14677Y1685303D02*
X-16213Y1685287D01*
G01X-15985Y1688436D02*
X-14449Y1688453D01*
G01X-14677D02*
X-18174Y1688415D01*
G01X-14677Y1688453D02*
X-16213Y1688436D01*
G01X-19469Y1666353D02*
X-20801Y1666341D01*
G01X-19469Y1669503D02*
X-20801Y1669491D01*
G01X-19469Y1672652D02*
X-20801Y1672641D01*
G01X-19469Y1675802D02*
X-20801Y1675790D01*
G01X-19469Y1678952D02*
X-20801Y1678940D01*
G01X-19469Y1682101D02*
X-20801Y1682089D01*
G01X-19469Y1685251D02*
X-20801Y1685239D01*
G01X-19469Y1688400D02*
X-20801Y1688389D01*
G01X-15985Y1666389D02*
X-17126Y1666379D01*
G01D02*
X-18435Y1666367D01*
G01X-15985Y1669539D02*
X-17126Y1669528D01*
G01D02*
X-18435Y1669517D01*
G01X-15985Y1672688D02*
X-17126Y1672678D01*
G01D02*
X-18435Y1672667D01*
G01X-15985Y1675838D02*
X-17126Y1675828D01*
G01D02*
X-18435Y1675816D01*
G01X-15985Y1678987D02*
X-17126Y1678977D01*
G01X-18435Y1678966D02*
X-17126Y1678977D01*
G01X-15985Y1682137D02*
X-17126Y1682127D01*
G01D02*
X-18435Y1682115D01*
G01X-15985Y1685287D02*
X-17126Y1685276D01*
G01D02*
X-18435Y1685265D01*
G01X-15985Y1688436D02*
X-17126Y1688426D01*
G01D02*
X-18435Y1688415D01*
G01X12410Y1665323D02*
X315D01*
G01X-14449Y1665421D02*
X-14677D01*
G01X-15985Y1665437D02*
X-16213D01*
G01X-18174Y1665459D02*
X-18435D01*
G01X-18174Y1666367D02*
X-18435D01*
G01X-15985Y1666389D02*
X-16213D01*
G01X-14449Y1666406D02*
X-14677D01*
G01X12410Y1666504D02*
X315D01*
G01X-13009Y1666701D02*
X-14147D01*
G01X512Y1667094D02*
X0D01*
G01X512Y1667882D02*
X0D01*
G01X-13009Y1668276D02*
X-14147D01*
G01X12410Y1668472D02*
X315D01*
G01X-14449Y1668571D02*
X-14677D01*
G01X-15985Y1668587D02*
X-16213D01*
G01X-18174Y1668609D02*
X-18435D01*
G01X-18174Y1669517D02*
X-18435D01*
G01X-15985Y1669539D02*
X-16213D01*
G01X-14449Y1669555D02*
X-14677D01*
G01X12410Y1669654D02*
X315D01*
G01X-13009Y1669850D02*
X-14147D01*
G01X512Y1670244D02*
X0D01*
G01X512Y1671031D02*
X0D01*
G01X-13009Y1671425D02*
X-14147D01*
G01X12410Y1671622D02*
X315D01*
G01X-14449Y1671720D02*
X-14677D01*
G01X-15985Y1671737D02*
X-16213D01*
G01X-18174Y1671758D02*
X-18435D01*
G01X-18174Y1672667D02*
X-18435D01*
G01X-15985Y1672688D02*
X-16213D01*
G01X-14449Y1672705D02*
X-14677D01*
G01X12410Y1672803D02*
X315D01*
G01X-13009Y1673000D02*
X-14147D01*
G01X512Y1673394D02*
X0D01*
G01X512Y1674181D02*
X0D01*
G01X-13009Y1674575D02*
X-14147D01*
G01X12410Y1674772D02*
X315D01*
G01X-14449Y1674870D02*
X-14677D01*
G01X-15985Y1674886D02*
X-16213D01*
G01X-18174Y1674908D02*
X-18435D01*
G01X-18174Y1675816D02*
X-18435D01*
G01X-15985Y1675838D02*
X-16213D01*
G01X-14449Y1675854D02*
X-14677D01*
G01X12410Y1675953D02*
X315D01*
G01X-13009Y1676150D02*
X-14147D01*
G01X512Y1676543D02*
X0D01*
G01X512Y1677331D02*
X0D01*
G01X-13009Y1677724D02*
X-14147D01*
G01X12410Y1677921D02*
X315D01*
G01X-14449Y1678020D02*
X-14677D01*
G01X-15985Y1678036D02*
X-16213D01*
G01X-18174Y1678057D02*
X-18435D01*
G01X-18174Y1678966D02*
X-18435D01*
G01X-15985Y1678987D02*
X-16213D01*
G01X-14449Y1679004D02*
X-14677D01*
G01X12410Y1679102D02*
X315D01*
G01X-13009Y1679299D02*
X-14147D01*
G01X512Y1679693D02*
X0D01*
G01X512Y1680480D02*
X0D01*
G01X-13009Y1680874D02*
X-14147D01*
G01X12410Y1681071D02*
X315D01*
G01X-14449Y1681169D02*
X-14677D01*
G01X-15985Y1681185D02*
X-16213D01*
G01X-18174Y1681207D02*
X-18435D01*
G01X-18174Y1682115D02*
X-18435D01*
G01X-15985Y1682137D02*
X-16213D01*
G01X-14449Y1682154D02*
X-14677D01*
G01X12410Y1682252D02*
X315D01*
G01X-13009Y1682449D02*
X-14147D01*
G01X512Y1682843D02*
X0D01*
G01X512Y1683630D02*
X0D01*
G01X-13009Y1684024D02*
X-14147D01*
G01X12410Y1684220D02*
X315D01*
G01X-14449Y1684319D02*
X-14677D01*
G01X-15985Y1684335D02*
X-16213D01*
G01X-18174Y1684357D02*
X-18435D01*
G01X-18174Y1685265D02*
X-18435D01*
G01X-15985Y1685287D02*
X-16213D01*
G01X-14449Y1685303D02*
X-14677D01*
G01X12410Y1685402D02*
X315D01*
G01X-13009Y1685598D02*
X-14147D01*
G01X512Y1685992D02*
X0D01*
G01X512Y1686780D02*
X0D01*
G01X-13009Y1687173D02*
X-14147D01*
G01X12410Y1687370D02*
X315D01*
G01X-14449Y1687469D02*
X-14677D01*
G01X-15985Y1687485D02*
X-16213D01*
G01X-18174Y1687506D02*
X-18435D01*
G01X-18174Y1688415D02*
X-18435D01*
G01X-15985Y1688436D02*
X-16213D01*
G01X-14449Y1688453D02*
X-14677D01*
G01X12410Y1688551D02*
X315D01*
G01X-13009Y1688748D02*
X-14147D01*
G01X512Y1689142D02*
X0D01*
G01X512Y1689929D02*
X0D01*
G01X-13009Y1690323D02*
X-14147D01*
G01X12410Y1690520D02*
X315D01*
G01X-14449Y1690618D02*
X-14677D01*
G01X-15985Y1690634D02*
X-16213D01*
G01X-18174Y1690656D02*
X-18435D01*
G01X-18174Y1691564D02*
X-18435D01*
G01X-15985Y1691586D02*
X-16213D01*
G01X-14449Y1691602D02*
X-14677D01*
G01X12410Y1691701D02*
X315D01*
G01X-13009Y1691898D02*
X-14147D01*
G01X512Y1692291D02*
X0D01*
G01X512Y1693079D02*
X0D01*
G01X-13009Y1693472D02*
X-14147D01*
G01X12410Y1693669D02*
X315D01*
G01X-14449Y1693768D02*
X-14677D01*
G01X-15985Y1693784D02*
X-16213D01*
G01X-18174Y1693806D02*
X-18435D01*
G01X-18174Y1694714D02*
X-18435D01*
G01X-15985Y1694735D02*
X-16213D01*
G01X-14449Y1694752D02*
X-14677D01*
G01X12410Y1694850D02*
X315D01*
G01X-13009Y1695047D02*
X-14147D01*
G01X512Y1695441D02*
X0D01*
G01X-19469Y1665474D02*
X-20801Y1665485D01*
G01X-15985Y1665437D02*
X-18435Y1665459D01*
G01X-19469Y1668623D02*
X-20801Y1668635D01*
G01X-15985Y1668587D02*
X-18435Y1668609D01*
G01X-19469Y1671773D02*
X-20801Y1671785D01*
G01X-15985Y1671737D02*
X-18435Y1671758D01*
G01X-19469Y1674922D02*
X-20801Y1674934D01*
G01X-15985Y1674886D02*
X-18435Y1674908D01*
G01X-19469Y1678072D02*
X-20801Y1678084D01*
G01X-15985Y1678036D02*
X-18435Y1678057D01*
G01X-19469Y1681222D02*
X-20801Y1681233D01*
G01X-15985Y1681185D02*
X-18435Y1681207D01*
G01X-19469Y1684371D02*
X-20801Y1684383D01*
G01X-15985Y1684335D02*
X-18435Y1684357D01*
G01X-19469Y1687521D02*
X-20801Y1687533D01*
G01X-15985Y1687485D02*
X-18435Y1687506D01*
G01X-19469Y1690670D02*
X-20801Y1690682D01*
G01X-15985Y1690634D02*
X-18435Y1690656D01*
G01X-19469Y1693820D02*
X-20801Y1693832D01*
G01X-15985Y1693784D02*
X-18435Y1693806D01*
G01X-19469Y1696970D02*
X-20801Y1696981D01*
G01X-15985Y1696933D02*
X-18435Y1696955D01*
G01X-19469Y1700119D02*
X-20801Y1700131D01*
G01X-15985Y1700083D02*
X-18435Y1700105D01*
G01X-15985Y1665437D02*
X-14449Y1665421D01*
G01X-15985Y1668587D02*
X-14449Y1668571D01*
G01X-15985Y1671737D02*
X-14449Y1671720D01*
G01X-15985Y1674886D02*
X-14449Y1674870D01*
G01X-15985Y1678036D02*
X-14449Y1678020D01*
G01X-15985Y1681185D02*
X-14449Y1681169D01*
G01X-15985Y1684335D02*
X-14449Y1684319D01*
G01X-15985Y1687485D02*
X-14449Y1687469D01*
G01X-15985Y1690634D02*
X-14449Y1690618D01*
G01X-15985Y1693784D02*
X-14449Y1693768D01*
G01X-15985Y1696933D02*
X-14449Y1696917D01*
G01X-15985Y1700083D02*
X-14449Y1700067D01*
G01X-18435Y1665459D02*
X-20801Y1665485D01*
G01X-18435Y1668609D02*
X-20801Y1668635D01*
G01X-18435Y1671758D02*
X-20801Y1671785D01*
G01X-18435Y1674908D02*
X-20801Y1674934D01*
G01X-18435Y1678057D02*
X-20801Y1678084D01*
G01X-18435Y1681207D02*
X-20801Y1681233D01*
G01X-18435Y1684357D02*
X-20801Y1684383D01*
G01X-18435Y1687506D02*
X-20801Y1687533D01*
G01X-18435Y1690656D02*
X-20801Y1690682D01*
G01X-18435Y1693806D02*
X-20801Y1693832D01*
G01X-18435Y1696955D02*
X-20801Y1696981D01*
G01X-18435Y1700105D02*
X-20801Y1700131D01*
G01X-19469Y1665474D02*
X-16213Y1665437D01*
G01X-18174Y1665459D02*
X-14677Y1665421D01*
G01X-19469Y1668623D02*
X-16213Y1668587D01*
G01X-18174Y1668609D02*
X-14677Y1668571D01*
G01X-19469Y1671773D02*
X-16213Y1671737D01*
G01X-18174Y1671758D02*
X-14677Y1671720D01*
G01X-19469Y1674922D02*
X-16213Y1674886D01*
G01X-18174Y1674908D02*
X-14677Y1674870D01*
G01X-19469Y1678072D02*
X-16213Y1678036D01*
G01X-18174Y1678057D02*
X-14677Y1678020D01*
G01X-19469Y1681222D02*
X-16213Y1681185D01*
G01X-18174Y1681207D02*
X-14677Y1681169D01*
G01X-19469Y1684371D02*
X-16213Y1684335D01*
G01X-18174Y1684357D02*
X-14677Y1684319D01*
G01X-19469Y1687521D02*
X-16213Y1687485D01*
G01X-18174Y1687506D02*
X-14677Y1687469D01*
G01X-19469Y1690670D02*
X-16213Y1690634D01*
G01X-18174Y1690656D02*
X-14677Y1690618D01*
G01X-19469Y1693820D02*
X-16213Y1693784D01*
G01X-18174Y1693806D02*
X-14677Y1693768D01*
G01X-19469Y1696970D02*
X-16213Y1696933D01*
G01X-18174Y1696955D02*
X-14677Y1696917D01*
G01X-19469Y1700119D02*
X-16213Y1700083D01*
G01X-18174Y1700105D02*
X-14677Y1700067D01*
G01X-19469Y1691550D02*
X-18174Y1691564D01*
G01X-18435D02*
X-20801Y1691538D01*
G01X-18174Y1691564D02*
X-17126Y1691576D01*
G01X-19469Y1694700D02*
X-18174Y1694714D01*
G01X-18435D02*
X-20801Y1694688D01*
G01X-18174Y1694714D02*
X-17126Y1694725D01*
G01X-19469Y1697849D02*
X-18174Y1697863D01*
G01X-18435D02*
X-20801Y1697837D01*
G01X-18174Y1697863D02*
X-17126Y1697875D01*
G01X-19469Y1700999D02*
X-18174Y1701013D01*
G01X-18435D02*
X-20801Y1700987D01*
G01X-18174Y1701013D02*
X-17126Y1701024D01*
G01X-19469Y1704148D02*
X-18174Y1704163D01*
G01X-18435D02*
X-20801Y1704137D01*
G01X-18174Y1704163D02*
X-17126Y1704174D01*
G01X-15985Y1691586D02*
X-14449Y1691602D01*
G01X-14677D02*
X-18174Y1691564D01*
G01X-14677Y1691602D02*
X-16213Y1691586D01*
G01X-15985Y1694735D02*
X-14449Y1694752D01*
G01X-14677D02*
X-18174Y1694714D01*
G01X-14677Y1694752D02*
X-16213Y1694735D01*
G01X-15985Y1697885D02*
X-14449Y1697902D01*
G01X-14677D02*
X-18174Y1697863D01*
G01X-14677Y1697902D02*
X-16213Y1697885D01*
G01X-15985Y1701035D02*
X-14449Y1701051D01*
G01X-14677D02*
X-18174Y1701013D01*
G01X-14677Y1701051D02*
X-16213Y1701035D01*
G01X-15985Y1704184D02*
X-14449Y1704201D01*
G01X-14677D02*
X-18174Y1704163D01*
G01X-14677Y1704201D02*
X-16213Y1704184D01*
G01X-19469Y1691550D02*
X-20801Y1691538D01*
G01X-19469Y1694700D02*
X-20801Y1694688D01*
G01X-19469Y1697849D02*
X-20801Y1697837D01*
G01X-19469Y1700999D02*
X-20801Y1700987D01*
G01X-19469Y1704148D02*
X-20801Y1704137D01*
G01X-15985Y1691586D02*
X-17126Y1691576D01*
G01D02*
X-18435Y1691564D01*
G01X-15985Y1694735D02*
X-17126Y1694725D01*
G01D02*
X-18435Y1694714D01*
G01X-15985Y1697885D02*
X-17126Y1697875D01*
G01D02*
X-18435Y1697863D01*
G01X-15985Y1701035D02*
X-17126Y1701024D01*
G01D02*
X-18435Y1701013D01*
G01X-15985Y1704184D02*
X-17126Y1704174D01*
G01D02*
X-18435Y1704163D01*
G01X512Y1696228D02*
X0D01*
G01X-13009Y1696622D02*
X-14147D01*
G01X12410Y1696819D02*
X315D01*
G01X-14449Y1696917D02*
X-14677D01*
G01X-15985Y1696933D02*
X-16213D01*
G01X-18174Y1696955D02*
X-18435D01*
G01X-18174Y1697863D02*
X-18435D01*
G01X-15985Y1697885D02*
X-16213D01*
G01X-14449Y1697902D02*
X-14677D01*
G01X12410Y1698000D02*
X315D01*
G01X-13009Y1698197D02*
X-14147D01*
G01X512Y1698591D02*
X0D01*
G01X512Y1699378D02*
X0D01*
G01X-13009Y1699772D02*
X-14147D01*
G01X12410Y1699969D02*
X315D01*
G01X-14449Y1700067D02*
X-14677D01*
G01X-15985Y1700083D02*
X-16213D01*
G01X-18174Y1700105D02*
X-18435D01*
G01X-18174Y1701013D02*
X-18435D01*
G01X-15985Y1701035D02*
X-16213D01*
G01X-14449Y1701051D02*
X-14677D01*
G01X12410Y1701150D02*
X315D01*
G01X-13009Y1701346D02*
X-14147D01*
G01X512Y1701740D02*
X0D01*
G01X512Y1702528D02*
X0D01*
G01X-13009Y1702921D02*
X-14147D01*
G01X12410Y1703118D02*
X315D01*
G01X-14449Y1703217D02*
X-14677D01*
G01X-15985Y1703233D02*
X-16213D01*
G01X-18174Y1703254D02*
X-18435D01*
G01X-18174Y1704163D02*
X-18435D01*
G01X-15985Y1704184D02*
X-16213D01*
G01X-14449Y1704201D02*
X-14677D01*
G01X12410Y1704299D02*
X315D01*
G01X-13009Y1704496D02*
X-14147D01*
G01X512Y1704890D02*
X0D01*
G01X-19469Y1703269D02*
X-20801Y1703281D01*
G01X-15985Y1703233D02*
X-18435Y1703254D01*
G01X-15985Y1703233D02*
X-14449Y1703217D01*
G01X-18435Y1703254D02*
X-20801Y1703281D01*
G01X-19469Y1703269D02*
X-16213Y1703233D01*
G01X-18174Y1703254D02*
X-14677Y1703217D01*
G01X-14537Y1720037D02*
X-14677Y1719949D01*
G01X-13977Y1720244D02*
X-14449Y1719949D01*
G01X-14537Y1716887D02*
X-14677Y1716799D01*
G01X-13977Y1717094D02*
X-14449Y1716799D01*
G01X-14537Y1713737D02*
X-14677Y1713650D01*
G01X-13977Y1713945D02*
X-14449Y1713650D01*
G01X-14537Y1710588D02*
X-14677Y1710500D01*
G01X-13977Y1710795D02*
X-14449Y1710500D01*
G01X-14537Y1707438D02*
X-14677Y1707350D01*
G01X-13977Y1707646D02*
X-14449Y1707350D01*
G01X-14147Y1720244D02*
X-14537Y1720037D01*
G01X-14147Y1717094D02*
X-14537Y1716887D01*
G01X-14147Y1713945D02*
X-14537Y1713737D01*
G01X-14147Y1710795D02*
X-14537Y1710588D01*
G01X-14147Y1707646D02*
X-14537Y1707438D01*
G01X-20801Y1719885D02*
Y1719029D01*
G01Y1716735D02*
Y1715879D01*
G01Y1710436D02*
Y1709580D01*
G01Y1713585D02*
Y1712730D01*
G01Y1707286D02*
Y1706430D01*
G01X-19469Y1719891D02*
Y1719023D01*
G01Y1716741D02*
Y1715873D01*
G01Y1710442D02*
Y1709574D01*
G01Y1713591D02*
Y1712724D01*
G01Y1707292D02*
Y1706424D01*
G01X-18435Y1719911D02*
Y1719002D01*
G01Y1716761D02*
Y1715853D01*
G01Y1710462D02*
Y1709554D01*
G01Y1713611D02*
Y1712703D01*
G01Y1707312D02*
Y1706404D01*
G01X-18174Y1719911D02*
Y1719002D01*
G01Y1716761D02*
Y1715853D01*
G01Y1710462D02*
Y1709554D01*
G01Y1713611D02*
Y1712703D01*
G01Y1707312D02*
Y1706404D01*
G01X-16213Y1719932D02*
Y1718981D01*
G01Y1716783D02*
Y1715831D01*
G01Y1710483D02*
Y1709532D01*
G01Y1713633D02*
Y1712681D01*
G01Y1707334D02*
Y1706382D01*
G01X-15985Y1719932D02*
Y1718981D01*
G01Y1716783D02*
Y1715831D01*
G01Y1710483D02*
Y1709532D01*
G01Y1713633D02*
Y1712681D01*
G01Y1707334D02*
Y1706382D01*
G01X-14537Y1720037D02*
Y1718877D01*
G01Y1716887D02*
Y1715727D01*
G01Y1710588D02*
Y1709428D01*
G01Y1713737D02*
Y1712578D01*
G01Y1707438D02*
Y1706278D01*
G01X-13009Y1720244D02*
Y1718669D01*
G01Y1717094D02*
Y1715520D01*
G01Y1710795D02*
Y1709220D01*
G01Y1713945D02*
Y1712370D01*
G01Y1707646D02*
Y1706071D01*
G01X315Y1720638D02*
Y1720047D01*
G01Y1714339D02*
Y1713748D01*
G01Y1717488D02*
Y1716898D01*
G01Y1715717D02*
Y1715126D01*
G01Y1718866D02*
Y1718276D01*
G01Y1711189D02*
Y1710598D01*
G01Y1712567D02*
Y1711976D01*
G01Y1708039D02*
Y1707449D01*
G01Y1706268D02*
Y1705677D01*
G01Y1709417D02*
Y1708827D01*
G01X512Y1720638D02*
Y1720047D01*
G01Y1714339D02*
Y1713748D01*
G01Y1717488D02*
Y1716898D01*
G01Y1715717D02*
Y1715126D01*
G01Y1718866D02*
Y1718276D01*
G01Y1711189D02*
Y1710598D01*
G01Y1712567D02*
Y1711976D01*
G01Y1708039D02*
Y1707449D01*
G01Y1706268D02*
Y1705677D01*
G01Y1709417D02*
Y1708827D01*
G01X709Y1720047D02*
Y1718866D01*
G01Y1716898D02*
Y1715717D01*
G01Y1710598D02*
Y1709417D01*
G01Y1713748D02*
Y1712567D01*
G01Y1707449D02*
Y1706268D01*
G01X1074Y1720047D02*
Y1718866D01*
G01Y1716898D02*
Y1715717D01*
G01Y1710598D02*
Y1709417D01*
G01Y1713748D02*
Y1712567D01*
G01Y1707449D02*
Y1706268D01*
G01X1184Y1720047D02*
Y1718866D01*
G01Y1716898D02*
Y1715717D01*
G01Y1710598D02*
Y1709417D01*
G01Y1713748D02*
Y1712567D01*
G01Y1707449D02*
Y1706268D01*
G01X9965Y1720047D02*
Y1718866D01*
G01Y1716898D02*
Y1715717D01*
G01Y1710598D02*
Y1709417D01*
G01Y1713748D02*
Y1712567D01*
G01Y1707449D02*
Y1706268D01*
G01X10075Y1720047D02*
Y1718866D01*
G01Y1716898D02*
Y1715717D01*
G01Y1710598D02*
Y1709417D01*
G01Y1713748D02*
Y1712567D01*
G01Y1707449D02*
Y1706268D01*
G01X-14537Y1706278D02*
X-14147Y1706071D01*
G01X-14537Y1709428D02*
X-14147Y1709220D01*
G01X-14537Y1712578D02*
X-14147Y1712370D01*
G01X-14537Y1715727D02*
X-14147Y1715520D01*
G01X-14537Y1718877D02*
X-14147Y1718669D01*
G01X-14677Y1706366D02*
X-14537Y1706278D01*
G01X-14449Y1706366D02*
X-13977Y1706071D01*
G01X-14677Y1709516D02*
X-14537Y1709428D01*
G01X-14449Y1709516D02*
X-13977Y1709220D01*
G01X-14677Y1712665D02*
X-14537Y1712578D01*
G01X-14449Y1712665D02*
X-13977Y1712370D01*
G01X-14677Y1715815D02*
X-14537Y1715727D01*
G01X-14449Y1715815D02*
X-13977Y1715520D01*
G01X-14677Y1718965D02*
X-14537Y1718877D01*
G01X-14449Y1718965D02*
X-13977Y1718669D01*
G01X-19469Y1707298D02*
X-18174Y1707312D01*
G01X-18435D02*
X-20801Y1707286D01*
G01X-18174Y1707312D02*
X-17126Y1707324D01*
G01X-19469Y1710448D02*
X-18174Y1710462D01*
G01X-18435D02*
X-20801Y1710436D01*
G01X-18174Y1710462D02*
X-17126Y1710473D01*
G01X-19469Y1713597D02*
X-18174Y1713611D01*
G01X-18435D02*
X-20801Y1713585D01*
G01X-18174Y1713611D02*
X-17126Y1713623D01*
G01X-19469Y1716747D02*
X-18174Y1716761D01*
G01X-18435D02*
X-20801Y1716735D01*
G01X-18174Y1716761D02*
X-17126Y1716772D01*
G01X-19469Y1719896D02*
X-18174Y1719911D01*
G01X-18435D02*
X-20801Y1719885D01*
G01X-18174Y1719911D02*
X-17126Y1719922D01*
G01X-15985Y1707334D02*
X-14449Y1707350D01*
G01X-14677D02*
X-18174Y1707312D01*
G01X-14677Y1707350D02*
X-16213Y1707334D01*
G01X-15985Y1710483D02*
X-14449Y1710500D01*
G01X-14677D02*
X-18174Y1710462D01*
G01X-14677Y1710500D02*
X-16213Y1710483D01*
G01X-15985Y1713633D02*
X-14449Y1713650D01*
G01X-14677D02*
X-18174Y1713611D01*
G01X-14677Y1713650D02*
X-16213Y1713633D01*
G01X-15985Y1716783D02*
X-14449Y1716799D01*
G01X-14677D02*
X-18174Y1716761D01*
G01X-14677Y1716799D02*
X-16213Y1716783D01*
G01X-15985Y1719932D02*
X-14449Y1719949D01*
G01X-14677D02*
X-18174Y1719911D01*
G01X-14677Y1719949D02*
X-16213Y1719932D01*
G01X-19469Y1707298D02*
X-20801Y1707286D01*
G01X-19469Y1710448D02*
X-20801Y1710436D01*
G01X-19469Y1713597D02*
X-20801Y1713585D01*
G01X-19469Y1716747D02*
X-20801Y1716735D01*
G01X-19469Y1719896D02*
X-20801Y1719885D01*
G01X-15985Y1707334D02*
X-17126Y1707324D01*
G01D02*
X-18435Y1707312D01*
G01X-15985Y1710483D02*
X-17126Y1710473D01*
G01D02*
X-18435Y1710462D01*
G01X-15985Y1713633D02*
X-17126Y1713623D01*
G01D02*
X-18435Y1713611D01*
G01X-15985Y1716783D02*
X-17126Y1716772D01*
G01D02*
X-18435Y1716761D01*
G01X-15985Y1719932D02*
X-17126Y1719922D01*
G01D02*
X-18435Y1719911D01*
G01X512Y1705677D02*
X0D01*
G01X-13009Y1706071D02*
X-14147D01*
G01X12410Y1706268D02*
X315D01*
G01X-14449Y1706366D02*
X-14677D01*
G01X-15985Y1706382D02*
X-16213D01*
G01X-18174Y1706404D02*
X-18435D01*
G01X-18174Y1707312D02*
X-18435D01*
G01X-15985Y1707334D02*
X-16213D01*
G01X-14449Y1707350D02*
X-14677D01*
G01X12410Y1707449D02*
X315D01*
G01X-13009Y1707646D02*
X-14147D01*
G01X512Y1708039D02*
X0D01*
G01X512Y1708827D02*
X0D01*
G01X-13009Y1709220D02*
X-14147D01*
G01X12410Y1709417D02*
X315D01*
G01X-14449Y1709516D02*
X-14677D01*
G01X-15985Y1709532D02*
X-16213D01*
G01X-18174Y1709554D02*
X-18435D01*
G01X-18174Y1710462D02*
X-18435D01*
G01X-15985Y1710483D02*
X-16213D01*
G01X-14449Y1710500D02*
X-14677D01*
G01X12410Y1710598D02*
X315D01*
G01X-13009Y1710795D02*
X-14147D01*
G01X512Y1711189D02*
X0D01*
G01X512Y1711976D02*
X0D01*
G01X-13009Y1712370D02*
X-14147D01*
G01X12410Y1712567D02*
X315D01*
G01X-14449Y1712665D02*
X-14677D01*
G01X-15985Y1712681D02*
X-16213D01*
G01X-18174Y1712703D02*
X-18435D01*
G01X-18174Y1713611D02*
X-18435D01*
G01X-15985Y1713633D02*
X-16213D01*
G01X-14449Y1713650D02*
X-14677D01*
G01X12410Y1713748D02*
X315D01*
G01X-13009Y1713945D02*
X-14147D01*
G01X512Y1714339D02*
X0D01*
G01X512Y1715126D02*
X0D01*
G01X-13009Y1715520D02*
X-14147D01*
G01X12410Y1715717D02*
X315D01*
G01X-14449Y1715815D02*
X-14677D01*
G01X-15985Y1715831D02*
X-16213D01*
G01X-18174Y1715853D02*
X-18435D01*
G01X-18174Y1716761D02*
X-18435D01*
G01X-15985Y1716783D02*
X-16213D01*
G01X-14449Y1716799D02*
X-14677D01*
G01X12410Y1716898D02*
X315D01*
G01X-13009Y1717094D02*
X-14147D01*
G01X512Y1717488D02*
X0D01*
G01X512Y1718276D02*
X0D01*
G01X-13009Y1718669D02*
X-14147D01*
G01X12410Y1718866D02*
X315D01*
G01X-14449Y1718965D02*
X-14677D01*
G01X-15985Y1718981D02*
X-16213D01*
G01X-18174Y1719002D02*
X-18435D01*
G01X-18174Y1719911D02*
X-18435D01*
G01X-15985Y1719932D02*
X-16213D01*
G01X-14449Y1719949D02*
X-14677D01*
G01X12410Y1720047D02*
X315D01*
G01X-13009Y1720244D02*
X-14147D01*
G01X512Y1720638D02*
X0D01*
G01X-19469Y1706419D02*
X-20801Y1706430D01*
G01X-15985Y1706382D02*
X-18435Y1706404D01*
G01X-19469Y1709568D02*
X-20801Y1709580D01*
G01X-15985Y1709532D02*
X-18435Y1709554D01*
G01X-19469Y1712718D02*
X-20801Y1712730D01*
G01X-15985Y1712681D02*
X-18435Y1712703D01*
G01X-19469Y1715867D02*
X-20801Y1715879D01*
G01X-15985Y1715831D02*
X-18435Y1715853D01*
G01X-19469Y1719017D02*
X-20801Y1719029D01*
G01X-15985Y1718981D02*
X-18435Y1719002D01*
G01X-15985Y1706382D02*
X-14449Y1706366D01*
G01X-15985Y1709532D02*
X-14449Y1709516D01*
G01X-15985Y1712681D02*
X-14449Y1712665D01*
G01X-15985Y1715831D02*
X-14449Y1715815D01*
G01X-15985Y1718981D02*
X-14449Y1718965D01*
G01X-18435Y1706404D02*
X-20801Y1706430D01*
G01X-18435Y1709554D02*
X-20801Y1709580D01*
G01X-18435Y1712703D02*
X-20801Y1712730D01*
G01X-18435Y1715853D02*
X-20801Y1715879D01*
G01X-18435Y1719002D02*
X-20801Y1719029D01*
G01X-19469Y1706419D02*
X-16213Y1706382D01*
G01X-18174Y1706404D02*
X-14677Y1706366D01*
G01X-19469Y1709568D02*
X-16213Y1709532D01*
G01X-18174Y1709554D02*
X-14677Y1709516D01*
G01X-19469Y1712718D02*
X-16213Y1712681D01*
G01X-18174Y1712703D02*
X-14677Y1712665D01*
G01X-19469Y1715867D02*
X-16213Y1715831D01*
G01X-18174Y1715853D02*
X-14677Y1715815D01*
G01X-19469Y1719017D02*
X-16213Y1718981D01*
G01X-18174Y1719002D02*
X-14677Y1718965D01*
G01X-14537Y1663344D02*
X-14677Y1663256D01*
G01X-13977Y1663551D02*
X-14449Y1663256D01*
G01X-14147Y1663551D02*
X-14537Y1663344D01*
G01X-26772Y1658827D02*
X-30709Y1656858D01*
G01X0Y1648591D02*
X1969Y1650559D01*
G01X-26772Y1837961D02*
Y1658827D01*
G01X-20801Y1663192D02*
Y1662336D01*
G01X-19469Y1663198D02*
Y1662330D01*
G01X-18435Y1663218D02*
Y1662309D01*
G01X-18174Y1663218D02*
Y1662309D01*
G01X-16213Y1663239D02*
Y1662288D01*
G01X-15985Y1663239D02*
Y1662288D01*
G01X-14537Y1663344D02*
Y1662184D01*
G01X-13009Y1663551D02*
Y1661976D01*
G01Y1666701D02*
Y1665126D01*
G01X-7283Y1839929D02*
Y1658827D01*
G01X315Y1663945D02*
Y1663354D01*
G01Y1665323D02*
Y1664732D01*
G01Y1662173D02*
Y1661583D01*
G01X512Y1663945D02*
Y1663354D01*
G01Y1665323D02*
Y1664732D01*
G01Y1662173D02*
Y1661583D01*
G01X709Y1663354D02*
Y1662173D01*
G01X1074Y1663354D02*
Y1662173D01*
G01X1184Y1663354D02*
Y1662173D01*
G01X9965Y1663354D02*
Y1662173D01*
G01X10075Y1663354D02*
Y1662173D01*
G01X1969Y1659220D02*
X0Y1661189D01*
G01X-14677Y1662272D02*
X-14537Y1662184D01*
G01X-14449Y1662272D02*
X-13977Y1661976D01*
G01X-14449Y1665421D02*
X-13977Y1665126D01*
G01X-30709Y1652921D02*
X-26772Y1650953D01*
G01X-14537Y1662184D02*
X-14147Y1661976D01*
G01X-14537Y1665333D02*
X-14147Y1665126D01*
G01X-19469Y1663204D02*
X-18174Y1663218D01*
G01X-18435D02*
X-20801Y1663192D01*
G01X-18174Y1663218D02*
X-17126Y1663229D01*
G01X-15985Y1663239D02*
X-14449Y1663256D01*
G01X-14677D02*
X-18174Y1663218D01*
G01X-14677Y1663256D02*
X-16213Y1663239D01*
G01X-19469Y1663204D02*
X-20801Y1663192D01*
G01X-15985Y1663239D02*
X-17126Y1663229D01*
G01D02*
X-18435Y1663218D01*
G01X1969Y1650559D02*
X17323D01*
G01X17717Y1650953D02*
X0D01*
G01X-26772D02*
X-7283D01*
G01X17717Y1658827D02*
X0D01*
G01X-7283D02*
X-26772D01*
G01X17323Y1659220D02*
X1969D01*
G01X512Y1661583D02*
X0D01*
G01X-13009Y1661976D02*
X-14147D01*
G01X12410Y1662173D02*
X315D01*
G01X-14449Y1662272D02*
X-14677D01*
G01X-15985Y1662288D02*
X-16213D01*
G01X-18174Y1662309D02*
X-18435D01*
G01X-18174Y1663218D02*
X-18435D01*
G01X-15985Y1663239D02*
X-16213D01*
G01X-14449Y1663256D02*
X-14677D01*
G01X12410Y1663354D02*
X315D01*
G01X-13009Y1663551D02*
X-14147D01*
G01X512Y1663945D02*
X0D01*
G01X512Y1664732D02*
X0D01*
G01X-13009Y1665126D02*
X-14147D01*
G01X-19469Y1662324D02*
X-20801Y1662336D01*
G01X-15985Y1662288D02*
X-18435Y1662309D01*
G01X-15985Y1662288D02*
X-14449Y1662272D01*
G01X-18435Y1662309D02*
X-20801Y1662336D01*
G01X-19469Y1662324D02*
X-16213Y1662288D01*
G01X-18174Y1662309D02*
X-14677Y1662272D01*
G01X12634Y1791563D02*
X12416Y1791293D01*
G01X12634Y1788413D02*
X12416Y1788143D01*
G01X12287Y1791563D02*
X12057Y1791307D01*
G01X12287Y1788413D02*
X12057Y1788157D01*
G01Y1789339D02*
Y1788157D01*
G01Y1792488D02*
Y1791307D01*
G01X12410Y1789339D02*
Y1788157D01*
G01Y1792488D02*
Y1791307D01*
G01X13353Y1792232D02*
Y1791563D01*
G01Y1789083D02*
Y1788413D01*
G01X13701Y1792232D02*
Y1791563D01*
G01Y1789083D02*
Y1788413D01*
G01X12057Y1786189D02*
X12287Y1785933D01*
G01X12057Y1789339D02*
X12287Y1789083D01*
G01X12057Y1792488D02*
X12287Y1792232D01*
G01X12416Y1786203D02*
X12634Y1785933D01*
G01X12416Y1789353D02*
X12634Y1789083D01*
G01X12416Y1792502D02*
X12634Y1792232D01*
G01X13701Y1785933D02*
X12287D01*
G01X13701Y1788413D02*
X12287D01*
G01X13701Y1789083D02*
X12287D01*
G01X13701Y1791563D02*
X12287D01*
G01X13701Y1792232D02*
X12287D01*
G01X12634Y1785264D02*
X12416Y1784994D01*
G01X12634Y1782114D02*
X12416Y1781844D01*
G01X12634Y1778965D02*
X12416Y1778694D01*
G01X12634Y1775815D02*
X12416Y1775545D01*
G01X12634Y1772665D02*
X12416Y1772395D01*
G01X12634Y1769516D02*
X12416Y1769246D01*
G01X12634Y1766366D02*
X12416Y1766096D01*
G01X12634Y1763217D02*
X12416Y1762946D01*
G01X12634Y1760067D02*
X12416Y1759797D01*
G01X12634Y1756917D02*
X12416Y1756647D01*
G01X12634Y1753768D02*
X12416Y1753498D01*
G01X12634Y1750618D02*
X12416Y1750348D01*
G01X12634Y1747469D02*
X12416Y1747198D01*
G01X12634Y1744319D02*
X12416Y1744049D01*
G01X12634Y1741169D02*
X12416Y1740899D01*
G01X12634Y1738020D02*
X12416Y1737750D01*
G01X12634Y1734870D02*
X12416Y1734600D01*
G01X12634Y1731720D02*
X12416Y1731450D01*
G01X12634Y1728571D02*
X12416Y1728301D01*
G01X12287Y1785264D02*
X12057Y1785008D01*
G01X12287Y1782114D02*
X12057Y1781858D01*
G01X12287Y1778965D02*
X12057Y1778709D01*
G01X12287Y1775815D02*
X12057Y1775559D01*
G01X12287Y1772665D02*
X12057Y1772409D01*
G01X12287Y1769516D02*
X12057Y1769260D01*
G01X12287Y1766366D02*
X12057Y1766110D01*
G01X12287Y1763217D02*
X12057Y1762961D01*
G01X12287Y1760067D02*
X12057Y1759811D01*
G01X12287Y1756917D02*
X12057Y1756661D01*
G01X12287Y1753768D02*
X12057Y1753512D01*
G01X12287Y1750618D02*
X12057Y1750362D01*
G01X12287Y1747469D02*
X12057Y1747213D01*
G01X12287Y1744319D02*
X12057Y1744063D01*
G01X12287Y1741169D02*
X12057Y1740913D01*
G01X12287Y1738020D02*
X12057Y1737764D01*
G01X12287Y1734870D02*
X12057Y1734614D01*
G01X12287Y1731720D02*
X12057Y1731465D01*
G01X12287Y1728571D02*
X12057Y1728315D01*
G01Y1786189D02*
Y1785008D01*
G01Y1779890D02*
Y1778709D01*
G01Y1783039D02*
Y1781858D01*
G01Y1776740D02*
Y1775559D01*
G01Y1773591D02*
Y1772409D01*
G01Y1767291D02*
Y1766110D01*
G01Y1770441D02*
Y1769260D01*
G01Y1764142D02*
Y1762961D01*
G01Y1757843D02*
Y1756661D01*
G01Y1760992D02*
Y1759811D01*
G01Y1754693D02*
Y1753512D01*
G01Y1748394D02*
Y1747213D01*
G01Y1751543D02*
Y1750362D01*
G01Y1745244D02*
Y1744063D01*
G01Y1738945D02*
Y1737764D01*
G01Y1742094D02*
Y1740913D01*
G01Y1735795D02*
Y1734614D01*
G01Y1729496D02*
Y1728315D01*
G01Y1732646D02*
Y1731465D01*
G01X12410Y1786189D02*
Y1785008D01*
G01Y1779890D02*
Y1778709D01*
G01Y1783039D02*
Y1781858D01*
G01Y1776740D02*
Y1775559D01*
G01Y1773591D02*
Y1772409D01*
G01Y1767291D02*
Y1766110D01*
G01Y1770441D02*
Y1769260D01*
G01Y1764142D02*
Y1762961D01*
G01Y1757843D02*
Y1756661D01*
G01Y1760992D02*
Y1759811D01*
G01Y1754693D02*
Y1753512D01*
G01Y1748394D02*
Y1747213D01*
G01Y1751543D02*
Y1750362D01*
G01Y1745244D02*
Y1744063D01*
G01Y1738945D02*
Y1737764D01*
G01Y1742094D02*
Y1740913D01*
G01Y1735795D02*
Y1734614D01*
G01Y1729496D02*
Y1728315D01*
G01Y1732646D02*
Y1731465D01*
G01X13353Y1785933D02*
Y1785264D01*
G01Y1782783D02*
Y1782114D01*
G01Y1776484D02*
Y1775815D01*
G01Y1779634D02*
Y1778965D01*
G01Y1773335D02*
Y1772665D01*
G01Y1767035D02*
Y1766366D01*
G01Y1770185D02*
Y1769516D01*
G01Y1763886D02*
Y1763217D01*
G01Y1757587D02*
Y1756917D01*
G01Y1760736D02*
Y1760067D01*
G01Y1754437D02*
Y1753768D01*
G01Y1748138D02*
Y1747469D01*
G01Y1751287D02*
Y1750618D01*
G01Y1744988D02*
Y1744319D01*
G01Y1738689D02*
Y1738020D01*
G01Y1741839D02*
Y1741169D01*
G01Y1735539D02*
Y1734870D01*
G01Y1729240D02*
Y1728571D01*
G01Y1732390D02*
Y1731720D01*
G01Y1726091D02*
Y1725421D01*
G01X13701Y1785933D02*
Y1785264D01*
G01Y1782783D02*
Y1782114D01*
G01Y1776484D02*
Y1775815D01*
G01Y1779634D02*
Y1778965D01*
G01Y1773335D02*
Y1772665D01*
G01Y1767035D02*
Y1766366D01*
G01Y1770185D02*
Y1769516D01*
G01Y1763886D02*
Y1763217D01*
G01Y1757587D02*
Y1756917D01*
G01Y1760736D02*
Y1760067D01*
G01Y1754437D02*
Y1753768D01*
G01Y1748138D02*
Y1747469D01*
G01Y1751287D02*
Y1750618D01*
G01Y1744988D02*
Y1744319D01*
G01Y1738689D02*
Y1738020D01*
G01Y1741839D02*
Y1741169D01*
G01Y1735539D02*
Y1734870D01*
G01Y1729240D02*
Y1728571D01*
G01Y1732390D02*
Y1731720D01*
G01Y1726091D02*
Y1725421D01*
G01X12416Y1726361D02*
X12634Y1726091D01*
G01X12416Y1729510D02*
X12634Y1729240D01*
G01X12416Y1732660D02*
X12634Y1732390D01*
G01X12416Y1735809D02*
X12634Y1735539D01*
G01X12416Y1738959D02*
X12634Y1738689D01*
G01X12416Y1742109D02*
X12634Y1741839D01*
G01X12416Y1745258D02*
X12634Y1744988D01*
G01X12416Y1748408D02*
X12634Y1748138D01*
G01X12057Y1726346D02*
X12287Y1726091D01*
G01X12057Y1729496D02*
X12287Y1729240D01*
G01X12057Y1732646D02*
X12287Y1732390D01*
G01X12057Y1735795D02*
X12287Y1735539D01*
G01X12057Y1738945D02*
X12287Y1738689D01*
G01X12057Y1742094D02*
X12287Y1741839D01*
G01X12057Y1745244D02*
X12287Y1744988D01*
G01X12057Y1748394D02*
X12287Y1748138D01*
G01X12057Y1751543D02*
X12287Y1751287D01*
G01X12057Y1754693D02*
X12287Y1754437D01*
G01X12057Y1757843D02*
X12287Y1757587D01*
G01X12057Y1760992D02*
X12287Y1760736D01*
G01X12057Y1764142D02*
X12287Y1763886D01*
G01X12057Y1767291D02*
X12287Y1767035D01*
G01X12057Y1770441D02*
X12287Y1770185D01*
G01X12057Y1773591D02*
X12287Y1773335D01*
G01X12057Y1776740D02*
X12287Y1776484D01*
G01X12057Y1779890D02*
X12287Y1779634D01*
G01X12057Y1783039D02*
X12287Y1782783D01*
G01X12416Y1751557D02*
X12634Y1751287D01*
G01X12416Y1754707D02*
X12634Y1754437D01*
G01X12416Y1757857D02*
X12634Y1757587D01*
G01X12416Y1761006D02*
X12634Y1760736D01*
G01X12416Y1764156D02*
X12634Y1763886D01*
G01X12416Y1767306D02*
X12634Y1767035D01*
G01X12416Y1770455D02*
X12634Y1770185D01*
G01X12416Y1773605D02*
X12634Y1773335D01*
G01X12416Y1776754D02*
X12634Y1776484D01*
G01X12416Y1779904D02*
X12634Y1779634D01*
G01X12416Y1783054D02*
X12634Y1782783D01*
G01X13701Y1725421D02*
X12287D01*
G01X13701Y1726091D02*
X12287D01*
G01X13701Y1728571D02*
X12287D01*
G01X13701Y1729240D02*
X12287D01*
G01X13701Y1731720D02*
X12287D01*
G01X13701Y1732390D02*
X12287D01*
G01X13701Y1734870D02*
X12287D01*
G01X13701Y1735539D02*
X12287D01*
G01X13701Y1738020D02*
X12287D01*
G01X13701Y1738689D02*
X12287D01*
G01X13701Y1741169D02*
X12287D01*
G01X13701Y1741839D02*
X12287D01*
G01X13701Y1744319D02*
X12287D01*
G01X13701Y1744988D02*
X12287D01*
G01X13701Y1747469D02*
X12287D01*
G01X13701Y1748138D02*
X12287D01*
G01X13701Y1750618D02*
X12287D01*
G01X13701Y1751287D02*
X12287D01*
G01X13701Y1753768D02*
X12287D01*
G01X13701Y1754437D02*
X12287D01*
G01X13701Y1756917D02*
X12287D01*
G01X13701Y1757587D02*
X12287D01*
G01X13701Y1760067D02*
X12287D01*
G01X13701Y1760736D02*
X12287D01*
G01X13701Y1763217D02*
X12287D01*
G01X13701Y1763886D02*
X12287D01*
G01X13701Y1766366D02*
X12287D01*
G01X13701Y1767035D02*
X12287D01*
G01X13701Y1769516D02*
X12287D01*
G01X13701Y1770185D02*
X12287D01*
G01X13701Y1772665D02*
X12287D01*
G01X13701Y1773335D02*
X12287D01*
G01X13701Y1775815D02*
X12287D01*
G01X13701Y1776484D02*
X12287D01*
G01X13701Y1778965D02*
X12287D01*
G01X13701Y1779634D02*
X12287D01*
G01X13701Y1782114D02*
X12287D01*
G01X13701Y1782783D02*
X12287D01*
G01X13701Y1785264D02*
X12287D01*
G01X12634Y1725421D02*
X12416Y1725151D01*
G01X12634Y1722272D02*
X12416Y1722002D01*
G01X12287Y1725421D02*
X12057Y1725165D01*
G01X12287Y1722272D02*
X12057Y1722016D01*
G01Y1726346D02*
Y1725165D01*
G01Y1723197D02*
Y1722016D01*
G01X12410Y1726346D02*
Y1725165D01*
G01Y1723197D02*
Y1722016D01*
G01X13353Y1722941D02*
Y1722272D01*
G01X13701Y1722941D02*
Y1722272D01*
G01X12416Y1723211D02*
X12634Y1722941D01*
G01X12057Y1723197D02*
X12287Y1722941D01*
G01X13701Y1722272D02*
X12287D01*
G01X13701Y1722941D02*
X12287D01*
G01X-20439Y1793997D02*
X-20942Y1793505D01*
G01X-20104Y1793177D02*
X-20272Y1793013D01*
G01X-14537Y1792478D02*
X-14677Y1792390D01*
G01X-13977Y1792685D02*
X-14449Y1792390D01*
G01X-14537Y1789328D02*
X-14677Y1789240D01*
G01X-13977Y1789535D02*
X-14449Y1789240D01*
G01X-14537Y1786178D02*
X-14677Y1786091D01*
G01X-13977Y1786386D02*
X-14449Y1786091D01*
G01X-14147Y1792685D02*
X-14537Y1792478D01*
G01X-14147Y1789535D02*
X-14537Y1789328D01*
G01X-14147Y1786386D02*
X-14537Y1786178D01*
G01X-19769Y1793341D02*
X-20104Y1793177D01*
G01X-15748Y1789404D02*
X-23622Y1786780D01*
G01X-18429Y1787600D02*
X-22952Y1786123D01*
G01X-15748Y1788420D02*
X-17759Y1787764D01*
G01X-20272Y1793013D02*
X-20439Y1792685D01*
G01X-20942Y1793505D02*
X-21109Y1793013D01*
G01X-23622Y1786780D02*
Y1785467D01*
G01X-21109Y1793013D02*
Y1792357D01*
G01Y1791537D02*
Y1790717D01*
G01X-20801Y1792326D02*
Y1791470D01*
G01Y1789176D02*
Y1788320D01*
G01X-20439Y1792685D02*
Y1792357D01*
G01X-19469Y1792331D02*
Y1791464D01*
G01Y1789182D02*
Y1788314D01*
G01X-18435Y1792352D02*
Y1791443D01*
G01Y1789202D02*
Y1788294D01*
G01X-18174Y1792352D02*
Y1791443D01*
G01Y1789202D02*
Y1788294D01*
G01X-16213Y1789224D02*
Y1788272D01*
G01Y1792373D02*
Y1791422D01*
G01X-15985Y1789224D02*
Y1788272D01*
G01Y1792373D02*
Y1791422D01*
G01X-15748Y1794161D02*
Y1793341D01*
G01Y1789404D02*
Y1788420D01*
G01Y1791537D02*
Y1790717D01*
G01X-14537Y1789328D02*
Y1788168D01*
G01Y1792478D02*
Y1791318D01*
G01X-13009Y1789535D02*
Y1787961D01*
G01Y1792685D02*
Y1791110D01*
G01X315Y1789929D02*
Y1789339D01*
G01Y1793079D02*
Y1792488D01*
G01Y1791307D02*
Y1790717D01*
G01Y1786780D02*
Y1786189D01*
G01Y1788157D02*
Y1787567D01*
G01X512Y1789929D02*
Y1789339D01*
G01Y1793079D02*
Y1792488D01*
G01Y1791307D02*
Y1790717D01*
G01Y1786780D02*
Y1786189D01*
G01Y1788157D02*
Y1787567D01*
G01X709Y1789339D02*
Y1788157D01*
G01Y1792488D02*
Y1791307D01*
G01X1074Y1789339D02*
Y1788157D01*
G01Y1792488D02*
Y1791307D01*
G01X1184Y1789339D02*
Y1788157D01*
G01Y1792488D02*
Y1791307D01*
G01X9965Y1789339D02*
Y1788157D01*
G01Y1792488D02*
Y1791307D01*
G01X10075Y1789339D02*
Y1788157D01*
G01Y1792488D02*
Y1791307D01*
G01X-21109Y1792357D02*
X-20942Y1791865D01*
G01X-20439Y1792357D02*
X-20272Y1791865D01*
G01X-20942D02*
X-20607Y1791537D01*
G01X-20272Y1791865D02*
X-19937Y1791537D01*
G01X-14677Y1788256D02*
X-14537Y1788168D01*
G01X-14449Y1788256D02*
X-13977Y1787961D01*
G01X-14537Y1788168D02*
X-14147Y1787961D01*
G01X-14537Y1791318D02*
X-14147Y1791110D01*
G01X-14677Y1791406D02*
X-14537Y1791318D01*
G01X-14449Y1791406D02*
X-13977Y1791110D01*
G01X-19469Y1786038D02*
X-18174Y1786052D01*
G01X-18435D02*
X-20801Y1786026D01*
G01X-18174Y1786052D02*
X-17126Y1786064D01*
G01X-19469Y1789188D02*
X-18174Y1789202D01*
G01X-18435D02*
X-20801Y1789176D01*
G01X-18174Y1789202D02*
X-17126Y1789213D01*
G01X-19469Y1792337D02*
X-18174Y1792352D01*
G01X-18435D02*
X-20801Y1792326D01*
G01X-18174Y1792352D02*
X-17126Y1792363D01*
G01X-15985Y1786074D02*
X-14449Y1786091D01*
G01X-14677D02*
X-18174Y1786052D01*
G01X-14677Y1786091D02*
X-16213Y1786074D01*
G01X-15985Y1789224D02*
X-14449Y1789240D01*
G01X-14677D02*
X-18174Y1789202D01*
G01X-14677Y1789240D02*
X-16213Y1789224D01*
G01X-15985Y1792373D02*
X-14449Y1792390D01*
G01X-14677D02*
X-18174Y1792352D01*
G01X-14677Y1792390D02*
X-16213Y1792373D01*
G01X-19469Y1786038D02*
X-20801Y1786026D01*
G01X-19469Y1789188D02*
X-20801Y1789176D01*
G01X-19469Y1792337D02*
X-20801Y1792326D01*
G01X-15985Y1786074D02*
X-17126Y1786064D01*
G01D02*
X-18435Y1786052D01*
G01X-15985Y1789224D02*
X-17126Y1789213D01*
G01D02*
X-18435Y1789202D01*
G01X-15985Y1792373D02*
X-17126Y1792363D01*
G01D02*
X-18435Y1792352D01*
G01X-18174Y1786052D02*
X-18435D01*
G01X-15985Y1786074D02*
X-16213D01*
G01X-14449Y1786091D02*
X-14677D01*
G01X12410Y1786189D02*
X315D01*
G01X-13009Y1786386D02*
X-14147D01*
G01X512Y1786780D02*
X0D01*
G01X512Y1787567D02*
X0D01*
G01X-13009Y1787961D02*
X-14147D01*
G01X12410Y1788157D02*
X315D01*
G01X-14449Y1788256D02*
X-14677D01*
G01X-15985Y1788272D02*
X-16213D01*
G01X-18174Y1788294D02*
X-18435D01*
G01X-18174Y1789202D02*
X-18435D01*
G01X-15985Y1789224D02*
X-16213D01*
G01X-14449Y1789240D02*
X-14677D01*
G01X12410Y1789339D02*
X315D01*
G01X-13009Y1789535D02*
X-14147D01*
G01X512Y1789929D02*
X0D01*
G01X512Y1790717D02*
X0D01*
G01X-15748D02*
X-21109D01*
G01X-13009Y1791110D02*
X-14147D01*
G01X12410Y1791307D02*
X315D01*
G01X-14449Y1791406D02*
X-14677D01*
G01X-15985Y1791422D02*
X-16213D01*
G01X-18174Y1791443D02*
X-18435D01*
G01X-15748Y1791537D02*
X-19937D01*
G01X-20607D02*
X-21109D01*
G01X-18174Y1792352D02*
X-18435D01*
G01X-15985Y1792373D02*
X-16213D01*
G01X-14449Y1792390D02*
X-14677D01*
G01X12410Y1792488D02*
X315D01*
G01X-13009Y1792685D02*
X-14147D01*
G01X512Y1793079D02*
X0D01*
G01X-15748Y1793341D02*
X-19769D01*
G01X-19469Y1788308D02*
X-20801Y1788320D01*
G01X-15985Y1788272D02*
X-18435Y1788294D01*
G01X-19469Y1791458D02*
X-20801Y1791470D01*
G01X-15985Y1791422D02*
X-18435Y1791443D01*
G01X-15985Y1788272D02*
X-14449Y1788256D01*
G01X-15985Y1791422D02*
X-14449Y1791406D01*
G01X-18435Y1788294D02*
X-20801Y1788320D01*
G01X-18435Y1791443D02*
X-20801Y1791470D01*
G01X-19469Y1788308D02*
X-16213Y1788272D01*
G01X-18174Y1788294D02*
X-14677Y1788256D01*
G01X-19469Y1791458D02*
X-16213Y1791422D01*
G01X-18174Y1791443D02*
X-14677Y1791406D01*
G01X-14537Y1783029D02*
X-14677Y1782941D01*
G01X-13977Y1783236D02*
X-14449Y1782941D01*
G01X-14537Y1779879D02*
X-14677Y1779791D01*
G01X-13977Y1780087D02*
X-14449Y1779791D01*
G01X-14537Y1776730D02*
X-14677Y1776642D01*
G01X-13977Y1776937D02*
X-14449Y1776642D01*
G01X-14537Y1773580D02*
X-14677Y1773492D01*
G01X-13977Y1773787D02*
X-14449Y1773492D01*
G01X-14537Y1770430D02*
X-14677Y1770343D01*
G01X-13977Y1770638D02*
X-14449Y1770343D01*
G01X-14537Y1767281D02*
X-14677Y1767193D01*
G01X-13977Y1767488D02*
X-14449Y1767193D01*
G01X-14537Y1764131D02*
X-14677Y1764043D01*
G01X-13977Y1764339D02*
X-14449Y1764043D01*
G01X-14537Y1760981D02*
X-14677Y1760894D01*
G01X-13977Y1761189D02*
X-14449Y1760894D01*
G01X-14537Y1757832D02*
X-14677Y1757744D01*
G01X-13977Y1758039D02*
X-14449Y1757744D01*
G01X-14537Y1754682D02*
X-14677Y1754594D01*
G01X-13977Y1754890D02*
X-14449Y1754594D01*
G01X-14537Y1751533D02*
X-14677Y1751445D01*
G01X-13977Y1751740D02*
X-14449Y1751445D01*
G01X-14537Y1748383D02*
X-14677Y1748295D01*
G01X-13977Y1748591D02*
X-14449Y1748295D01*
G01X-14537Y1745233D02*
X-14677Y1745146D01*
G01X-13977Y1745441D02*
X-14449Y1745146D01*
G01X-14537Y1742084D02*
X-14677Y1741996D01*
G01X-13977Y1742291D02*
X-14449Y1741996D01*
G01X-14147Y1783236D02*
X-14537Y1783029D01*
G01X-14147Y1780087D02*
X-14537Y1779879D01*
G01X-14147Y1776937D02*
X-14537Y1776730D01*
G01X-14147Y1773787D02*
X-14537Y1773580D01*
G01X-14147Y1770638D02*
X-14537Y1770430D01*
G01X-14147Y1767488D02*
X-14537Y1767281D01*
G01X-14147Y1764339D02*
X-14537Y1764131D01*
G01X-14147Y1761189D02*
X-14537Y1760981D01*
G01X-14147Y1758039D02*
X-14537Y1757832D01*
G01X-14147Y1754890D02*
X-14537Y1754682D01*
G01X-14147Y1751740D02*
X-14537Y1751533D01*
G01X-14147Y1748591D02*
X-14537Y1748383D01*
G01Y1738934D02*
X-14677Y1738846D01*
G01X-13977Y1739142D02*
X-14449Y1738846D01*
G01X-14537Y1735785D02*
X-14677Y1735697D01*
G01X-13977Y1735992D02*
X-14449Y1735697D01*
G01X-14537Y1732635D02*
X-14677Y1732547D01*
G01X-13977Y1732843D02*
X-14449Y1732547D01*
G01X-14537Y1729485D02*
X-14677Y1729398D01*
G01X-13977Y1729693D02*
X-14449Y1729398D01*
G01X-14537Y1726336D02*
X-14677Y1726248D01*
G01X-13977Y1726543D02*
X-14449Y1726248D01*
G01X-14147Y1745441D02*
X-14537Y1745233D01*
G01X-14147Y1742291D02*
X-14537Y1742084D01*
G01X-14147Y1739142D02*
X-14537Y1738934D01*
G01X-14147Y1735992D02*
X-14537Y1735785D01*
G01X-14147Y1732843D02*
X-14537Y1732635D01*
G01X-14147Y1729693D02*
X-14537Y1729485D01*
G01X-14147Y1726543D02*
X-14537Y1726336D01*
G01X-20801Y1786026D02*
Y1785170D01*
G01Y1782877D02*
Y1782021D01*
G01Y1776578D02*
Y1775722D01*
G01Y1779727D02*
Y1778871D01*
G01Y1773428D02*
Y1772572D01*
G01Y1767129D02*
Y1766273D01*
G01Y1770278D02*
Y1769422D01*
G01Y1763979D02*
Y1763123D01*
G01Y1757680D02*
Y1756824D01*
G01Y1760830D02*
Y1759974D01*
G01Y1754530D02*
Y1753674D01*
G01Y1748231D02*
Y1747375D01*
G01Y1751381D02*
Y1750525D01*
G01Y1745081D02*
Y1744226D01*
G01Y1738782D02*
Y1737926D01*
G01Y1741932D02*
Y1741076D01*
G01Y1735633D02*
Y1734777D01*
G01Y1729333D02*
Y1728478D01*
G01Y1732483D02*
Y1731627D01*
G01Y1726184D02*
Y1725328D01*
G01X-19469Y1786032D02*
Y1785165D01*
G01Y1782883D02*
Y1782015D01*
G01Y1776583D02*
Y1775716D01*
G01Y1779733D02*
Y1778865D01*
G01Y1773434D02*
Y1772566D01*
G01Y1767135D02*
Y1766267D01*
G01Y1770284D02*
Y1769417D01*
G01Y1763985D02*
Y1763117D01*
G01Y1757686D02*
Y1756818D01*
G01Y1760835D02*
Y1759968D01*
G01Y1754536D02*
Y1753669D01*
G01Y1748237D02*
Y1747369D01*
G01Y1751387D02*
Y1750519D01*
G01Y1745087D02*
Y1744220D01*
G01Y1738788D02*
Y1737920D01*
G01Y1741938D02*
Y1741070D01*
G01Y1735639D02*
Y1734771D01*
G01Y1729339D02*
Y1728472D01*
G01Y1732489D02*
Y1731621D01*
G01Y1726190D02*
Y1725322D01*
G01X-18435Y1786052D02*
Y1785144D01*
G01Y1782903D02*
Y1781994D01*
G01Y1776604D02*
Y1775695D01*
G01Y1779753D02*
Y1778845D01*
G01Y1773454D02*
Y1772546D01*
G01Y1767155D02*
Y1766246D01*
G01Y1770304D02*
Y1769396D01*
G01Y1764005D02*
Y1763097D01*
G01Y1757706D02*
Y1756798D01*
G01Y1760856D02*
Y1759947D01*
G01Y1754556D02*
Y1753648D01*
G01Y1748257D02*
Y1747349D01*
G01Y1751407D02*
Y1750498D01*
G01Y1745107D02*
Y1744199D01*
G01Y1738808D02*
Y1737900D01*
G01Y1741958D02*
Y1741050D01*
G01Y1735659D02*
Y1734750D01*
G01Y1729359D02*
Y1728451D01*
G01Y1732509D02*
Y1731601D01*
G01Y1726210D02*
Y1725302D01*
G01X-18429Y1787600D02*
Y1784647D01*
G01X-18174Y1786052D02*
Y1785144D01*
G01Y1782903D02*
Y1781994D01*
G01Y1776604D02*
Y1775695D01*
G01Y1779753D02*
Y1778845D01*
G01Y1773454D02*
Y1772546D01*
G01Y1767155D02*
Y1766246D01*
G01Y1770304D02*
Y1769396D01*
G01Y1764005D02*
Y1763097D01*
G01Y1757706D02*
Y1756798D01*
G01Y1760856D02*
Y1759947D01*
G01Y1754556D02*
Y1753648D01*
G01Y1748257D02*
Y1747349D01*
G01Y1751407D02*
Y1750498D01*
G01Y1745107D02*
Y1744199D01*
G01Y1738808D02*
Y1737900D01*
G01Y1741958D02*
Y1741050D01*
G01Y1735659D02*
Y1734750D01*
G01Y1729359D02*
Y1728451D01*
G01Y1732509D02*
Y1731601D01*
G01Y1726210D02*
Y1725302D01*
G01X-17759Y1787764D02*
Y1784483D01*
G01X-16213Y1786074D02*
Y1785122D01*
G01Y1782924D02*
Y1781973D01*
G01Y1776625D02*
Y1775674D01*
G01Y1779775D02*
Y1778823D01*
G01Y1773476D02*
Y1772524D01*
G01Y1767176D02*
Y1766225D01*
G01Y1770326D02*
Y1769374D01*
G01Y1764027D02*
Y1763075D01*
G01Y1757728D02*
Y1756776D01*
G01Y1760877D02*
Y1759926D01*
G01Y1754578D02*
Y1753626D01*
G01Y1748279D02*
Y1747327D01*
G01Y1751428D02*
Y1750477D01*
G01Y1745129D02*
Y1744178D01*
G01Y1738830D02*
Y1737878D01*
G01Y1741980D02*
Y1741028D01*
G01Y1735680D02*
Y1734729D01*
G01Y1729381D02*
Y1728430D01*
G01Y1732531D02*
Y1731579D01*
G01Y1726231D02*
Y1725280D01*
G01X-15985Y1786074D02*
Y1785122D01*
G01Y1782924D02*
Y1781973D01*
G01Y1776625D02*
Y1775674D01*
G01Y1779775D02*
Y1778823D01*
G01Y1773476D02*
Y1772524D01*
G01Y1767176D02*
Y1766225D01*
G01Y1770326D02*
Y1769374D01*
G01Y1764027D02*
Y1763075D01*
G01Y1757728D02*
Y1756776D01*
G01Y1760877D02*
Y1759926D01*
G01Y1754578D02*
Y1753626D01*
G01Y1748279D02*
Y1747327D01*
G01Y1751428D02*
Y1750477D01*
G01Y1745129D02*
Y1744178D01*
G01Y1738830D02*
Y1737878D01*
G01Y1741980D02*
Y1741028D01*
G01Y1735680D02*
Y1734729D01*
G01Y1729381D02*
Y1728430D01*
G01Y1732531D02*
Y1731579D01*
G01Y1726231D02*
Y1725280D01*
G01X-15748Y1783827D02*
Y1782843D01*
G01X-14537Y1786178D02*
Y1785019D01*
G01Y1779879D02*
Y1778719D01*
G01Y1783029D02*
Y1781869D01*
G01Y1776730D02*
Y1775570D01*
G01Y1773580D02*
Y1772420D01*
G01Y1767281D02*
Y1766121D01*
G01Y1770430D02*
Y1769270D01*
G01Y1764131D02*
Y1762971D01*
G01Y1757832D02*
Y1756672D01*
G01Y1760981D02*
Y1759822D01*
G01Y1754682D02*
Y1753522D01*
G01Y1748383D02*
Y1747223D01*
G01Y1751533D02*
Y1750373D01*
G01Y1745233D02*
Y1744074D01*
G01Y1738934D02*
Y1737774D01*
G01Y1742084D02*
Y1740924D01*
G01Y1735785D02*
Y1734625D01*
G01Y1729485D02*
Y1728326D01*
G01Y1732635D02*
Y1731475D01*
G01X-13009Y1786386D02*
Y1784811D01*
G01Y1780087D02*
Y1778512D01*
G01Y1783236D02*
Y1781661D01*
G01Y1776937D02*
Y1775362D01*
G01Y1770638D02*
Y1769063D01*
G01Y1773787D02*
Y1772213D01*
G01Y1767488D02*
Y1765913D01*
G01Y1761189D02*
Y1759614D01*
G01Y1764339D02*
Y1762764D01*
G01Y1758039D02*
Y1756465D01*
G01Y1754890D02*
Y1753315D01*
G01Y1748591D02*
Y1747016D01*
G01Y1751740D02*
Y1750165D01*
G01Y1745441D02*
Y1743866D01*
G01Y1739142D02*
Y1737567D01*
G01Y1742291D02*
Y1740717D01*
G01Y1735992D02*
Y1734417D01*
G01Y1729693D02*
Y1728118D01*
G01Y1732843D02*
Y1731268D01*
G01X315Y1785008D02*
Y1784417D01*
G01Y1780480D02*
Y1779890D01*
G01Y1783630D02*
Y1783039D01*
G01Y1781858D02*
Y1781268D01*
G01Y1777331D02*
Y1776740D01*
G01Y1775559D02*
Y1774969D01*
G01Y1778709D02*
Y1778118D01*
G01Y1771031D02*
Y1770441D01*
G01Y1774181D02*
Y1773591D01*
G01Y1772409D02*
Y1771819D01*
G01Y1767882D02*
Y1767291D01*
G01Y1766110D02*
Y1765520D01*
G01Y1769260D02*
Y1768669D01*
G01Y1761583D02*
Y1760992D01*
G01Y1764732D02*
Y1764142D01*
G01Y1762961D02*
Y1762370D01*
G01Y1758433D02*
Y1757843D01*
G01Y1756661D02*
Y1756071D01*
G01Y1759811D02*
Y1759220D01*
G01Y1752134D02*
Y1751543D01*
G01Y1755283D02*
Y1754693D01*
G01Y1753512D02*
Y1752921D01*
G01Y1748984D02*
Y1748394D01*
G01Y1747213D02*
Y1746622D01*
G01Y1750362D02*
Y1749772D01*
G01Y1742685D02*
Y1742094D01*
G01Y1745835D02*
Y1745244D01*
G01Y1744063D02*
Y1743472D01*
G01Y1739535D02*
Y1738945D01*
G01Y1737764D02*
Y1737173D01*
G01Y1740913D02*
Y1740323D01*
G01Y1733236D02*
Y1732646D01*
G01Y1736386D02*
Y1735795D01*
G01Y1734614D02*
Y1734024D01*
G01Y1730087D02*
Y1729496D01*
G01Y1731465D02*
Y1730874D01*
G01Y1726937D02*
Y1726346D01*
G01Y1728315D02*
Y1727724D01*
G01X512Y1785008D02*
Y1784417D01*
G01Y1780480D02*
Y1779890D01*
G01Y1783630D02*
Y1783039D01*
G01Y1781858D02*
Y1781268D01*
G01Y1777331D02*
Y1776740D01*
G01Y1775559D02*
Y1774969D01*
G01Y1778709D02*
Y1778118D01*
G01Y1771031D02*
Y1770441D01*
G01Y1774181D02*
Y1773591D01*
G01Y1772409D02*
Y1771819D01*
G01Y1767882D02*
Y1767291D01*
G01Y1766110D02*
Y1765520D01*
G01Y1769260D02*
Y1768669D01*
G01Y1761583D02*
Y1760992D01*
G01Y1764732D02*
Y1764142D01*
G01Y1762961D02*
Y1762370D01*
G01Y1758433D02*
Y1757843D01*
G01Y1756661D02*
Y1756071D01*
G01Y1759811D02*
Y1759220D01*
G01Y1752134D02*
Y1751543D01*
G01Y1755283D02*
Y1754693D01*
G01Y1753512D02*
Y1752921D01*
G01Y1748984D02*
Y1748394D01*
G01Y1747213D02*
Y1746622D01*
G01Y1750362D02*
Y1749772D01*
G01Y1742685D02*
Y1742094D01*
G01Y1745835D02*
Y1745244D01*
G01Y1744063D02*
Y1743472D01*
G01Y1739535D02*
Y1738945D01*
G01Y1737764D02*
Y1737173D01*
G01Y1740913D02*
Y1740323D01*
G01Y1733236D02*
Y1732646D01*
G01Y1736386D02*
Y1735795D01*
G01Y1734614D02*
Y1734024D01*
G01Y1730087D02*
Y1729496D01*
G01Y1731465D02*
Y1730874D01*
G01Y1726937D02*
Y1726346D01*
G01Y1728315D02*
Y1727724D01*
G01X709Y1786189D02*
Y1785008D01*
G01Y1779890D02*
Y1778709D01*
G01Y1783039D02*
Y1781858D01*
G01Y1776740D02*
Y1775559D01*
G01Y1773591D02*
Y1772409D01*
G01Y1767291D02*
Y1766110D01*
G01Y1770441D02*
Y1769260D01*
G01Y1764142D02*
Y1762961D01*
G01Y1757843D02*
Y1756661D01*
G01Y1760992D02*
Y1759811D01*
G01Y1754693D02*
Y1753512D01*
G01Y1748394D02*
Y1747213D01*
G01Y1751543D02*
Y1750362D01*
G01Y1745244D02*
Y1744063D01*
G01Y1738945D02*
Y1737764D01*
G01Y1742094D02*
Y1740913D01*
G01Y1735795D02*
Y1734614D01*
G01Y1729496D02*
Y1728315D01*
G01Y1732646D02*
Y1731465D01*
G01X1074Y1786189D02*
Y1785008D01*
G01Y1779890D02*
Y1778709D01*
G01Y1783039D02*
Y1781858D01*
G01Y1776740D02*
Y1775559D01*
G01Y1773591D02*
Y1772409D01*
G01Y1767291D02*
Y1766110D01*
G01Y1770441D02*
Y1769260D01*
G01Y1764142D02*
Y1762961D01*
G01Y1757843D02*
Y1756661D01*
G01Y1760992D02*
Y1759811D01*
G01Y1754693D02*
Y1753512D01*
G01Y1748394D02*
Y1747213D01*
G01Y1751543D02*
Y1750362D01*
G01Y1745244D02*
Y1744063D01*
G01Y1738945D02*
Y1737764D01*
G01Y1742094D02*
Y1740913D01*
G01Y1735795D02*
Y1734614D01*
G01Y1729496D02*
Y1728315D01*
G01Y1732646D02*
Y1731465D01*
G01X1184Y1786189D02*
Y1785008D01*
G01Y1779890D02*
Y1778709D01*
G01Y1783039D02*
Y1781858D01*
G01Y1776740D02*
Y1775559D01*
G01Y1773591D02*
Y1772409D01*
G01Y1767291D02*
Y1766110D01*
G01Y1770441D02*
Y1769260D01*
G01Y1764142D02*
Y1762961D01*
G01Y1757843D02*
Y1756661D01*
G01Y1760992D02*
Y1759811D01*
G01Y1754693D02*
Y1753512D01*
G01Y1748394D02*
Y1747213D01*
G01Y1751543D02*
Y1750362D01*
G01Y1745244D02*
Y1744063D01*
G01Y1738945D02*
Y1737764D01*
G01Y1742094D02*
Y1740913D01*
G01Y1735795D02*
Y1734614D01*
G01Y1729496D02*
Y1728315D01*
G01Y1732646D02*
Y1731465D01*
G01X9965Y1786189D02*
Y1785008D01*
G01Y1779890D02*
Y1778709D01*
G01Y1783039D02*
Y1781858D01*
G01Y1776740D02*
Y1775559D01*
G01Y1773591D02*
Y1772409D01*
G01Y1767291D02*
Y1766110D01*
G01Y1770441D02*
Y1769260D01*
G01Y1764142D02*
Y1762961D01*
G01Y1757843D02*
Y1756661D01*
G01Y1760992D02*
Y1759811D01*
G01Y1754693D02*
Y1753512D01*
G01Y1748394D02*
Y1747213D01*
G01Y1751543D02*
Y1750362D01*
G01Y1745244D02*
Y1744063D01*
G01Y1738945D02*
Y1737764D01*
G01Y1742094D02*
Y1740913D01*
G01Y1735795D02*
Y1734614D01*
G01Y1729496D02*
Y1728315D01*
G01Y1732646D02*
Y1731465D01*
G01X10075Y1786189D02*
Y1785008D01*
G01Y1779890D02*
Y1778709D01*
G01Y1783039D02*
Y1781858D01*
G01Y1776740D02*
Y1775559D01*
G01Y1773591D02*
Y1772409D01*
G01Y1767291D02*
Y1766110D01*
G01Y1770441D02*
Y1769260D01*
G01Y1764142D02*
Y1762961D01*
G01Y1757843D02*
Y1756661D01*
G01Y1760992D02*
Y1759811D01*
G01Y1754693D02*
Y1753512D01*
G01Y1748394D02*
Y1747213D01*
G01Y1751543D02*
Y1750362D01*
G01Y1745244D02*
Y1744063D01*
G01Y1738945D02*
Y1737764D01*
G01Y1742094D02*
Y1740913D01*
G01Y1735795D02*
Y1734614D01*
G01Y1729496D02*
Y1728315D01*
G01Y1732646D02*
Y1731465D01*
G01X-14677Y1728413D02*
X-14537Y1728326D01*
G01X-14449Y1728413D02*
X-13977Y1728118D01*
G01X-14677Y1731563D02*
X-14537Y1731475D01*
G01X-14449Y1731563D02*
X-13977Y1731268D01*
G01X-14677Y1734713D02*
X-14537Y1734625D01*
G01X-14449Y1734713D02*
X-13977Y1734417D01*
G01X-14677Y1737862D02*
X-14537Y1737774D01*
G01X-14449Y1737862D02*
X-13977Y1737567D01*
G01X-14677Y1741012D02*
X-14537Y1740924D01*
G01X-14449Y1741012D02*
X-13977Y1740717D01*
G01X-14677Y1744161D02*
X-14537Y1744074D01*
G01X-14449Y1744161D02*
X-13977Y1743866D01*
G01X-14677Y1747311D02*
X-14537Y1747223D01*
G01X-14449Y1747311D02*
X-13977Y1747016D01*
G01X-14677Y1750461D02*
X-14537Y1750373D01*
G01X-14449Y1750461D02*
X-13977Y1750165D01*
G01X-14677Y1753610D02*
X-14537Y1753522D01*
G01X-14449Y1753610D02*
X-13977Y1753315D01*
G01X-14677Y1756760D02*
X-14537Y1756672D01*
G01X-14449Y1756760D02*
X-13977Y1756465D01*
G01X-14677Y1759909D02*
X-14537Y1759822D01*
G01X-14449Y1759909D02*
X-13977Y1759614D01*
G01X-14677Y1763059D02*
X-14537Y1762971D01*
G01X-14449Y1763059D02*
X-13977Y1762764D01*
G01X-14677Y1766209D02*
X-14537Y1766121D01*
G01X-14449Y1766209D02*
X-13977Y1765913D01*
G01X-14677Y1769358D02*
X-14537Y1769270D01*
G01X-14449Y1769358D02*
X-13977Y1769063D01*
G01X-14677Y1772508D02*
X-14537Y1772420D01*
G01X-14449Y1772508D02*
X-13977Y1772213D01*
G01X-14677Y1775657D02*
X-14537Y1775570D01*
G01X-14449Y1775657D02*
X-13977Y1775362D01*
G01X-14677Y1778807D02*
X-14537Y1778719D01*
G01X-14449Y1778807D02*
X-13977Y1778512D01*
G01X-14677Y1781957D02*
X-14537Y1781869D01*
G01X-14449Y1781957D02*
X-13977Y1781661D01*
G01X-14677Y1785106D02*
X-14537Y1785019D01*
G01X-14449Y1785106D02*
X-13977Y1784811D01*
G01X-14537Y1728326D02*
X-14147Y1728118D01*
G01X-14537Y1731475D02*
X-14147Y1731268D01*
G01X-14537Y1734625D02*
X-14147Y1734417D01*
G01X-14537Y1737774D02*
X-14147Y1737567D01*
G01X-14537Y1740924D02*
X-14147Y1740717D01*
G01X-14537Y1744074D02*
X-14147Y1743866D01*
G01X-14537Y1747223D02*
X-14147Y1747016D01*
G01X-14537Y1750373D02*
X-14147Y1750165D01*
G01X-14537Y1753522D02*
X-14147Y1753315D01*
G01X-14537Y1756672D02*
X-14147Y1756465D01*
G01X-14537Y1759822D02*
X-14147Y1759614D01*
G01X-14537Y1762971D02*
X-14147Y1762764D01*
G01X-14537Y1766121D02*
X-14147Y1765913D01*
G01X-14537Y1769270D02*
X-14147Y1769063D01*
G01X-14537Y1772420D02*
X-14147Y1772213D01*
G01X-14537Y1775570D02*
X-14147Y1775362D01*
G01X-14537Y1778719D02*
X-14147Y1778512D01*
G01X-14537Y1781869D02*
X-14147Y1781661D01*
G01X-14537Y1785019D02*
X-14147Y1784811D01*
G01X-22952Y1786123D02*
X-18429Y1784647D01*
G01X-17759Y1784483D02*
X-15748Y1783827D01*
G01X-23622Y1785467D02*
X-15748Y1782843D01*
G01X-19469Y1726196D02*
X-18174Y1726210D01*
G01X-18435D02*
X-20801Y1726184D01*
G01X-18174Y1726210D02*
X-17126Y1726221D01*
G01X-19469Y1729345D02*
X-18174Y1729359D01*
G01X-18435D02*
X-20801Y1729333D01*
G01X-18174Y1729359D02*
X-17126Y1729371D01*
G01X-19469Y1732495D02*
X-18174Y1732509D01*
G01X-18435D02*
X-20801Y1732483D01*
G01X-18174Y1732509D02*
X-17126Y1732520D01*
G01X-19469Y1735644D02*
X-18174Y1735659D01*
G01X-18435D02*
X-20801Y1735633D01*
G01X-18174Y1735659D02*
X-17126Y1735670D01*
G01X-19469Y1738794D02*
X-18174Y1738808D01*
G01X-18435D02*
X-20801Y1738782D01*
G01X-18174Y1738808D02*
X-17126Y1738820D01*
G01X-19469Y1741944D02*
X-18174Y1741958D01*
G01X-18435D02*
X-20801Y1741932D01*
G01X-18174Y1741958D02*
X-17126Y1741969D01*
G01X-19469Y1745093D02*
X-18174Y1745107D01*
G01X-18435D02*
X-20801Y1745081D01*
G01X-18174Y1745107D02*
X-17126Y1745119D01*
G01X-19469Y1748243D02*
X-18174Y1748257D01*
G01X-18435D02*
X-20801Y1748231D01*
G01X-18174Y1748257D02*
X-17126Y1748269D01*
G01X-19469Y1751393D02*
X-18174Y1751407D01*
G01X-18435D02*
X-20801Y1751381D01*
G01X-18174Y1751407D02*
X-17126Y1751418D01*
G01X-19469Y1754542D02*
X-18174Y1754556D01*
G01X-18435D02*
X-20801Y1754530D01*
G01X-18174Y1754556D02*
X-17126Y1754568D01*
G01X-19469Y1757692D02*
X-18174Y1757706D01*
G01X-18435D02*
X-20801Y1757680D01*
G01X-18174Y1757706D02*
X-17126Y1757717D01*
G01X-19469Y1760841D02*
X-18174Y1760856D01*
G01X-18435D02*
X-20801Y1760830D01*
G01X-18174Y1760856D02*
X-17126Y1760867D01*
G01X-19469Y1763991D02*
X-18174Y1764005D01*
G01X-18435D02*
X-20801Y1763979D01*
G01X-18174Y1764005D02*
X-17126Y1764017D01*
G01X-15985Y1726231D02*
X-14449Y1726248D01*
G01X-14677D02*
X-18174Y1726210D01*
G01X-14677Y1726248D02*
X-16213Y1726231D01*
G01X-15985Y1729381D02*
X-14449Y1729398D01*
G01X-14677D02*
X-18174Y1729359D01*
G01X-14677Y1729398D02*
X-16213Y1729381D01*
G01X-15985Y1732531D02*
X-14449Y1732547D01*
G01X-14677D02*
X-18174Y1732509D01*
G01X-14677Y1732547D02*
X-16213Y1732531D01*
G01X-15985Y1735680D02*
X-14449Y1735697D01*
G01X-14677D02*
X-18174Y1735659D01*
G01X-14677Y1735697D02*
X-16213Y1735680D01*
G01X-15985Y1738830D02*
X-14449Y1738846D01*
G01X-14677D02*
X-18174Y1738808D01*
G01X-14677Y1738846D02*
X-16213Y1738830D01*
G01X-15985Y1741980D02*
X-14449Y1741996D01*
G01X-14677D02*
X-18174Y1741958D01*
G01X-14677Y1741996D02*
X-16213Y1741980D01*
G01X-15985Y1745129D02*
X-14449Y1745146D01*
G01X-14677D02*
X-18174Y1745107D01*
G01X-14677Y1745146D02*
X-16213Y1745129D01*
G01X-15985Y1748279D02*
X-14449Y1748295D01*
G01X-14677D02*
X-18174Y1748257D01*
G01X-14677Y1748295D02*
X-16213Y1748279D01*
G01X-15985Y1751428D02*
X-14449Y1751445D01*
G01X-14677D02*
X-18174Y1751407D01*
G01X-14677Y1751445D02*
X-16213Y1751428D01*
G01X-15985Y1754578D02*
X-14449Y1754594D01*
G01X-14677D02*
X-18174Y1754556D01*
G01X-14677Y1754594D02*
X-16213Y1754578D01*
G01X-15985Y1757728D02*
X-14449Y1757744D01*
G01X-14677D02*
X-18174Y1757706D01*
G01X-14677Y1757744D02*
X-16213Y1757728D01*
G01X-15985Y1760877D02*
X-14449Y1760894D01*
G01X-14677D02*
X-18174Y1760856D01*
G01X-14677Y1760894D02*
X-16213Y1760877D01*
G01X-15985Y1764027D02*
X-14449Y1764043D01*
G01X-14677D02*
X-18174Y1764005D01*
G01X-14677Y1764043D02*
X-16213Y1764027D01*
G01X-19469Y1726196D02*
X-20801Y1726184D01*
G01X-19469Y1729345D02*
X-20801Y1729333D01*
G01X-19469Y1732495D02*
X-20801Y1732483D01*
G01X-19469Y1735644D02*
X-20801Y1735633D01*
G01X-19469Y1738794D02*
X-20801Y1738782D01*
G01X-19469Y1741944D02*
X-20801Y1741932D01*
G01X-19469Y1745093D02*
X-20801Y1745081D01*
G01X-19469Y1748243D02*
X-20801Y1748231D01*
G01X-19469Y1751393D02*
X-20801Y1751381D01*
G01X-19469Y1754542D02*
X-20801Y1754530D01*
G01X-19469Y1757692D02*
X-20801Y1757680D01*
G01X-19469Y1760841D02*
X-20801Y1760830D01*
G01X-19469Y1763991D02*
X-20801Y1763979D01*
G01X-19469Y1767141D02*
X-20801Y1767129D01*
G01X-15985Y1726231D02*
X-17126Y1726221D01*
G01D02*
X-18435Y1726210D01*
G01X-15985Y1729381D02*
X-17126Y1729371D01*
G01D02*
X-18435Y1729359D01*
G01X-15985Y1732531D02*
X-17126Y1732520D01*
G01D02*
X-18435Y1732509D01*
G01X-15985Y1735680D02*
X-17126Y1735670D01*
G01D02*
X-18435Y1735659D01*
G01X-15985Y1738830D02*
X-17126Y1738820D01*
G01D02*
X-18435Y1738808D01*
G01X-15985Y1741980D02*
X-17126Y1741969D01*
G01D02*
X-18435Y1741958D01*
G01X-15985Y1745129D02*
X-17126Y1745119D01*
G01D02*
X-18435Y1745107D01*
G01X-15985Y1748279D02*
X-17126Y1748269D01*
G01D02*
X-18435Y1748257D01*
G01X-15985Y1751428D02*
X-17126Y1751418D01*
G01D02*
X-18435Y1751407D01*
G01X-15985Y1754578D02*
X-17126Y1754568D01*
G01D02*
X-18435Y1754556D01*
G01X-15985Y1757728D02*
X-17126Y1757717D01*
G01D02*
X-18435Y1757706D01*
G01X-15985Y1760877D02*
X-17126Y1760867D01*
G01D02*
X-18435Y1760856D01*
G01X-15985Y1764027D02*
X-17126Y1764017D01*
G01D02*
X-18435Y1764005D01*
G01X-15985Y1767176D02*
X-17126Y1767166D01*
G01D02*
X-18435Y1767155D01*
G01X-15985Y1725280D02*
X-16213D01*
G01X-18174Y1725302D02*
X-18435D01*
G01X-18174Y1726210D02*
X-18435D01*
G01X-15985Y1726231D02*
X-16213D01*
G01X-14449Y1726248D02*
X-14677D01*
G01X12410Y1726346D02*
X315D01*
G01X-13009Y1726543D02*
X-14147D01*
G01X512Y1726937D02*
X0D01*
G01X512Y1727724D02*
X0D01*
G01X-13009Y1728118D02*
X-14147D01*
G01X12410Y1728315D02*
X315D01*
G01X-14449Y1728413D02*
X-14677D01*
G01X-15985Y1728430D02*
X-16213D01*
G01X-18174Y1728451D02*
X-18435D01*
G01X-18174Y1729359D02*
X-18435D01*
G01X-15985Y1729381D02*
X-16213D01*
G01X-14449Y1729398D02*
X-14677D01*
G01X12410Y1729496D02*
X315D01*
G01X-13009Y1729693D02*
X-14147D01*
G01X512Y1730087D02*
X0D01*
G01X512Y1730874D02*
X0D01*
G01X-13009Y1731268D02*
X-14147D01*
G01X12410Y1731465D02*
X315D01*
G01X-14449Y1731563D02*
X-14677D01*
G01X-15985Y1731579D02*
X-16213D01*
G01X-18174Y1731601D02*
X-18435D01*
G01X-18174Y1732509D02*
X-18435D01*
G01X-15985Y1732531D02*
X-16213D01*
G01X-14449Y1732547D02*
X-14677D01*
G01X12410Y1732646D02*
X315D01*
G01X-13009Y1732843D02*
X-14147D01*
G01X512Y1733236D02*
X0D01*
G01X512Y1734024D02*
X0D01*
G01X-13009Y1734417D02*
X-14147D01*
G01X12410Y1734614D02*
X315D01*
G01X-14449Y1734713D02*
X-14677D01*
G01X-15985Y1734729D02*
X-16213D01*
G01X-18174Y1734750D02*
X-18435D01*
G01X-18174Y1735659D02*
X-18435D01*
G01X-15985Y1735680D02*
X-16213D01*
G01X-14449Y1735697D02*
X-14677D01*
G01X12410Y1735795D02*
X315D01*
G01X-13009Y1735992D02*
X-14147D01*
G01X512Y1736386D02*
X0D01*
G01X512Y1737173D02*
X0D01*
G01X-13009Y1737567D02*
X-14147D01*
G01X12410Y1737764D02*
X315D01*
G01X-14449Y1737862D02*
X-14677D01*
G01X-15985Y1737878D02*
X-16213D01*
G01X-18174Y1737900D02*
X-18435D01*
G01X-18174Y1738808D02*
X-18435D01*
G01X-15985Y1738830D02*
X-16213D01*
G01X-14449Y1738846D02*
X-14677D01*
G01X12410Y1738945D02*
X315D01*
G01X-13009Y1739142D02*
X-14147D01*
G01X512Y1739535D02*
X0D01*
G01X512Y1740323D02*
X0D01*
G01X-13009Y1740717D02*
X-14147D01*
G01X12410Y1740913D02*
X315D01*
G01X-14449Y1741012D02*
X-14677D01*
G01X-15985Y1741028D02*
X-16213D01*
G01X-18174Y1741050D02*
X-18435D01*
G01X-18174Y1741958D02*
X-18435D01*
G01X-15985Y1741980D02*
X-16213D01*
G01X-14449Y1741996D02*
X-14677D01*
G01X12410Y1742094D02*
X315D01*
G01X-13009Y1742291D02*
X-14147D01*
G01X512Y1742685D02*
X0D01*
G01X512Y1743472D02*
X0D01*
G01X-13009Y1743866D02*
X-14147D01*
G01X12410Y1744063D02*
X315D01*
G01X-14449Y1744161D02*
X-14677D01*
G01X-15985Y1744178D02*
X-16213D01*
G01X-18174Y1744199D02*
X-18435D01*
G01X-18174Y1745107D02*
X-18435D01*
G01X-15985Y1745129D02*
X-16213D01*
G01X-14449Y1745146D02*
X-14677D01*
G01X12410Y1745244D02*
X315D01*
G01X-13009Y1745441D02*
X-14147D01*
G01X512Y1745835D02*
X0D01*
G01X512Y1746622D02*
X0D01*
G01X-13009Y1747016D02*
X-14147D01*
G01X12410Y1747213D02*
X315D01*
G01X-14449Y1747311D02*
X-14677D01*
G01X-15985Y1747327D02*
X-16213D01*
G01X-18174Y1747349D02*
X-18435D01*
G01X-18174Y1748257D02*
X-18435D01*
G01X-15985Y1748279D02*
X-16213D01*
G01X-14449Y1748295D02*
X-14677D01*
G01X12410Y1748394D02*
X315D01*
G01X-13009Y1748591D02*
X-14147D01*
G01X512Y1748984D02*
X0D01*
G01X512Y1749772D02*
X0D01*
G01X-13009Y1750165D02*
X-14147D01*
G01X12410Y1750362D02*
X315D01*
G01X-14449Y1750461D02*
X-14677D01*
G01X-15985Y1750477D02*
X-16213D01*
G01X-18174Y1750498D02*
X-18435D01*
G01X-18174Y1751407D02*
X-18435D01*
G01X-15985Y1751428D02*
X-16213D01*
G01X-14449Y1751445D02*
X-14677D01*
G01X12410Y1751543D02*
X315D01*
G01X-13009Y1751740D02*
X-14147D01*
G01X512Y1752134D02*
X0D01*
G01X512Y1752921D02*
X0D01*
G01X-13009Y1753315D02*
X-14147D01*
G01X12410Y1753512D02*
X315D01*
G01X-14449Y1753610D02*
X-14677D01*
G01X-15985Y1753626D02*
X-16213D01*
G01X-18174Y1753648D02*
X-18435D01*
G01X-18174Y1754556D02*
X-18435D01*
G01X-15985Y1754578D02*
X-16213D01*
G01X-14449Y1754594D02*
X-14677D01*
G01X12410Y1754693D02*
X315D01*
G01X-13009Y1754890D02*
X-14147D01*
G01X512Y1755283D02*
X0D01*
G01X512Y1756071D02*
X0D01*
G01X-13009Y1756465D02*
X-14147D01*
G01X12410Y1756661D02*
X315D01*
G01X-14449Y1756760D02*
X-14677D01*
G01X-15985Y1756776D02*
X-16213D01*
G01X-18174Y1756798D02*
X-18435D01*
G01X-18174Y1757706D02*
X-18435D01*
G01X-15985Y1757728D02*
X-16213D01*
G01X-14449Y1757744D02*
X-14677D01*
G01X12410Y1757843D02*
X315D01*
G01X-13009Y1758039D02*
X-14147D01*
G01X512Y1758433D02*
X0D01*
G01X512Y1759220D02*
X0D01*
G01X-13009Y1759614D02*
X-14147D01*
G01X12410Y1759811D02*
X315D01*
G01X-14449Y1759909D02*
X-14677D01*
G01X-15985Y1759926D02*
X-16213D01*
G01X-18174Y1759947D02*
X-18435D01*
G01X-18174Y1760856D02*
X-18435D01*
G01X-15985Y1760877D02*
X-16213D01*
G01X-14449Y1760894D02*
X-14677D01*
G01X12410Y1760992D02*
X315D01*
G01X-13009Y1761189D02*
X-14147D01*
G01X512Y1761583D02*
X0D01*
G01X512Y1762370D02*
X0D01*
G01X-13009Y1762764D02*
X-14147D01*
G01X12410Y1762961D02*
X315D01*
G01X-14449Y1763059D02*
X-14677D01*
G01X-15985Y1763075D02*
X-16213D01*
G01X-18174Y1763097D02*
X-18435D01*
G01X-18174Y1764005D02*
X-18435D01*
G01X-15985Y1764027D02*
X-16213D01*
G01X-14449Y1764043D02*
X-14677D01*
G01X12410Y1764142D02*
X315D01*
G01X-13009Y1764339D02*
X-14147D01*
G01X512Y1764732D02*
X0D01*
G01X512Y1765520D02*
X0D01*
G01X-13009Y1765913D02*
X-14147D01*
G01X12410Y1766110D02*
X315D01*
G01X-14449Y1766209D02*
X-14677D01*
G01X-15985Y1766225D02*
X-16213D01*
G01X-18174Y1766246D02*
X-18435D01*
G01X-18174Y1767155D02*
X-18435D01*
G01X-15985Y1767176D02*
X-16213D01*
G01X-14449Y1767193D02*
X-14677D01*
G01X12410Y1767291D02*
X315D01*
G01X-13009Y1767488D02*
X-14147D01*
G01X512Y1767882D02*
X0D01*
G01X512Y1768669D02*
X0D01*
G01X-13009Y1769063D02*
X-14147D01*
G01X12410Y1769260D02*
X315D01*
G01X-14449Y1769358D02*
X-14677D01*
G01X-15985Y1769374D02*
X-16213D01*
G01X-18174Y1769396D02*
X-18435D01*
G01X-18174Y1770304D02*
X-18435D01*
G01X-15985Y1770326D02*
X-16213D01*
G01X-14449Y1770343D02*
X-14677D01*
G01X12410Y1770441D02*
X315D01*
G01X-13009Y1770638D02*
X-14147D01*
G01X512Y1771031D02*
X0D01*
G01X512Y1771819D02*
X0D01*
G01X-13009Y1772213D02*
X-14147D01*
G01X-19469Y1725316D02*
X-20801Y1725328D01*
G01X-15985Y1725280D02*
X-18435Y1725302D01*
G01X-19469Y1728466D02*
X-20801Y1728478D01*
G01X-15985Y1728430D02*
X-18435Y1728451D01*
G01X-19469Y1731615D02*
X-20801Y1731627D01*
G01X-15985Y1731579D02*
X-18435Y1731601D01*
G01X-19469Y1734765D02*
X-20801Y1734777D01*
G01X-15985Y1734729D02*
X-18435Y1734750D01*
G01X-19469Y1737915D02*
X-20801Y1737926D01*
G01X-15985Y1737878D02*
X-18435Y1737900D01*
G01X-19469Y1741064D02*
X-20801Y1741076D01*
G01X-15985Y1741028D02*
X-18435Y1741050D01*
G01X-19469Y1744214D02*
X-20801Y1744226D01*
G01X-15985Y1744178D02*
X-18435Y1744199D01*
G01X-19469Y1747363D02*
X-20801Y1747375D01*
G01X-15985Y1747327D02*
X-18435Y1747349D01*
G01X-19469Y1750513D02*
X-20801Y1750525D01*
G01X-15985Y1750477D02*
X-18435Y1750498D01*
G01X-19469Y1753663D02*
X-20801Y1753674D01*
G01X-15985Y1753626D02*
X-18435Y1753648D01*
G01X-19469Y1756812D02*
X-20801Y1756824D01*
G01X-15985Y1756776D02*
X-18435Y1756798D01*
G01X-19469Y1759962D02*
X-20801Y1759974D01*
G01X-15985Y1759926D02*
X-18435Y1759947D01*
G01X-19469Y1763111D02*
X-20801Y1763123D01*
G01X-15985Y1763075D02*
X-18435Y1763097D01*
G01X-19469Y1766261D02*
X-20801Y1766273D01*
G01X-15985Y1766225D02*
X-18435Y1766246D01*
G01X-19469Y1769411D02*
X-20801Y1769422D01*
G01X-15985Y1769374D02*
X-18435Y1769396D01*
G01X-19469Y1772560D02*
X-20801Y1772572D01*
G01X-15985Y1772524D02*
X-18435Y1772546D01*
G01X-19469Y1775710D02*
X-20801Y1775722D01*
G01X-15985Y1775674D02*
X-18435Y1775695D01*
G01X-15985Y1728430D02*
X-14449Y1728413D01*
G01X-15985Y1731579D02*
X-14449Y1731563D01*
G01X-15985Y1734729D02*
X-14449Y1734713D01*
G01X-15985Y1737878D02*
X-14449Y1737862D01*
G01X-15985Y1741028D02*
X-14449Y1741012D01*
G01X-15985Y1744178D02*
X-14449Y1744161D01*
G01X-15985Y1747327D02*
X-14449Y1747311D01*
G01X-15985Y1750477D02*
X-14449Y1750461D01*
G01X-15985Y1753626D02*
X-14449Y1753610D01*
G01X-15985Y1756776D02*
X-14449Y1756760D01*
G01X-15985Y1759926D02*
X-14449Y1759909D01*
G01X-15985Y1763075D02*
X-14449Y1763059D01*
G01X-15985Y1766225D02*
X-14449Y1766209D01*
G01X-15985Y1769374D02*
X-14449Y1769358D01*
G01X-15985Y1772524D02*
X-14449Y1772508D01*
G01X-15985Y1775674D02*
X-14449Y1775657D01*
G01X-18435Y1725302D02*
X-20801Y1725328D01*
G01X-18435Y1728451D02*
X-20801Y1728478D01*
G01X-18435Y1731601D02*
X-20801Y1731627D01*
G01X-18435Y1734750D02*
X-20801Y1734777D01*
G01X-18435Y1737900D02*
X-20801Y1737926D01*
G01X-18435Y1741050D02*
X-20801Y1741076D01*
G01X-18435Y1744199D02*
X-20801Y1744226D01*
G01X-18435Y1747349D02*
X-20801Y1747375D01*
G01X-18435Y1750498D02*
X-20801Y1750525D01*
G01X-18435Y1753648D02*
X-20801Y1753674D01*
G01X-18435Y1756798D02*
X-20801Y1756824D01*
G01X-18435Y1759947D02*
X-20801Y1759974D01*
G01X-18435Y1763097D02*
X-20801Y1763123D01*
G01X-18435Y1766246D02*
X-20801Y1766273D01*
G01X-18435Y1769396D02*
X-20801Y1769422D01*
G01X-18435Y1772546D02*
X-20801Y1772572D01*
G01X-18435Y1775695D02*
X-20801Y1775722D01*
G01X-19469Y1725316D02*
X-16213Y1725280D01*
G01X-19469Y1728466D02*
X-16213Y1728430D01*
G01X-18174Y1728451D02*
X-14677Y1728413D01*
G01X-19469Y1731615D02*
X-16213Y1731579D01*
G01X-18174Y1731601D02*
X-14677Y1731563D01*
G01X-19469Y1734765D02*
X-16213Y1734729D01*
G01X-18174Y1734750D02*
X-14677Y1734713D01*
G01X-19469Y1737915D02*
X-16213Y1737878D01*
G01X-18174Y1737900D02*
X-14677Y1737862D01*
G01X-19469Y1741064D02*
X-16213Y1741028D01*
G01X-18174Y1741050D02*
X-14677Y1741012D01*
G01X-19469Y1744214D02*
X-16213Y1744178D01*
G01X-18174Y1744199D02*
X-14677Y1744161D01*
G01X-19469Y1747363D02*
X-16213Y1747327D01*
G01X-18174Y1747349D02*
X-14677Y1747311D01*
G01X-19469Y1750513D02*
X-16213Y1750477D01*
G01X-18174Y1750498D02*
X-14677Y1750461D01*
G01X-19469Y1753663D02*
X-16213Y1753626D01*
G01X-18174Y1753648D02*
X-14677Y1753610D01*
G01X-19469Y1756812D02*
X-16213Y1756776D01*
G01X-18174Y1756798D02*
X-14677Y1756760D01*
G01X-19469Y1759962D02*
X-16213Y1759926D01*
G01X-18174Y1759947D02*
X-14677Y1759909D01*
G01X-19469Y1763111D02*
X-16213Y1763075D01*
G01X-18174Y1763097D02*
X-14677Y1763059D01*
G01X-19469Y1766261D02*
X-16213Y1766225D01*
G01X-18174Y1766246D02*
X-14677Y1766209D01*
G01X-19469Y1769411D02*
X-16213Y1769374D01*
G01X-18174Y1769396D02*
X-14677Y1769358D01*
G01X-19469Y1772560D02*
X-16213Y1772524D01*
G01X-18174Y1772546D02*
X-14677Y1772508D01*
G01X-19469Y1775710D02*
X-16213Y1775674D01*
G01X-18174Y1775695D02*
X-14677Y1775657D01*
G01X-19469Y1767141D02*
X-18174Y1767155D01*
G01X-18435D02*
X-20801Y1767129D01*
G01X-18174Y1767155D02*
X-17126Y1767166D01*
G01X-19469Y1770290D02*
X-18174Y1770304D01*
G01X-18435D02*
X-20801Y1770278D01*
G01X-18174Y1770304D02*
X-17126Y1770316D01*
G01X-19469Y1773440D02*
X-18174Y1773454D01*
G01X-18435D02*
X-20801Y1773428D01*
G01X-18174Y1773454D02*
X-17126Y1773465D01*
G01X-19469Y1776589D02*
X-18174Y1776604D01*
G01X-18435D02*
X-20801Y1776578D01*
G01X-18174Y1776604D02*
X-17126Y1776615D01*
G01X-19469Y1779739D02*
X-18174Y1779753D01*
G01X-18435D02*
X-20801Y1779727D01*
G01X-18174Y1779753D02*
X-17126Y1779765D01*
G01X-19469Y1782889D02*
X-18174Y1782903D01*
G01X-18435D02*
X-20801Y1782877D01*
G01X-18174Y1782903D02*
X-17126Y1782914D01*
G01X-15985Y1767176D02*
X-14449Y1767193D01*
G01X-14677D02*
X-18174Y1767155D01*
G01X-14677Y1767193D02*
X-16213Y1767176D01*
G01X-15985Y1770326D02*
X-14449Y1770343D01*
G01X-14677D02*
X-18174Y1770304D01*
G01X-14677Y1770343D02*
X-16213Y1770326D01*
G01X-15985Y1773476D02*
X-14449Y1773492D01*
G01X-14677D02*
X-18174Y1773454D01*
G01X-14677Y1773492D02*
X-16213Y1773476D01*
G01X-15985Y1776625D02*
X-14449Y1776642D01*
G01X-14677D02*
X-18174Y1776604D01*
G01X-14677Y1776642D02*
X-16213Y1776625D01*
G01X-15985Y1779775D02*
X-14449Y1779791D01*
G01X-14677D02*
X-18174Y1779753D01*
G01X-14677Y1779791D02*
X-16213Y1779775D01*
G01X-15985Y1782924D02*
X-14449Y1782941D01*
G01X-14677D02*
X-18174Y1782903D01*
G01X-14677Y1782941D02*
X-16213Y1782924D01*
G01X-19469Y1770290D02*
X-20801Y1770278D01*
G01X-19469Y1773440D02*
X-20801Y1773428D01*
G01X-19469Y1776589D02*
X-20801Y1776578D01*
G01X-19469Y1779739D02*
X-20801Y1779727D01*
G01X-19469Y1782889D02*
X-20801Y1782877D01*
G01X-15985Y1770326D02*
X-17126Y1770316D01*
G01D02*
X-18435Y1770304D01*
G01X-15985Y1773476D02*
X-17126Y1773465D01*
G01D02*
X-18435Y1773454D01*
G01X-15985Y1776625D02*
X-17126Y1776615D01*
G01D02*
X-18435Y1776604D01*
G01X-15985Y1779775D02*
X-17126Y1779765D01*
G01D02*
X-18435Y1779753D01*
G01X-15985Y1782924D02*
X-17126Y1782914D01*
G01D02*
X-18435Y1782903D01*
G01X12410Y1772409D02*
X315D01*
G01X-14449Y1772508D02*
X-14677D01*
G01X-15985Y1772524D02*
X-16213D01*
G01X-18174Y1772546D02*
X-18435D01*
G01X-18174Y1773454D02*
X-18435D01*
G01X-15985Y1773476D02*
X-16213D01*
G01X-14449Y1773492D02*
X-14677D01*
G01X12410Y1773591D02*
X315D01*
G01X-13009Y1773787D02*
X-14147D01*
G01X512Y1774181D02*
X0D01*
G01X512Y1774969D02*
X0D01*
G01X-13009Y1775362D02*
X-14147D01*
G01X12410Y1775559D02*
X315D01*
G01X-14449Y1775657D02*
X-14677D01*
G01X-15985Y1775674D02*
X-16213D01*
G01X-18174Y1775695D02*
X-18435D01*
G01X-18174Y1776604D02*
X-18435D01*
G01X-16213Y1776625D02*
X-15985D01*
G01X-14449Y1776642D02*
X-14677D01*
G01X12410Y1776740D02*
X315D01*
G01X-13009Y1776937D02*
X-14147D01*
G01X512Y1777331D02*
X0D01*
G01X512Y1778118D02*
X0D01*
G01X-13009Y1778512D02*
X-14147D01*
G01X12410Y1778709D02*
X315D01*
G01X-14449Y1778807D02*
X-14677D01*
G01X-15985Y1778823D02*
X-16213D01*
G01X-18174Y1778845D02*
X-18435D01*
G01X-18174Y1779753D02*
X-18435D01*
G01X-15985Y1779775D02*
X-16213D01*
G01X-14449Y1779791D02*
X-14677D01*
G01X12410Y1779890D02*
X315D01*
G01X-13009Y1780087D02*
X-14147D01*
G01X512Y1780480D02*
X0D01*
G01X512Y1781268D02*
X0D01*
G01X-13009Y1781661D02*
X-14147D01*
G01X12410Y1781858D02*
X315D01*
G01X-14449Y1781957D02*
X-14677D01*
G01X-15985Y1781973D02*
X-16213D01*
G01X-18174Y1781994D02*
X-18435D01*
G01X-18174Y1782903D02*
X-18435D01*
G01X-15985Y1782924D02*
X-16213D01*
G01X-14449Y1782941D02*
X-14677D01*
G01X12410Y1783039D02*
X315D01*
G01X-13009Y1783236D02*
X-14147D01*
G01X512Y1783630D02*
X0D01*
G01X512Y1784417D02*
X0D01*
G01X-13009Y1784811D02*
X-14147D01*
G01X12410Y1785008D02*
X315D01*
G01X-14449Y1785106D02*
X-14677D01*
G01X-15985Y1785122D02*
X-16213D01*
G01X-18174Y1785144D02*
X-18435D01*
G01X-19469Y1778859D02*
X-20801Y1778871D01*
G01X-15985Y1778823D02*
X-18435Y1778845D01*
G01X-19469Y1782009D02*
X-20801Y1782021D01*
G01X-15985Y1781973D02*
X-18435Y1781994D01*
G01X-19469Y1785159D02*
X-20801Y1785170D01*
G01X-15985Y1785122D02*
X-18435Y1785144D01*
G01X-15985Y1778823D02*
X-14449Y1778807D01*
G01X-15985Y1781973D02*
X-14449Y1781957D01*
G01X-15985Y1785122D02*
X-14449Y1785106D01*
G01X-18435Y1778845D02*
X-20801Y1778871D01*
G01X-18435Y1781994D02*
X-20801Y1782021D01*
G01X-18435Y1785144D02*
X-20801Y1785170D01*
G01X-19469Y1778859D02*
X-16213Y1778823D01*
G01X-18174Y1778845D02*
X-14677Y1778807D01*
G01X-19469Y1782009D02*
X-16213Y1781973D01*
G01X-18174Y1781994D02*
X-14677Y1781957D01*
G01X-19469Y1785159D02*
X-16213Y1785122D01*
G01X-18174Y1785144D02*
X-14677Y1785106D01*
G01X-14537Y1723186D02*
X-14677Y1723098D01*
G01X-13977Y1723394D02*
X-14449Y1723098D01*
G01X-14147Y1723394D02*
X-14537Y1723186D01*
G01X-20801Y1723034D02*
Y1722178D01*
G01X-19469Y1723040D02*
Y1722172D01*
G01X-18435Y1723060D02*
Y1722152D01*
G01X-18174Y1723060D02*
Y1722152D01*
G01X-16213Y1723082D02*
Y1722130D01*
G01X-15985Y1723082D02*
Y1722130D01*
G01X-14537Y1726336D02*
Y1725176D01*
G01Y1723186D02*
Y1722026D01*
G01X-13009Y1726543D02*
Y1724969D01*
G01Y1723394D02*
Y1721819D01*
G01X315Y1723787D02*
Y1723197D01*
G01Y1725165D02*
Y1724575D01*
G01Y1722016D02*
Y1721425D01*
G01X512Y1723787D02*
Y1723197D01*
G01Y1725165D02*
Y1724575D01*
G01Y1722016D02*
Y1721425D01*
G01X709Y1726346D02*
Y1725165D01*
G01Y1723197D02*
Y1722016D01*
G01X1074Y1726346D02*
Y1725165D01*
G01Y1723197D02*
Y1722016D01*
G01X1184Y1726346D02*
Y1725165D01*
G01Y1723197D02*
Y1722016D01*
G01X9965Y1726346D02*
Y1725165D01*
G01Y1723197D02*
Y1722016D01*
G01X10075Y1726346D02*
Y1725165D01*
G01Y1723197D02*
Y1722016D01*
G01X-14677Y1722114D02*
X-14537Y1722026D01*
G01X-14449Y1722114D02*
X-13977Y1721819D01*
G01X-14677Y1725264D02*
X-14537Y1725176D01*
G01X-14449Y1725264D02*
X-13977Y1724969D01*
G01X-14537Y1722026D02*
X-14147Y1721819D01*
G01X-14537Y1725176D02*
X-14147Y1724969D01*
G01X-19469Y1723046D02*
X-18174Y1723060D01*
G01X-18435D02*
X-20801Y1723034D01*
G01X-18174Y1723060D02*
X-17126Y1723072D01*
G01X-15985Y1723082D02*
X-14449Y1723098D01*
G01X-14677D02*
X-18174Y1723060D01*
G01X-14677Y1723098D02*
X-16213Y1723082D01*
G01X-19469Y1723046D02*
X-20801Y1723034D01*
G01X-15985Y1723082D02*
X-17126Y1723072D01*
G01D02*
X-18435Y1723060D01*
G01X512Y1721425D02*
X0D01*
G01X-13009Y1721819D02*
X-14147D01*
G01X12410Y1722016D02*
X315D01*
G01X-14449Y1722114D02*
X-14677D01*
G01X-15985Y1722130D02*
X-16213D01*
G01X-18174Y1722152D02*
X-18435D01*
G01X-18174Y1723060D02*
X-18435D01*
G01X-15985Y1723082D02*
X-16213D01*
G01X-14449Y1723098D02*
X-14677D01*
G01X12410Y1723197D02*
X315D01*
G01X-13009Y1723394D02*
X-14147D01*
G01X512Y1723787D02*
X0D01*
G01X512Y1724575D02*
X0D01*
G01X-13009Y1724969D02*
X-14147D01*
G01X12410Y1725165D02*
X315D01*
G01X-14449Y1725264D02*
X-14677D01*
G01X-19469Y1722167D02*
X-20801Y1722178D01*
G01X-15985Y1722130D02*
X-18435Y1722152D01*
G01X-15985Y1722130D02*
X-14449Y1722114D01*
G01X-15985Y1725280D02*
X-14449Y1725264D01*
G01X-18435Y1722152D02*
X-20801Y1722178D01*
G01X-19469Y1722167D02*
X-16213Y1722130D01*
G01X-18174Y1722152D02*
X-14677Y1722114D01*
G01X-18174Y1725302D02*
X-14677Y1725264D01*
G01X12287Y1823059D02*
X12057Y1822803D01*
G01X12287Y1819909D02*
X12057Y1819654D01*
G01X12287Y1816760D02*
X12057Y1816504D01*
G01X12287Y1813610D02*
X12057Y1813354D01*
G01X12287Y1810461D02*
X12057Y1810205D01*
G01X12287Y1807311D02*
X12057Y1807055D01*
G01X12287Y1804161D02*
X12057Y1803906D01*
G01X12634Y1823059D02*
X12416Y1822789D01*
G01X12634Y1819909D02*
X12416Y1819639D01*
G01X12634Y1816760D02*
X12416Y1816490D01*
G01X12634Y1813610D02*
X12416Y1813340D01*
G01X12634Y1810461D02*
X12416Y1810191D01*
G01X12634Y1807311D02*
X12416Y1807041D01*
G01X12634Y1804161D02*
X12416Y1803891D01*
G01X12634Y1801012D02*
X12416Y1800742D01*
G01X12634Y1797862D02*
X12416Y1797592D01*
G01X12634Y1794713D02*
X12416Y1794443D01*
G01X12287Y1801012D02*
X12057Y1800756D01*
G01X12287Y1797862D02*
X12057Y1797606D01*
G01X12287Y1794713D02*
X12057Y1794457D01*
G01Y1823984D02*
Y1822803D01*
G01Y1817685D02*
Y1816504D01*
G01Y1820835D02*
Y1819654D01*
G01Y1814535D02*
Y1813354D01*
G01Y1808236D02*
Y1807055D01*
G01Y1811386D02*
Y1810205D01*
G01Y1805087D02*
Y1803906D01*
G01Y1798787D02*
Y1797606D01*
G01Y1801937D02*
Y1800756D01*
G01Y1795638D02*
Y1794457D01*
G01X12410Y1823984D02*
Y1822803D01*
G01Y1817685D02*
Y1816504D01*
G01Y1820835D02*
Y1819654D01*
G01Y1814535D02*
Y1813354D01*
G01Y1808236D02*
Y1807055D01*
G01Y1811386D02*
Y1810205D01*
G01Y1805087D02*
Y1803906D01*
G01Y1798787D02*
Y1797606D01*
G01Y1801937D02*
Y1800756D01*
G01Y1795638D02*
Y1794457D01*
G01X13353Y1823728D02*
Y1823059D01*
G01Y1817429D02*
Y1816760D01*
G01Y1820579D02*
Y1819909D01*
G01Y1814280D02*
Y1813610D01*
G01Y1807980D02*
Y1807311D01*
G01Y1811130D02*
Y1810461D01*
G01Y1804831D02*
Y1804161D01*
G01Y1801681D02*
Y1801012D01*
G01Y1795382D02*
Y1794713D01*
G01Y1798531D02*
Y1797862D01*
G01X13701Y1823728D02*
Y1823059D01*
G01Y1817429D02*
Y1816760D01*
G01Y1820579D02*
Y1819909D01*
G01Y1814280D02*
Y1813610D01*
G01Y1807980D02*
Y1807311D01*
G01Y1811130D02*
Y1810461D01*
G01Y1804831D02*
Y1804161D01*
G01Y1801681D02*
Y1801012D01*
G01Y1795382D02*
Y1794713D01*
G01Y1798531D02*
Y1797862D01*
G01X12057Y1795638D02*
X12287Y1795382D01*
G01X12416Y1795652D02*
X12634Y1795382D01*
G01X12416Y1798802D02*
X12634Y1798531D01*
G01X12416Y1801951D02*
X12634Y1801681D01*
G01X12416Y1805101D02*
X12634Y1804831D01*
G01X12416Y1808250D02*
X12634Y1807980D01*
G01X12416Y1811400D02*
X12634Y1811130D01*
G01X12416Y1814550D02*
X12634Y1814280D01*
G01X12416Y1817699D02*
X12634Y1817429D01*
G01X12416Y1820849D02*
X12634Y1820579D01*
G01X12416Y1823998D02*
X12634Y1823728D01*
G01X12057Y1798787D02*
X12287Y1798531D01*
G01X12057Y1801937D02*
X12287Y1801681D01*
G01X12057Y1805087D02*
X12287Y1804831D01*
G01X12057Y1808236D02*
X12287Y1807980D01*
G01X12057Y1811386D02*
X12287Y1811130D01*
G01X12057Y1814535D02*
X12287Y1814280D01*
G01X12057Y1817685D02*
X12287Y1817429D01*
G01X12057Y1820835D02*
X12287Y1820579D01*
G01X12057Y1823984D02*
X12287Y1823728D01*
G01X13701Y1794713D02*
X12287D01*
G01X13701Y1795382D02*
X12287D01*
G01X13701Y1797862D02*
X12287D01*
G01X13701Y1798531D02*
X12287D01*
G01X13701Y1801012D02*
X12287D01*
G01X13701Y1801681D02*
X12287D01*
G01X13701Y1804161D02*
X12287D01*
G01X13701Y1804831D02*
X12287D01*
G01X13701Y1807311D02*
X12287D01*
G01X13701Y1807980D02*
X12287D01*
G01X13701Y1810461D02*
X12287D01*
G01X13701Y1811130D02*
X12287D01*
G01X13701Y1813610D02*
X12287D01*
G01X13701Y1814280D02*
X12287D01*
G01X13701Y1816760D02*
X12287D01*
G01X13701Y1817429D02*
X12287D01*
G01X13701Y1819909D02*
X12287D01*
G01X13701Y1820579D02*
X12287D01*
G01X13701Y1823059D02*
X12287D01*
G01X13701Y1823728D02*
X12287D01*
G01X22441Y1876543D02*
Y1847016D01*
G01Y1858433D02*
X11811D01*
G01X11861D02*
G03Y1867094I-50J4330D01*
G01X12634Y1835657D02*
X12416Y1835387D01*
G01X12634Y1832508D02*
X12416Y1832238D01*
G01X12634Y1829358D02*
X12416Y1829088D01*
G01X12634Y1826209D02*
X12416Y1825939D01*
G01X12287Y1835657D02*
X12057Y1835402D01*
G01X12287Y1832508D02*
X12057Y1832252D01*
G01X12287Y1829358D02*
X12057Y1829102D01*
G01X12287Y1826209D02*
X12057Y1825953D01*
G01Y1836583D02*
Y1835402D01*
G01Y1833433D02*
Y1832252D01*
G01Y1827134D02*
Y1825953D01*
G01Y1830283D02*
Y1829102D01*
G01X12410Y1836583D02*
Y1835402D01*
G01Y1833433D02*
Y1832252D01*
G01Y1827134D02*
Y1825953D01*
G01Y1830283D02*
Y1829102D01*
G01X13353Y1836327D02*
Y1835657D01*
G01Y1833177D02*
Y1832508D01*
G01Y1826878D02*
Y1826209D01*
G01Y1830028D02*
Y1829358D01*
G01X13701Y1836327D02*
Y1835657D01*
G01Y1833177D02*
Y1832508D01*
G01Y1826878D02*
Y1826209D01*
G01Y1830028D02*
Y1829358D01*
G01X12416Y1827148D02*
X12634Y1826878D01*
G01X12416Y1830298D02*
X12634Y1830028D01*
G01X12416Y1833447D02*
X12634Y1833177D01*
G01X12416Y1836597D02*
X12634Y1836327D01*
G01X12057Y1827134D02*
X12287Y1826878D01*
G01X12057Y1830283D02*
X12287Y1830028D01*
G01X12057Y1833433D02*
X12287Y1833177D01*
G01X12057Y1836583D02*
X12287Y1836327D01*
G01X13701Y1826209D02*
X12287D01*
G01X13701Y1826878D02*
X12287D01*
G01X13701Y1829358D02*
X12287D01*
G01X13701Y1830028D02*
X12287D01*
G01X13701Y1832508D02*
X12287D01*
G01X13701Y1833177D02*
X12287D01*
G01X13701Y1835657D02*
X12287D01*
G01X13701Y1836327D02*
X12287D01*
G01X35827Y1800650D02*
X40551Y1805295D01*
G01X40547Y1804188D02*
X35827Y1799546D01*
G01Y1798917D02*
Y1800650D01*
G01X39236Y1796949D02*
X35827Y1798917D01*
G01X-20272Y1821392D02*
X-20607Y1821064D01*
G01X-16586Y1824673D02*
X-16921Y1824345D01*
G01X-19769Y1820736D02*
X-20104Y1820408D01*
G01X-16083Y1824017D02*
X-16418Y1823689D01*
G01X-20272Y1808925D02*
X-20607Y1808597D01*
G01X-16754Y1812206D02*
X-17256Y1811714D01*
G01X-19769Y1808269D02*
X-20104Y1807941D01*
G01X-16418Y1811386D02*
X-16754Y1811057D01*
G01X-20104Y1803020D02*
X-20607Y1802528D01*
G01Y1796458D02*
X-20942Y1796130D01*
G01X-20104Y1795802D02*
X-20272Y1795638D01*
G01X-16083Y1799411D02*
X-16418Y1799083D01*
G01X-19769Y1815651D02*
X-20439Y1815159D01*
G01X-16921Y1824345D02*
X-17424Y1824017D01*
G01X-16418Y1823689D02*
X-16921Y1823361D01*
G01X-19434Y1814994D02*
X-19937Y1814667D01*
G01X-19434Y1802363D02*
X-19937Y1802035D01*
G01X-17089Y1799246D02*
X-17591Y1798919D01*
G01X-14537Y1823974D02*
X-14677Y1823886D01*
G01X-13977Y1824181D02*
X-14449Y1823886D01*
G01X-14537Y1820824D02*
X-14677Y1820736D01*
G01X-13977Y1821031D02*
X-14449Y1820736D01*
G01X-14537Y1817674D02*
X-14677Y1817587D01*
G01X-13977Y1817882D02*
X-14449Y1817587D01*
G01X-14537Y1814525D02*
X-14677Y1814437D01*
G01X-13977Y1814732D02*
X-14449Y1814437D01*
G01X-14537Y1811375D02*
X-14677Y1811287D01*
G01X-13977Y1811583D02*
X-14449Y1811287D01*
G01X-14537Y1808226D02*
X-14677Y1808138D01*
G01X-13977Y1808433D02*
X-14449Y1808138D01*
G01X-14537Y1805076D02*
X-14677Y1804988D01*
G01X-13977Y1805283D02*
X-14449Y1804988D01*
G01X-14537Y1801926D02*
X-14677Y1801839D01*
G01X-13977Y1802134D02*
X-14449Y1801839D01*
G01X-14537Y1798777D02*
X-14677Y1798689D01*
G01X-13977Y1798984D02*
X-14449Y1798689D01*
G01X-14537Y1795627D02*
X-14677Y1795539D01*
G01X-13977Y1795835D02*
X-14449Y1795539D01*
G01X-14147Y1824181D02*
X-14537Y1823974D01*
G01X-14147Y1821031D02*
X-14537Y1820824D01*
G01X-14147Y1817882D02*
X-14537Y1817674D01*
G01X-14147Y1814732D02*
X-14537Y1814525D01*
G01X-14147Y1811583D02*
X-14537Y1811375D01*
G01X-14147Y1808433D02*
X-14537Y1808226D01*
G01X-14147Y1805283D02*
X-14537Y1805076D01*
G01X-14147Y1802134D02*
X-14537Y1801926D01*
G01X-14147Y1798984D02*
X-14537Y1798777D01*
G01X-14147Y1795835D02*
X-14537Y1795627D01*
G01X-17256Y1811714D02*
X-17591Y1811550D01*
G01X-16754Y1811057D02*
X-17424Y1810730D01*
G01X-19937Y1809089D02*
X-20272Y1808925D01*
G01X-19769Y1803183D02*
X-20104Y1803020D01*
G01X-16418Y1799083D02*
X-16754Y1798919D01*
G01X-19769Y1795966D02*
X-20104Y1795802D01*
G01X-19769Y1796786D02*
X-20607Y1796458D01*
G01X-19769Y1821556D02*
X-20272Y1821392D01*
G01X-17591Y1811550D02*
X-18094Y1811386D01*
G01X-18931Y1802528D02*
X-19434Y1802363D01*
G01X-20104Y1820408D02*
X-20272Y1820080D01*
G01X-15916Y1824345D02*
X-16083Y1824017D01*
G01X-20104Y1807941D02*
X-20272Y1807613D01*
G01X-16586Y1812534D02*
X-16754Y1812206D01*
G01X-19937Y1802035D02*
X-20272Y1801379D01*
G01Y1795638D02*
X-20439Y1795309D01*
G01X-15916Y1799739D02*
X-16083Y1799411D01*
G01X-20439Y1815159D02*
X-20942Y1814339D01*
G01X-20607Y1821064D02*
X-20942Y1820572D01*
G01X-19937Y1814667D02*
X-20272Y1814174D01*
G01X-20607Y1808597D02*
X-20942Y1808105D01*
G01X-16083Y1811878D02*
X-16418Y1811386D01*
G01X-20607Y1802528D02*
X-20942Y1802035D01*
G01X-16754Y1799739D02*
X-17089Y1799246D01*
G01X-20942Y1820572D02*
X-21109Y1820080D01*
G01X-20942Y1808105D02*
X-21109Y1807613D01*
G01X-15916Y1812370D02*
X-16083Y1811878D01*
G01X-20942Y1796130D02*
X-21109Y1795638D01*
G01X-20272Y1820080D02*
X-20439Y1819424D01*
G01X-16418Y1825329D02*
X-16586Y1824673D01*
G01X-20272Y1807613D02*
X-20439Y1806957D01*
G01X-15748Y1825001D02*
X-15916Y1824345D01*
G01X-20942Y1802035D02*
X-21109Y1801379D01*
G01X-16418Y1813190D02*
X-16586Y1812534D01*
G01Y1800395D02*
X-16754Y1799739D01*
G01X-15748Y1800395D02*
X-15916Y1799739D01*
G01X-20942Y1814339D02*
X-21109Y1813354D01*
G01X-20272Y1814174D02*
X-20439Y1813190D01*
G01X-15748Y1813354D02*
X-15916Y1812370D01*
G01X-23622Y1805480D02*
Y1804660D01*
G01X-21109Y1826313D02*
Y1825001D01*
G01Y1820080D02*
Y1819424D01*
G01Y1817947D02*
Y1817127D01*
G01Y1807613D02*
Y1806957D01*
G01Y1801379D02*
Y1800395D01*
G01Y1798919D02*
Y1798098D01*
G01Y1795638D02*
Y1794981D01*
G01X-20801Y1823822D02*
Y1822966D01*
G01Y1817522D02*
Y1816667D01*
G01Y1820672D02*
Y1819816D01*
G01Y1814373D02*
Y1813517D01*
G01Y1808074D02*
Y1807218D01*
G01Y1811223D02*
Y1810367D01*
G01Y1804924D02*
Y1804068D01*
G01Y1798625D02*
Y1797769D01*
G01Y1801774D02*
Y1800919D01*
G01Y1795475D02*
Y1794619D01*
G01X-20439Y1795309D02*
Y1794817D01*
G01X-20272Y1801379D02*
Y1800395D01*
G01X-19469Y1823828D02*
Y1822960D01*
G01Y1817528D02*
Y1816661D01*
G01Y1820678D02*
Y1819810D01*
G01Y1814379D02*
Y1813511D01*
G01Y1808080D02*
Y1807212D01*
G01Y1811229D02*
Y1810361D01*
G01Y1804930D02*
Y1804062D01*
G01Y1798631D02*
Y1797763D01*
G01Y1801780D02*
Y1800913D01*
G01Y1795481D02*
Y1794613D01*
G01X-19099Y1814994D02*
Y1811550D01*
G01X-18435Y1823848D02*
Y1822939D01*
G01Y1817548D02*
Y1816640D01*
G01Y1820698D02*
Y1819790D01*
G01Y1814399D02*
Y1813491D01*
G01Y1808100D02*
Y1807191D01*
G01Y1811249D02*
Y1810341D01*
G01Y1804950D02*
Y1804042D01*
G01Y1798651D02*
Y1797743D01*
G01Y1801800D02*
Y1800892D01*
G01Y1795501D02*
Y1794593D01*
G01X-18429Y1815815D02*
Y1811386D01*
G01X-18174Y1823848D02*
Y1822939D01*
G01Y1817548D02*
Y1816640D01*
G01Y1820698D02*
Y1819790D01*
G01Y1814399D02*
Y1813491D01*
G01Y1808100D02*
Y1807191D01*
G01Y1811249D02*
Y1810341D01*
G01Y1804950D02*
Y1804042D01*
G01Y1798651D02*
Y1797743D01*
G01Y1801800D02*
Y1800892D01*
G01Y1795501D02*
Y1794593D01*
G01X-17424Y1815815D02*
Y1814994D01*
G01X-16586Y1801051D02*
Y1800395D01*
G01X-16213Y1823869D02*
Y1822918D01*
G01Y1817570D02*
Y1816619D01*
G01Y1820720D02*
Y1819768D01*
G01Y1814420D02*
Y1813469D01*
G01Y1808121D02*
Y1807170D01*
G01Y1811271D02*
Y1810319D01*
G01Y1804972D02*
Y1804020D01*
G01Y1798672D02*
Y1797721D01*
G01Y1801822D02*
Y1800870D01*
G01Y1795523D02*
Y1794571D01*
G01X-15985Y1823869D02*
Y1822918D01*
G01Y1817570D02*
Y1816619D01*
G01Y1820720D02*
Y1819768D01*
G01Y1814420D02*
Y1813469D01*
G01Y1808121D02*
Y1807170D01*
G01Y1811271D02*
Y1810319D01*
G01Y1804972D02*
Y1804020D01*
G01Y1798672D02*
Y1797721D01*
G01Y1801822D02*
Y1800870D01*
G01Y1795523D02*
Y1794571D01*
G01X-15748Y1826313D02*
Y1825001D01*
G01Y1817947D02*
Y1817127D01*
G01Y1821720D02*
Y1820900D01*
G01Y1809253D02*
Y1808433D01*
G01Y1805480D02*
Y1804660D01*
G01Y1801379D02*
Y1800395D01*
G01Y1796786D02*
Y1795966D01*
G01X-14537Y1823974D02*
Y1822814D01*
G01Y1817674D02*
Y1816515D01*
G01Y1820824D02*
Y1819664D01*
G01Y1814525D02*
Y1813365D01*
G01Y1808226D02*
Y1807066D01*
G01Y1811375D02*
Y1810215D01*
G01Y1805076D02*
Y1803916D01*
G01Y1798777D02*
Y1797617D01*
G01Y1801926D02*
Y1800767D01*
G01Y1795627D02*
Y1794467D01*
G01X-13068Y1798919D02*
Y1798098D01*
G01X-13009Y1824181D02*
Y1822606D01*
G01Y1817882D02*
Y1816307D01*
G01Y1821031D02*
Y1819457D01*
G01Y1814732D02*
Y1813157D01*
G01Y1808433D02*
Y1806858D01*
G01Y1811583D02*
Y1810008D01*
G01Y1805283D02*
Y1803709D01*
G01Y1798984D02*
Y1797409D01*
G01Y1802134D02*
Y1800559D01*
G01Y1795835D02*
Y1794260D01*
G01X315Y1824575D02*
Y1823984D01*
G01Y1822803D02*
Y1822213D01*
G01Y1818276D02*
Y1817685D01*
G01Y1821425D02*
Y1820835D01*
G01Y1819654D02*
Y1819063D01*
G01Y1815126D02*
Y1814535D01*
G01Y1813354D02*
Y1812764D01*
G01Y1816504D02*
Y1815913D01*
G01Y1808827D02*
Y1808236D01*
G01Y1811976D02*
Y1811386D01*
G01Y1810205D02*
Y1809614D01*
G01Y1805677D02*
Y1805087D01*
G01Y1803906D02*
Y1803315D01*
G01Y1807055D02*
Y1806465D01*
G01Y1799378D02*
Y1798787D01*
G01Y1802528D02*
Y1801937D01*
G01Y1800756D02*
Y1800165D01*
G01Y1796228D02*
Y1795638D01*
G01Y1794457D02*
Y1793866D01*
G01Y1797606D02*
Y1797016D01*
G01X512Y1824575D02*
Y1823984D01*
G01Y1822803D02*
Y1822213D01*
G01Y1818276D02*
Y1817685D01*
G01Y1821425D02*
Y1820835D01*
G01Y1819654D02*
Y1819063D01*
G01Y1815126D02*
Y1814535D01*
G01Y1813354D02*
Y1812764D01*
G01Y1816504D02*
Y1815913D01*
G01Y1808827D02*
Y1808236D01*
G01Y1811976D02*
Y1811386D01*
G01Y1810205D02*
Y1809614D01*
G01Y1805677D02*
Y1805087D01*
G01Y1803906D02*
Y1803315D01*
G01Y1807055D02*
Y1806465D01*
G01Y1799378D02*
Y1798787D01*
G01Y1802528D02*
Y1801937D01*
G01Y1800756D02*
Y1800165D01*
G01Y1796228D02*
Y1795638D01*
G01Y1794457D02*
Y1793866D01*
G01Y1797606D02*
Y1797016D01*
G01X709Y1823984D02*
Y1822803D01*
G01Y1817685D02*
Y1816504D01*
G01Y1820835D02*
Y1819654D01*
G01Y1814535D02*
Y1813354D01*
G01Y1808236D02*
Y1807055D01*
G01Y1811386D02*
Y1810205D01*
G01Y1805087D02*
Y1803906D01*
G01Y1798787D02*
Y1797606D01*
G01Y1801937D02*
Y1800756D01*
G01Y1795638D02*
Y1794457D01*
G01X1074Y1823984D02*
Y1822803D01*
G01Y1817685D02*
Y1816504D01*
G01Y1820835D02*
Y1819654D01*
G01Y1814535D02*
Y1813354D01*
G01Y1808236D02*
Y1807055D01*
G01Y1811386D02*
Y1810205D01*
G01Y1805087D02*
Y1803906D01*
G01Y1798787D02*
Y1797606D01*
G01Y1801937D02*
Y1800756D01*
G01Y1795638D02*
Y1794457D01*
G01X1184Y1823984D02*
Y1822803D01*
G01Y1817685D02*
Y1816504D01*
G01Y1820835D02*
Y1819654D01*
G01Y1814535D02*
Y1813354D01*
G01Y1808236D02*
Y1807055D01*
G01Y1811386D02*
Y1810205D01*
G01Y1805087D02*
Y1803906D01*
G01Y1798787D02*
Y1797606D01*
G01Y1801937D02*
Y1800756D01*
G01Y1795638D02*
Y1794457D01*
G01X9965Y1823984D02*
Y1822803D01*
G01Y1817685D02*
Y1816504D01*
G01Y1820835D02*
Y1819654D01*
G01Y1814535D02*
Y1813354D01*
G01Y1808236D02*
Y1807055D01*
G01Y1811386D02*
Y1810205D01*
G01Y1805087D02*
Y1803906D01*
G01Y1798787D02*
Y1797606D01*
G01Y1801937D02*
Y1800756D01*
G01Y1795638D02*
Y1794457D01*
G01X10075Y1823984D02*
Y1822803D01*
G01Y1817685D02*
Y1816504D01*
G01Y1820835D02*
Y1819654D01*
G01Y1814535D02*
Y1813354D01*
G01Y1808236D02*
Y1807055D01*
G01Y1811386D02*
Y1810205D01*
G01Y1805087D02*
Y1803906D01*
G01Y1798787D02*
Y1797606D01*
G01Y1801937D02*
Y1800756D01*
G01Y1795638D02*
Y1794457D01*
G01X-21109Y1813354D02*
X-20942Y1812370D01*
G01X-16586Y1814339D02*
X-16418Y1813190D01*
G01X-15916Y1814502D02*
X-15748Y1813354D01*
G01X-21109Y1800395D02*
X-20942Y1799739D01*
G01X-20272Y1800395D02*
X-20104Y1799739D01*
G01X-21109Y1806957D02*
X-20942Y1806300D01*
G01X-20439Y1806957D02*
X-20272Y1806300D01*
G01X-20439Y1813190D02*
X-20272Y1812534D01*
G01X-16754Y1801707D02*
X-16586Y1801051D01*
G01X-21109Y1819424D02*
X-20942Y1818768D01*
G01X-20439Y1819424D02*
X-20272Y1818768D01*
G01X-15916Y1802035D02*
X-15748Y1801379D01*
G01X-21109Y1825001D02*
X-20942Y1824345D01*
G01X-20439Y1825329D02*
X-20272Y1824673D01*
G01X-21109Y1794981D02*
X-20942Y1794489D01*
G01Y1812370D02*
X-20774Y1811878D01*
G01X-20439Y1794817D02*
X-20272Y1794489D01*
G01X-20942Y1799739D02*
X-20774Y1799411D01*
G01X-20272Y1812534D02*
X-20104Y1812206D01*
G01X-20942Y1824345D02*
X-20774Y1824017D01*
G01X-16251Y1815159D02*
X-15916Y1814502D01*
G01X-20104Y1799739D02*
X-19769Y1799246D01*
G01X-20942Y1806300D02*
X-20607Y1805808D01*
G01X-20272Y1806300D02*
X-19937Y1805808D01*
G01X-17089Y1802199D02*
X-16754Y1801707D01*
G01X-16251Y1802528D02*
X-15916Y1802035D01*
G01X-20774Y1811878D02*
X-20439Y1811386D01*
G01X-20942Y1818768D02*
X-20607Y1818276D01*
G01X-20272Y1818768D02*
X-19937Y1818276D01*
G01X-16921Y1814831D02*
X-16586Y1814339D01*
G01X-20942Y1794489D02*
X-20439Y1793997D01*
G01X-20272Y1794489D02*
X-20104Y1794325D01*
G01X-20774Y1799411D02*
X-20439Y1799083D01*
G01X-20607Y1805808D02*
X-20272Y1805480D01*
G01X-19937Y1805808D02*
X-19602Y1805480D01*
G01X-20439Y1811386D02*
X-20104Y1811057D01*
G01Y1812206D02*
X-19602Y1811714D01*
G01X-20607Y1818276D02*
X-20272Y1817947D01*
G01X-19937Y1818276D02*
X-19602Y1817947D01*
G01X-16754Y1815651D02*
X-16251Y1815159D01*
G01X-20774Y1824017D02*
X-20439Y1823689D01*
G01X-20272Y1824673D02*
X-19937Y1824345D01*
G01X-17089Y1803183D02*
X-16251Y1802528D01*
G01X-19769Y1799246D02*
X-19267Y1798919D01*
G01X-14537Y1794467D02*
X-14147Y1794260D01*
G01X-14537Y1797617D02*
X-14147Y1797409D01*
G01X-14537Y1800767D02*
X-14147Y1800559D01*
G01X-14537Y1803916D02*
X-14147Y1803709D01*
G01X-14537Y1807066D02*
X-14147Y1806858D01*
G01X-14677Y1794555D02*
X-14537Y1794467D01*
G01X-14449Y1794555D02*
X-13977Y1794260D01*
G01X-14677Y1797705D02*
X-14537Y1797617D01*
G01X-14449Y1797705D02*
X-13977Y1797409D01*
G01X-14677Y1800854D02*
X-14537Y1800767D01*
G01X-14449Y1800854D02*
X-13977Y1800559D01*
G01X-14677Y1804004D02*
X-14537Y1803916D01*
G01X-14449Y1804004D02*
X-13977Y1803709D01*
G01X-14677Y1807154D02*
X-14537Y1807066D01*
G01X-14449Y1807154D02*
X-13977Y1806858D01*
G01X-14677Y1810303D02*
X-14537Y1810215D01*
G01X-14449Y1810303D02*
X-13977Y1810008D01*
G01X-14677Y1813453D02*
X-14537Y1813365D01*
G01X-14449Y1813453D02*
X-13977Y1813157D01*
G01X-14677Y1816602D02*
X-14537Y1816515D01*
G01X-14449Y1816602D02*
X-13977Y1816307D01*
G01X-14677Y1819752D02*
X-14537Y1819664D01*
G01X-14449Y1819752D02*
X-13977Y1819457D01*
G01X-14677Y1822902D02*
X-14537Y1822814D01*
G01X-14449Y1822902D02*
X-13977Y1822606D01*
G01X-20439Y1823689D02*
X-19937Y1823361D01*
G01Y1824345D02*
X-19434Y1824017D01*
G01X-20104Y1794325D02*
X-19769Y1794161D01*
G01X-20439Y1799083D02*
X-20104Y1798919D01*
G01X-17424Y1802363D02*
X-17089Y1802199D01*
G01X-20104Y1811057D02*
X-19434Y1810730D01*
G01X-19602Y1811714D02*
X-19267Y1811550D01*
G01X-14537Y1810215D02*
X-14147Y1810008D01*
G01X-14537Y1813365D02*
X-14147Y1813157D01*
G01X-14537Y1816515D02*
X-14147Y1816307D01*
G01X-14537Y1819664D02*
X-14147Y1819457D01*
G01X-14537Y1822814D02*
X-14147Y1822606D01*
G01X-17926Y1802528D02*
X-17424Y1802363D01*
G01Y1814994D02*
X-16921Y1814831D01*
G01X-19937Y1823361D02*
X-19434Y1823197D01*
G01X-17089Y1803183D02*
X-17759Y1803348D01*
G01X-16754Y1815651D02*
X-17424Y1815815D01*
G01X-18764Y1823033D02*
X-19434Y1823197D01*
G01X-18764Y1823853D02*
X-19434Y1824017D01*
G01X-18429Y1810565D02*
X-19434Y1810730D01*
G01X-19469Y1795487D02*
X-18174Y1795501D01*
G01X-18435D02*
X-20801Y1795475D01*
G01X-18174Y1795501D02*
X-17126Y1795513D01*
G01X-19469Y1798637D02*
X-18174Y1798651D01*
G01X-18435D02*
X-20801Y1798625D01*
G01X-18174Y1798651D02*
X-17126Y1798662D01*
G01X-19469Y1801786D02*
X-18174Y1801800D01*
G01X-18435D02*
X-20801Y1801774D01*
G01X-18174Y1801800D02*
X-17126Y1801812D01*
G01X-19469Y1804936D02*
X-18174Y1804950D01*
G01X-18435D02*
X-20801Y1804924D01*
G01X-18174Y1804950D02*
X-17126Y1804961D01*
G01X-19469Y1808085D02*
X-18174Y1808100D01*
G01X-18435D02*
X-20801Y1808074D01*
G01X-18174Y1808100D02*
X-17126Y1808111D01*
G01X-19469Y1811235D02*
X-18174Y1811249D01*
G01X-18435D02*
X-20801Y1811223D01*
G01X-18174Y1811249D02*
X-17126Y1811261D01*
G01X-19469Y1814385D02*
X-18174Y1814399D01*
G01X-18435D02*
X-20801Y1814373D01*
G01X-18174Y1814399D02*
X-17126Y1814410D01*
G01X-19469Y1817534D02*
X-18174Y1817548D01*
G01X-18435D02*
X-20801Y1817522D01*
G01X-18174Y1817548D02*
X-17126Y1817560D01*
G01X-19469Y1820684D02*
X-18174Y1820698D01*
G01X-18435D02*
X-20801Y1820672D01*
G01X-18174Y1820698D02*
X-17126Y1820709D01*
G01X-19469Y1823833D02*
X-18174Y1823848D01*
G01X-18435D02*
X-20801Y1823822D01*
G01X-18174Y1823848D02*
X-17126Y1823859D01*
G01X-15985Y1795523D02*
X-14449Y1795539D01*
G01X-14677D02*
X-18174Y1795501D01*
G01X-14677Y1795539D02*
X-16213Y1795523D01*
G01X-15985Y1798672D02*
X-14449Y1798689D01*
G01X-14677D02*
X-18174Y1798651D01*
G01X-14677Y1798689D02*
X-16213Y1798672D01*
G01X-15985Y1801822D02*
X-14449Y1801839D01*
G01X-14677D02*
X-18174Y1801800D01*
G01X-14677Y1801839D02*
X-16213Y1801822D01*
G01X-15985Y1804972D02*
X-14449Y1804988D01*
G01X-14677D02*
X-18174Y1804950D01*
G01X-14677Y1804988D02*
X-16213Y1804972D01*
G01X-15985Y1808121D02*
X-14449Y1808138D01*
G01X-14677D02*
X-18174Y1808100D01*
G01X-14677Y1808138D02*
X-16213Y1808121D01*
G01X-15985Y1811271D02*
X-14449Y1811287D01*
G01X-14677D02*
X-18174Y1811249D01*
G01X-14677Y1811287D02*
X-16213Y1811271D01*
G01X-15985Y1814420D02*
X-14449Y1814437D01*
G01X-14677D02*
X-18174Y1814399D01*
G01X-14677Y1814437D02*
X-16213Y1814420D01*
G01X-15985Y1817570D02*
X-14449Y1817587D01*
G01X-14677D02*
X-18174Y1817548D01*
G01X-14677Y1817587D02*
X-16213Y1817570D01*
G01X-15985Y1820720D02*
X-14449Y1820736D01*
G01X-14677D02*
X-18174Y1820698D01*
G01X-14677Y1820736D02*
X-16213Y1820720D01*
G01X-15985Y1823869D02*
X-14449Y1823886D01*
G01X-14677D02*
X-18174Y1823848D01*
G01X-14677Y1823886D02*
X-16213Y1823869D01*
G01X-19469Y1795487D02*
X-20801Y1795475D01*
G01X-19469Y1798637D02*
X-20801Y1798625D01*
G01X-19469Y1801786D02*
X-20801Y1801774D01*
G01X-19469Y1804936D02*
X-20801Y1804924D01*
G01X-19469Y1808085D02*
X-20801Y1808074D01*
G01X-19469Y1811235D02*
X-20801Y1811223D01*
G01X-19469Y1814385D02*
X-20801Y1814373D01*
G01X-19469Y1817534D02*
X-20801Y1817522D01*
G01X-19469Y1820684D02*
X-20801Y1820672D01*
G01X-19469Y1823833D02*
X-20801Y1823822D01*
G01X-15985Y1795523D02*
X-17126Y1795513D01*
G01D02*
X-18435Y1795501D01*
G01X-15985Y1798672D02*
X-17126Y1798662D01*
G01D02*
X-18435Y1798651D01*
G01X-15985Y1801822D02*
X-17126Y1801812D01*
G01D02*
X-18435Y1801800D01*
G01X-15985Y1804972D02*
X-17126Y1804961D01*
G01D02*
X-18435Y1804950D01*
G01X-15985Y1808121D02*
X-17126Y1808111D01*
G01D02*
X-18435Y1808100D01*
G01X-15985Y1811271D02*
X-17126Y1811261D01*
G01D02*
X-18435Y1811249D01*
G01X-15985Y1814420D02*
X-17126Y1814410D01*
G01D02*
X-18435Y1814399D01*
G01X-15985Y1817570D02*
X-17126Y1817560D01*
G01D02*
X-18435Y1817548D01*
G01X-15985Y1820720D02*
X-17126Y1820709D01*
G01D02*
X-18435Y1820698D01*
G01X-15985Y1823869D02*
X-17126Y1823859D01*
G01D02*
X-18435Y1823848D01*
G01X512Y1793866D02*
X0D01*
G01X-15748Y1794161D02*
X-19769D01*
G01X-13009Y1794260D02*
X-14147D01*
G01X12410Y1794457D02*
X315D01*
G01X-14449Y1794555D02*
X-14677D01*
G01X-15985Y1794571D02*
X-16213D01*
G01X-18174Y1794593D02*
X-18435D01*
G01X-18174Y1795501D02*
X-18435D01*
G01X-15985Y1795523D02*
X-16213D01*
G01X-14449Y1795539D02*
X-14677D01*
G01X12410Y1795638D02*
X315D01*
G01X-13009Y1795835D02*
X-14147D01*
G01X-15748Y1795966D02*
X-19769D01*
G01X512Y1796228D02*
X0D01*
G01X-15748Y1796786D02*
X-19769D01*
G01X512Y1797016D02*
X0D01*
G01X-13009Y1797409D02*
X-14147D01*
G01X12410Y1797606D02*
X315D01*
G01X-14449Y1797705D02*
X-14677D01*
G01X-15985Y1797721D02*
X-16213D01*
G01X-18174Y1797743D02*
X-18435D01*
G01X-13068Y1798098D02*
X-21109D01*
G01X-18174Y1798651D02*
X-18435D01*
G01X-15985Y1798672D02*
X-16213D01*
G01X-14449Y1798689D02*
X-14677D01*
G01X12410Y1798787D02*
X315D01*
G01X-13068Y1798919D02*
X-16754D01*
G01X-17591D02*
X-19267D01*
G01X-20104D02*
X-21109D01*
G01X-13009Y1798984D02*
X-14147D01*
G01X512Y1799378D02*
X0D01*
G01X512Y1800165D02*
X0D01*
G01X-13009Y1800559D02*
X-14147D01*
G01X12410Y1800756D02*
X315D01*
G01X-14449Y1800854D02*
X-14677D01*
G01X-15985Y1800870D02*
X-16213D01*
G01X-18174Y1800892D02*
X-18435D01*
G01X-18174Y1801800D02*
X-18435D01*
G01X-15985Y1801822D02*
X-16213D01*
G01X-14449Y1801839D02*
X-14677D01*
G01X12410Y1801937D02*
X315D01*
G01X-13009Y1802134D02*
X-14147D01*
G01X512Y1802528D02*
X0D01*
G01X-17926D02*
X-18931D01*
G01X512Y1803315D02*
X0D01*
G01X-17759Y1803348D02*
X-19099D01*
G01X-13009Y1803709D02*
X-14147D01*
G01X12410Y1803906D02*
X315D01*
G01X-14449Y1804004D02*
X-14677D01*
G01X-15985Y1804020D02*
X-16213D01*
G01X-18174Y1804042D02*
X-18435D01*
G01X-15748Y1804660D02*
X-23622D01*
G01X-18174Y1804950D02*
X-18435D01*
G01X-15985Y1804972D02*
X-16213D01*
G01X-14449Y1804988D02*
X-14677D01*
G01X12410Y1805087D02*
X315D01*
G01X-13009Y1805283D02*
X-14147D01*
G01X-15748Y1805480D02*
X-19602D01*
G01X-20272D02*
X-23622D01*
G01X512Y1805677D02*
X0D01*
G01X512Y1806465D02*
X0D01*
G01X-13009Y1806858D02*
X-14147D01*
G01X12410Y1807055D02*
X315D01*
G01X-14449Y1807154D02*
X-14677D01*
G01X-15985Y1807170D02*
X-16213D01*
G01X-18174Y1807191D02*
X-18435D01*
G01X-18174Y1808100D02*
X-18435D01*
G01X-15985Y1808121D02*
X-16213D01*
G01X-14449Y1808138D02*
X-14677D01*
G01X12410Y1808236D02*
X315D01*
G01X-13009Y1808433D02*
X-14147D01*
G01X-15748D02*
X-19099D01*
G01X512Y1808827D02*
X0D01*
G01X-15748Y1809253D02*
X-19099D01*
G01X512Y1809614D02*
X0D01*
G01X-13009Y1810008D02*
X-14147D01*
G01X12410Y1810205D02*
X315D01*
G01X-14449Y1810303D02*
X-14677D01*
G01X-15985Y1810319D02*
X-16213D01*
G01X-18174Y1810341D02*
X-18435D01*
G01X-18174Y1811249D02*
X-18435D01*
G01X-15985Y1811271D02*
X-16213D01*
G01X-14449Y1811287D02*
X-14677D01*
G01X12410Y1811386D02*
X315D01*
G01X-18094D02*
X-18429D01*
G01X-19099Y1811550D02*
X-19267D01*
G01X-13009Y1811583D02*
X-14147D01*
G01X512Y1811976D02*
X0D01*
G01X512Y1812764D02*
X0D01*
G01X-13009Y1813157D02*
X-14147D01*
G01X12410Y1813354D02*
X315D01*
G01X-14449Y1813453D02*
X-14677D01*
G01X-15985Y1813469D02*
X-16213D01*
G01X-18174Y1813491D02*
X-18435D01*
G01X-18174Y1814399D02*
X-18435D01*
G01X-15985Y1814420D02*
X-16213D01*
G01X-14449Y1814437D02*
X-14677D01*
G01X12410Y1814535D02*
X315D01*
G01X-13009Y1814732D02*
X-14147D01*
G01X-19099Y1814994D02*
X-19434D01*
G01X512Y1815126D02*
X0D01*
G01X-18429Y1815815D02*
X-19099D01*
G01X512Y1815913D02*
X0D01*
G01X-13009Y1816307D02*
X-14147D01*
G01X12410Y1816504D02*
X315D01*
G01X-14449Y1816602D02*
X-14677D01*
G01X-15985Y1816619D02*
X-16213D01*
G01X-18174Y1816640D02*
X-18435D01*
G01X-15748Y1817127D02*
X-21109D01*
G01X-18174Y1817548D02*
X-18435D01*
G01X-15985Y1817570D02*
X-16213D01*
G01X-14449Y1817587D02*
X-14677D01*
G01X12410Y1817685D02*
X315D01*
G01X-13009Y1817882D02*
X-14147D01*
G01X-15748Y1817947D02*
X-19602D01*
G01X-20272D02*
X-21109D01*
G01X512Y1818276D02*
X0D01*
G01X512Y1819063D02*
X0D01*
G01X-13009Y1819457D02*
X-14147D01*
G01X12410Y1819654D02*
X315D01*
G01X-14449Y1819752D02*
X-14677D01*
G01X-15985Y1819768D02*
X-16213D01*
G01X-18174Y1819790D02*
X-18435D01*
G01X-18174Y1820698D02*
X-18435D01*
G01X-15985Y1820720D02*
X-16213D01*
G01X-14449Y1820736D02*
X-14677D01*
G01X12410Y1820835D02*
X315D01*
G01X-15748Y1820900D02*
X-18931D01*
G01X-13009Y1821031D02*
X-14147D01*
G01X512Y1821425D02*
X0D01*
G01X-15748Y1821720D02*
X-18931D01*
G01X512Y1822213D02*
X0D01*
G01X-13009Y1822606D02*
X-14147D01*
G01X12410Y1822803D02*
X315D01*
G01X-14449Y1822902D02*
X-14677D01*
G01X-15985Y1822918D02*
X-16213D01*
G01X-18174Y1822939D02*
X-18435D01*
G01X-18094Y1823033D02*
X-18764D01*
G01X-18174Y1823848D02*
X-18435D01*
G01X-18094Y1823853D02*
X-18764D01*
G01X-15985Y1823869D02*
X-16213D01*
G01X-14449Y1823886D02*
X-14677D01*
G01X12410Y1823984D02*
X315D01*
G01X-13009Y1824181D02*
X-14147D01*
G01X512Y1824575D02*
X0D01*
G01X-19469Y1794607D02*
X-20801Y1794619D01*
G01X-15985Y1794571D02*
X-18435Y1794593D01*
G01X-19469Y1797757D02*
X-20801Y1797769D01*
G01X-15985Y1797721D02*
X-18435Y1797743D01*
G01X-19469Y1800907D02*
X-20801Y1800919D01*
G01X-15985Y1800870D02*
X-18435Y1800892D01*
G01X-19469Y1804056D02*
X-20801Y1804068D01*
G01X-15985Y1804020D02*
X-18435Y1804042D01*
G01X-19469Y1807206D02*
X-20801Y1807218D01*
G01X-15985Y1807170D02*
X-18435Y1807191D01*
G01X-19469Y1810356D02*
X-20801Y1810367D01*
G01X-15985Y1810319D02*
X-18435Y1810341D01*
G01X-19469Y1813505D02*
X-20801Y1813517D01*
G01X-15985Y1813469D02*
X-18435Y1813491D01*
G01X-19469Y1816655D02*
X-20801Y1816667D01*
G01X-15985Y1816619D02*
X-18435Y1816640D01*
G01X-19469Y1819804D02*
X-20801Y1819816D01*
G01X-15985Y1819768D02*
X-18435Y1819790D01*
G01X-19469Y1822954D02*
X-20801Y1822966D01*
G01X-15985Y1822918D02*
X-18435Y1822939D01*
G01X-15985Y1794571D02*
X-14449Y1794555D01*
G01X-15985Y1797721D02*
X-14449Y1797705D01*
G01X-15985Y1800870D02*
X-14449Y1800854D01*
G01X-15985Y1804020D02*
X-14449Y1804004D01*
G01X-15985Y1807170D02*
X-14449Y1807154D01*
G01X-15985Y1810319D02*
X-14449Y1810303D01*
G01X-15985Y1813469D02*
X-14449Y1813453D01*
G01X-15985Y1816619D02*
X-14449Y1816602D01*
G01X-15985Y1819768D02*
X-14449Y1819752D01*
G01X-15985Y1822918D02*
X-14449Y1822902D01*
G01X-18435Y1794593D02*
X-20801Y1794619D01*
G01X-18435Y1797743D02*
X-20801Y1797769D01*
G01X-18435Y1800892D02*
X-20801Y1800919D01*
G01X-18435Y1804042D02*
X-20801Y1804068D01*
G01X-18435Y1807191D02*
X-20801Y1807218D01*
G01X-18435Y1810341D02*
X-20801Y1810367D01*
G01X-18435Y1813491D02*
X-20801Y1813517D01*
G01X-18435Y1816640D02*
X-20801Y1816667D01*
G01X-18435Y1819790D02*
X-20801Y1819816D01*
G01X-18435Y1822939D02*
X-20801Y1822966D01*
G01X-19469Y1794607D02*
X-16213Y1794571D01*
G01X-18174Y1794593D02*
X-14677Y1794555D01*
G01X-19469Y1797757D02*
X-16213Y1797721D01*
G01X-18174Y1797743D02*
X-14677Y1797705D01*
G01X-19469Y1800907D02*
X-16213Y1800870D01*
G01X-18174Y1800892D02*
X-14677Y1800854D01*
G01X-19469Y1804056D02*
X-16213Y1804020D01*
G01X-18174Y1804042D02*
X-14677Y1804004D01*
G01X-19469Y1807206D02*
X-16213Y1807170D01*
G01X-18174Y1807191D02*
X-14677Y1807154D01*
G01X-19469Y1810356D02*
X-16213Y1810319D01*
G01X-18174Y1810341D02*
X-14677Y1810303D01*
G01X-19469Y1813505D02*
X-16213Y1813469D01*
G01X-18174Y1813491D02*
X-14677Y1813453D01*
G01X-19469Y1816655D02*
X-16213Y1816619D01*
G01X-18174Y1816640D02*
X-14677Y1816602D01*
G01X-19469Y1819804D02*
X-16213Y1819768D01*
G01X-18174Y1819790D02*
X-14677Y1819752D01*
G01X-19469Y1822954D02*
X-16213Y1822918D01*
G01X-18174Y1822939D02*
X-14677Y1822902D01*
G01X-19099Y1803348D02*
X-19769Y1803183D01*
G01X-19099Y1808433D02*
X-19769Y1808269D01*
G01X-19099Y1815815D02*
X-19769Y1815651D01*
G01X-19099Y1809253D02*
X-19937Y1809089D01*
G01X-18931Y1820900D02*
X-19769Y1820736D01*
G01X-18931Y1821720D02*
X-19769Y1821556D01*
G01X-17424Y1810730D02*
X-18429Y1810565D01*
G01X-16921Y1823361D02*
X-18094Y1823033D01*
G01X-17424Y1824017D02*
X-18094Y1823853D01*
G01X-9055Y1876543D02*
Y1855677D01*
G01X22441Y1847016D02*
X3937D01*
G01X11893Y1858434D02*
X-9055Y1858039D01*
G01X11817Y1858433D02*
X-9055Y1858039D01*
G01X16142Y1862764D02*
G03I-4331J0D01*
G01X11827Y1867094D02*
G03Y1858433I-16J-4331D01*
G01X-19937Y1827954D02*
X-20439Y1827626D01*
G01X-19434Y1827298D02*
X-19937Y1826970D01*
G01X-14537Y1836572D02*
X-14677Y1836484D01*
G01X-13977Y1836780D02*
X-14449Y1836484D01*
G01X-14537Y1833422D02*
X-14677Y1833335D01*
G01X-13977Y1833630D02*
X-14449Y1833335D01*
G01X-14537Y1830273D02*
X-14677Y1830185D01*
G01X-13977Y1830480D02*
X-14449Y1830185D01*
G01X-14147Y1836780D02*
X-14537Y1836572D01*
G01X-14147Y1833630D02*
X-14537Y1833422D01*
G01X3937Y1847016D02*
X0Y1843079D01*
G01X-20439Y1827626D02*
X-20774Y1827298D01*
G01X-19937Y1826970D02*
X-20272Y1826642D01*
G01X-14537Y1827123D02*
X-14677Y1827035D01*
G01X-13977Y1827331D02*
X-14449Y1827035D01*
G01X-14147Y1830480D02*
X-14537Y1830273D01*
G01X-14147Y1827331D02*
X-14537Y1827123D01*
G01X-19434Y1828118D02*
X-19937Y1827954D01*
G01X-20774Y1827298D02*
X-20942Y1826970D01*
G01D02*
X-21109Y1826313D01*
G01X-20272Y1826642D02*
X-20439Y1825985D01*
G01X-30709Y1847016D02*
Y1841898D01*
G01X-23622Y1830415D02*
Y1829594D01*
G01X-20801Y1836420D02*
Y1835564D01*
G01Y1833270D02*
Y1832415D01*
G01Y1826971D02*
Y1826115D01*
G01Y1830121D02*
Y1829265D01*
G01X-20439Y1825985D02*
Y1825329D01*
G01X-19469Y1836426D02*
Y1835558D01*
G01Y1833276D02*
Y1832409D01*
G01Y1826977D02*
Y1826109D01*
G01Y1830127D02*
Y1829259D01*
G01X-18435Y1836446D02*
Y1835538D01*
G01Y1833296D02*
Y1832388D01*
G01Y1826997D02*
Y1826089D01*
G01Y1830147D02*
Y1829239D01*
G01X-18174Y1836446D02*
Y1835538D01*
G01Y1833296D02*
Y1832388D01*
G01Y1826997D02*
Y1826089D01*
G01Y1830147D02*
Y1829239D01*
G01X-16418Y1825985D02*
Y1825329D01*
G01X-16213Y1836468D02*
Y1835516D01*
G01Y1833318D02*
Y1832367D01*
G01Y1827019D02*
Y1826067D01*
G01Y1830169D02*
Y1829217D01*
G01X-15985Y1836468D02*
Y1835516D01*
G01Y1833318D02*
Y1832367D01*
G01Y1827019D02*
Y1826067D01*
G01Y1830169D02*
Y1829217D01*
G01X-15748Y1830415D02*
Y1829594D01*
G01X-14537Y1836572D02*
Y1835412D01*
G01Y1833422D02*
Y1832263D01*
G01Y1827123D02*
Y1825963D01*
G01Y1830273D02*
Y1829113D01*
G01X-13009Y1836780D02*
Y1835205D01*
G01Y1833630D02*
Y1832055D01*
G01Y1827331D02*
Y1825756D01*
G01Y1830480D02*
Y1828906D01*
G01X315Y1837173D02*
Y1836583D01*
G01Y1834024D02*
Y1833433D01*
G01Y1832252D02*
Y1831661D01*
G01Y1835402D02*
Y1834811D01*
G01Y1827724D02*
Y1827134D01*
G01Y1830874D02*
Y1830283D01*
G01Y1829102D02*
Y1828512D01*
G01Y1825953D02*
Y1825362D01*
G01X512Y1837173D02*
Y1836583D01*
G01Y1834024D02*
Y1833433D01*
G01Y1832252D02*
Y1831661D01*
G01Y1835402D02*
Y1834811D01*
G01Y1827724D02*
Y1827134D01*
G01Y1830874D02*
Y1830283D01*
G01Y1829102D02*
Y1828512D01*
G01Y1825953D02*
Y1825362D01*
G01X709Y1836583D02*
Y1835402D01*
G01Y1833433D02*
Y1832252D01*
G01Y1827134D02*
Y1825953D01*
G01Y1830283D02*
Y1829102D01*
G01X1074Y1836583D02*
Y1835402D01*
G01Y1833433D02*
Y1832252D01*
G01Y1827134D02*
Y1825953D01*
G01Y1830283D02*
Y1829102D01*
G01X1184Y1836583D02*
Y1835402D01*
G01Y1833433D02*
Y1832252D01*
G01Y1827134D02*
Y1825953D01*
G01Y1830283D02*
Y1829102D01*
G01X9965Y1836583D02*
Y1835402D01*
G01Y1833433D02*
Y1832252D01*
G01Y1827134D02*
Y1825953D01*
G01Y1830283D02*
Y1829102D01*
G01X10075Y1836583D02*
Y1835402D01*
G01Y1833433D02*
Y1832252D01*
G01Y1827134D02*
Y1825953D01*
G01Y1830283D02*
Y1829102D01*
G01X-16586Y1826642D02*
X-16418Y1825985D01*
G01X-15916Y1826970D02*
X-15748Y1826313D01*
G01X-16083Y1827298D02*
X-15916Y1826970D01*
G01X-16921D02*
X-16586Y1826642D01*
G01X-16418Y1827626D02*
X-16083Y1827298D01*
G01X-14677Y1826051D02*
X-14537Y1825963D01*
G01X-14449Y1826051D02*
X-13977Y1825756D01*
G01X-14677Y1829201D02*
X-14537Y1829113D01*
G01X-14449Y1829201D02*
X-13977Y1828906D01*
G01X-14677Y1832350D02*
X-14537Y1832263D01*
G01X-14449Y1832350D02*
X-13977Y1832055D01*
G01X-14677Y1835500D02*
X-14537Y1835412D01*
G01X-14449Y1835500D02*
X-13977Y1835205D01*
G01X-17424Y1827298D02*
X-16921Y1826970D01*
G01Y1827954D02*
X-16418Y1827626D01*
G01X-30709Y1841898D02*
X-26772Y1839929D01*
G01X-14537Y1825963D02*
X-14147Y1825756D01*
G01X-14537Y1829113D02*
X-14147Y1828906D01*
G01X-14537Y1832263D02*
X-14147Y1832055D01*
G01X-14537Y1835412D02*
X-14147Y1835205D01*
G01X-17424Y1827298D02*
X-18094Y1827462D01*
G01X-16921Y1827954D02*
X-18094Y1828282D01*
G01X-19469Y1826983D02*
X-18174Y1826997D01*
G01X-18435D02*
X-20801Y1826971D01*
G01X-18174Y1826997D02*
X-17126Y1827009D01*
G01X-19469Y1830133D02*
X-18174Y1830147D01*
G01X-18435D02*
X-20801Y1830121D01*
G01X-18174Y1830147D02*
X-17126Y1830158D01*
G01X-19469Y1833282D02*
X-18174Y1833296D01*
G01X-18435D02*
X-20801Y1833270D01*
G01X-18174Y1833296D02*
X-17126Y1833308D01*
G01X-19469Y1836432D02*
X-18174Y1836446D01*
G01X-18435D02*
X-20801Y1836420D01*
G01X-18174Y1836446D02*
X-17126Y1836457D01*
G01X-15985Y1827019D02*
X-14449Y1827035D01*
G01X-14677D02*
X-18174Y1826997D01*
G01X-14677Y1827035D02*
X-16213Y1827019D01*
G01X-15985Y1830169D02*
X-14449Y1830185D01*
G01X-14677D02*
X-18174Y1830147D01*
G01X-14677Y1830185D02*
X-16213Y1830169D01*
G01X-15985Y1833318D02*
X-14449Y1833335D01*
G01X-14677D02*
X-18174Y1833296D01*
G01X-14677Y1833335D02*
X-16213Y1833318D01*
G01X-15985Y1836468D02*
X-14449Y1836484D01*
G01X-14677D02*
X-18174Y1836446D01*
G01X-14677Y1836484D02*
X-16213Y1836468D01*
G01X-19469Y1826983D02*
X-20801Y1826971D01*
G01X-19469Y1830133D02*
X-20801Y1830121D01*
G01X-19469Y1833282D02*
X-20801Y1833270D01*
G01X-19469Y1836432D02*
X-20801Y1836420D01*
G01X-15985Y1827019D02*
X-17126Y1827009D01*
G01D02*
X-18435Y1826997D01*
G01X-15985Y1830169D02*
X-17126Y1830158D01*
G01D02*
X-18435Y1830147D01*
G01X-15985Y1833318D02*
X-17126Y1833308D01*
G01D02*
X-18435Y1833296D01*
G01X-15985Y1836468D02*
X-17126Y1836457D01*
G01D02*
X-18435Y1836446D01*
G01X512Y1825362D02*
X0D01*
G01X-13009Y1825756D02*
X-14147D01*
G01X12410Y1825953D02*
X315D01*
G01X-14449Y1826051D02*
X-14677D01*
G01X-15985Y1826067D02*
X-16213D01*
G01X-18174Y1826089D02*
X-18435D01*
G01X-18174Y1826997D02*
X-18435D01*
G01X-15985Y1827019D02*
X-16213D01*
G01X-14449Y1827035D02*
X-14677D01*
G01X12410Y1827134D02*
X315D01*
G01X-13009Y1827331D02*
X-14147D01*
G01X-18094Y1827462D02*
X-18764D01*
G01X512Y1827724D02*
X0D01*
G01X-18094Y1828282D02*
X-18764D01*
G01X512Y1828512D02*
X0D01*
G01X-13009Y1828906D02*
X-14147D01*
G01X12410Y1829102D02*
X315D01*
G01X-14449Y1829201D02*
X-14677D01*
G01X-15985Y1829217D02*
X-16213D01*
G01X-18174Y1829239D02*
X-18435D01*
G01X-15748Y1829594D02*
X-23622D01*
G01X-18174Y1830147D02*
X-18435D01*
G01X-15985Y1830169D02*
X-16213D01*
G01X-14449Y1830185D02*
X-14677D01*
G01X12410Y1830283D02*
X315D01*
G01X-15748Y1830415D02*
X-23622D01*
G01X-13009Y1830480D02*
X-14147D01*
G01X512Y1830874D02*
X0D01*
G01X512Y1831661D02*
X0D01*
G01X-13009Y1832055D02*
X-14147D01*
G01X12410Y1832252D02*
X315D01*
G01X-14449Y1832350D02*
X-14677D01*
G01X-15985Y1832367D02*
X-16213D01*
G01X-18174Y1832388D02*
X-18435D01*
G01X-18174Y1833296D02*
X-18435D01*
G01X-15985Y1833318D02*
X-16213D01*
G01X-14449Y1833335D02*
X-14677D01*
G01X12410Y1833433D02*
X315D01*
G01X-13009Y1833630D02*
X-14147D01*
G01X512Y1834024D02*
X0D01*
G01X512Y1834811D02*
X0D01*
G01X-13009Y1835205D02*
X-14147D01*
G01X12410Y1835402D02*
X315D01*
G01X-14449Y1835500D02*
X-14677D01*
G01X-15985Y1835516D02*
X-16213D01*
G01X-18174Y1835538D02*
X-18435D01*
G01X-18174Y1836446D02*
X-18435D01*
G01X-15985Y1836468D02*
X-16213D01*
G01X-14449Y1836484D02*
X-14677D01*
G01X12410Y1836583D02*
X315D01*
G01X-13009Y1836780D02*
X-14147D01*
G01X512Y1837173D02*
X0D01*
G01X-7283Y1839929D02*
X-26772D01*
G01X-19469Y1826104D02*
X-20801Y1826115D01*
G01X-15985Y1826067D02*
X-18435Y1826089D01*
G01X-19469Y1829253D02*
X-20801Y1829265D01*
G01X-15985Y1829217D02*
X-18435Y1829239D01*
G01X-19469Y1832403D02*
X-20801Y1832415D01*
G01X-15985Y1832367D02*
X-18435Y1832388D01*
G01X-19469Y1835552D02*
X-20801Y1835564D01*
G01X-15985Y1835516D02*
X-18435Y1835538D01*
G01X-15985Y1826067D02*
X-14449Y1826051D01*
G01X-15985Y1829217D02*
X-14449Y1829201D01*
G01X-15985Y1832367D02*
X-14449Y1832350D01*
G01X-15985Y1835516D02*
X-14449Y1835500D01*
G01X-18435Y1826089D02*
X-20801Y1826115D01*
G01X-18435Y1829239D02*
X-20801Y1829265D01*
G01X-18435Y1832388D02*
X-20801Y1832415D01*
G01X-18435Y1835538D02*
X-20801Y1835564D01*
G01X-19469Y1826104D02*
X-16213Y1826067D01*
G01X-18174Y1826089D02*
X-14677Y1826051D01*
G01X-19469Y1829253D02*
X-16213Y1829217D01*
G01X-18174Y1829239D02*
X-14677Y1829201D01*
G01X-19469Y1832403D02*
X-16213Y1832367D01*
G01X-18174Y1832388D02*
X-14677Y1832350D01*
G01X-19469Y1835552D02*
X-16213Y1835516D01*
G01X-18174Y1835538D02*
X-14677Y1835500D01*
G01X-18764Y1827462D02*
X-19434Y1827298D01*
G01X-18764Y1828282D02*
X-19434Y1828118D01*
G01X31338Y1927849D02*
G03I-985J0D01*
G01X27663Y1931524D02*
G03I-984J0D01*
G01X32683Y1922830D02*
G03I-985J0D01*
G01X27564Y1918694D02*
G03X28689Y1915939I3937J1D01*
G01X27564Y1922830D02*
G03X15753I-5906J0D01*
G01X27564D02*
G03X15753I-5906J0D01*
G01X27958D02*
G03I-6299J0D01*
G01X29533D02*
G03X13785I-7874J0D01*
G01X35438D02*
G03X7879I-13780J0D01*
G01X37407D02*
G03X5911I-15748J0D01*
G01X37407D02*
G03X5911I-15748J0D01*
G01X37407D02*
G03X5911I-15748J0D01*
G01X14629Y1915939D02*
G03X28689I7030J-6889D01*
G01X5911Y1909050D02*
G03X37407I15748J0D01*
G01X5911D02*
G03X37407I15748J0D01*
G01X5911D02*
G03X37407I15748J0D01*
G01X17623Y1931524D02*
G03I-984J0D01*
G01X13949Y1927849D02*
G03I-984J0D01*
G01X12604Y1922830D02*
G03I-984J0D01*
G01X14629Y1915939D02*
G03X15753Y1918694I-2813J2754D01*
G01X27564Y1920468D02*
X35438D01*
G01X7879D02*
X15753D01*
G01X37407Y1909050D02*
Y1922830D01*
G01Y1909050D02*
Y1922830D01*
G01Y1909050D02*
Y1922830D01*
G01X35438Y1920468D02*
Y1922830D01*
G01X29533Y1920468D02*
Y1922830D01*
G01X27564Y1918694D02*
Y1922830D01*
G01D02*
Y1920468D01*
G01X15753D02*
Y1922830D01*
G01D02*
Y1918694D01*
G01X13785Y1922830D02*
Y1920468D01*
G01X7879Y1922830D02*
Y1920468D01*
G01X5911Y1909050D02*
Y1922830D01*
G01Y1909050D02*
Y1922830D01*
G01Y1909050D02*
Y1922830D01*
G01X22441Y1867094D02*
X11811D01*
G01X22441Y1876543D02*
X-9055D01*
G01Y1867488D02*
X11813Y1867095D01*
G01X11893Y1867094D02*
X-9055Y1867488D01*
G01X-7874Y1930791D02*
Y1900165D01*
G01X0Y1930791D02*
G03X-7874I-3937J0D01*
G01X29799Y1950500D02*
G03I-4299J0D01*
G01X0Y1992126D02*
Y2041371D01*
G01X-7874Y1961500D02*
G03X0I3937J0D01*
G01X-7874Y1992126D02*
Y1961500D01*
G01X64646Y11142D02*
X81024D01*
G01X75000Y15472D02*
X70669D01*
G01X75625Y16260D02*
X70044D01*
G01Y17835D02*
X75625D01*
G01X70669Y18622D02*
X75000D01*
G01X81024Y21319D02*
X64646D01*
G01X79783Y24961D02*
X84390D01*
G01X84041Y26142D02*
X84059Y26086D01*
X84111Y25920D01*
X84190Y25662D01*
X84285Y25334D01*
X84390Y24961D01*
G01X64646Y37539D02*
Y11142D01*
G01X66929Y24075D02*
Y32421D01*
G01X70044Y17835D02*
Y16260D01*
G01X70079D02*
Y17835D01*
G01X70103Y16260D02*
Y17835D01*
G01X71426D02*
Y16260D01*
G01X71796D02*
Y17835D01*
G01X73873D02*
Y16260D01*
G01X74243D02*
Y17835D01*
G01X75567D02*
Y16260D01*
G01X75591Y17835D02*
Y16260D01*
G01X75625D02*
Y17835D01*
G01X81024Y24075D02*
Y11142D01*
G01X94488Y24075D02*
Y37953D01*
G01X79783Y24961D02*
X79886Y25330D01*
X79982Y25659D01*
X80063Y25921D01*
X80115Y26087D01*
X80132Y26142D01*
G01X70669Y18622D02*
G03Y15472I0J-1575D01*
G01X77278Y25685D02*
G03X80324Y25687I1521J2363D01*
G01X75000Y15472D02*
G03Y18622I0J1575D01*
G01X84390Y24961D02*
G03Y32756I-2304J3897D01*
G01X79783D02*
G03Y24961I2304J-3898D01*
G01X85669Y25277D02*
G03X87254Y25563I264J3073D01*
G01X94488Y24075D02*
X40551D01*
G01Y25256D02*
X66929D01*
G01X40519Y24106D02*
X40462Y24246D01*
X40457Y24486D01*
G01X40551Y32421D02*
Y25256D01*
G01X40493Y24807D02*
X40457Y24483D01*
X40463Y24242D01*
X40519Y24106D01*
G01X40493Y24805D02*
X40547Y25182D01*
G01X85237Y45315D02*
X73228D01*
G01X85384D02*
X92717D01*
G01X81890Y45374D02*
X74724D01*
G01X81890Y46949D02*
X74724D01*
G01X77756Y47146D02*
X76772D01*
G01X77756Y47539D02*
X76772D01*
G01X52529Y46949D02*
X52956Y46358D01*
G01X51802Y47677D02*
X51829Y47681D01*
X51855Y47692D01*
X51879Y47710D01*
X51900Y47735D01*
X51917Y47765D01*
X51930Y47798D01*
X51938Y47835D01*
X51941Y47874D01*
G01X51839Y46949D02*
X52112Y46358D01*
G01D02*
Y45965D01*
G01X52956Y46358D02*
Y45965D01*
G01X75787Y46949D02*
Y45374D01*
G01X78740Y46949D02*
Y45374D01*
G01X81890D02*
Y46949D01*
G01X84298Y45315D02*
Y47677D01*
G01X51428Y47874D02*
X51417Y47776D01*
X51389Y47704D01*
X51351Y47677D01*
G01X52112Y45965D02*
X51839Y45374D01*
G01X52529D02*
X52956Y45965D01*
G01X74331Y47343D02*
G03X74724Y46949I393J-1D01*
G01X51351Y42165D02*
X51389Y42139D01*
X51417Y42067D01*
X51428Y41969D01*
G01X51351Y45315D02*
X51389Y45289D01*
X51417Y45217D01*
X51428Y45118D01*
G01X89662Y25476D02*
X88254D01*
G01X92747D02*
X91198D01*
G01X83082D02*
X81622D01*
G01X75823D02*
X74430D01*
G01X73000D02*
X71541D01*
G01X70110D02*
X68670D01*
G01X94488Y26043D02*
X70866D01*
G01X84041Y26142D02*
X80132D01*
G01X88097Y26632D02*
X86594D01*
G01X88228Y27076D02*
X85228D01*
G01X86655Y27902D02*
X85229D01*
G01X90044Y29483D02*
X88428D01*
G01X92721D02*
X91339D01*
G01X70113D02*
X68670D01*
G01X94488Y29823D02*
X70866D01*
G01X83082Y31230D02*
X81622D01*
G01X80132Y31575D02*
X84041D01*
G01X94488Y31791D02*
X70866D01*
G01X84390Y32756D02*
X79783D01*
G01X94488Y34193D02*
X70866D01*
G01X79328Y34724D02*
X73228D01*
G01X79328Y34783D02*
X73228D01*
G01X93696Y35177D02*
X73228D01*
G01X74331Y36358D02*
X64961D01*
G01X64646Y37539D02*
X71181D01*
G01X94488Y37953D02*
X74331D01*
G01Y38130D02*
X64961D01*
G01X77756Y39587D02*
X76772D01*
G01X87331Y39705D02*
X78346D01*
G01X77756Y39783D02*
X76772D01*
G01X77756Y40177D02*
X76772D01*
G01X74724Y40374D02*
X81890D01*
G01X92717Y41378D02*
X85384D01*
G01X85237D02*
X73228D01*
G01X74724Y41949D02*
X81890D01*
G01X77756Y42146D02*
X76772D01*
G01X85237Y42165D02*
X73228D01*
G01X85384D02*
X92717D01*
G01X77756Y42539D02*
X76772D01*
G01X77756Y42736D02*
X76772D01*
G01X92717Y44528D02*
X85384D01*
G01X85237D02*
X73228D01*
G01X77756Y44587D02*
X76772D01*
G01X77756Y44783D02*
X76772D01*
G01X77756Y45177D02*
X76772D01*
G01X52529Y41949D02*
X52956Y41358D01*
G01X51802Y41378D02*
X51829Y41381D01*
X51855Y41393D01*
X51879Y41411D01*
X51900Y41435D01*
X51917Y41465D01*
X51930Y41499D01*
X51938Y41536D01*
X51941Y41575D01*
G01X51802Y44528D02*
X51829Y44531D01*
X51855Y44542D01*
X51879Y44560D01*
X51900Y44585D01*
X51917Y44615D01*
X51930Y44649D01*
X51938Y44685D01*
X51941Y44724D01*
G01X88428Y29483D02*
X89697Y27623D01*
G01X90044Y29483D02*
X90650Y28497D01*
G01X91426Y27632D02*
X92747Y25476D01*
G01X90453Y26754D02*
X91198Y25476D01*
G01X51839Y41949D02*
X52112Y41358D01*
G01X80132Y31575D02*
X80114Y31631D01*
X80062Y31796D01*
X79983Y32055D01*
X79887Y32382D01*
X79783Y32756D01*
G01X51941Y41969D02*
X51938Y42007D01*
X51930Y42043D01*
X51917Y42077D01*
X51900Y42107D01*
X51879Y42132D01*
X51856Y42150D01*
X51830Y42161D01*
X51802Y42165D01*
G01X51941Y45118D02*
X51938Y45156D01*
X51930Y45193D01*
X51917Y45227D01*
X51900Y45257D01*
X51879Y45281D01*
X51856Y45300D01*
X51830Y45311D01*
X51802Y45315D01*
G01X51428Y45118D02*
Y44724D01*
G01Y41969D02*
Y41575D01*
G01X51941D02*
Y41969D01*
G01Y44724D02*
Y45118D01*
G01X52112Y41358D02*
Y40965D01*
G01X52956Y41358D02*
Y40965D01*
G01X53118Y41575D02*
Y41969D01*
G01Y44724D02*
Y45118D01*
G01X62992Y37343D02*
Y169980D01*
G01X64961Y38130D02*
Y36358D01*
G01X68670Y29483D02*
Y25476D01*
G01X69213Y55059D02*
Y37539D01*
G01X70110Y28001D02*
Y25476D01*
G01X70113Y29483D02*
Y28926D01*
G01X70866Y34193D02*
Y31791D01*
G01Y29823D02*
Y26043D01*
G01X71181Y169783D02*
Y37539D01*
G01X71541Y25476D02*
Y28001D01*
G01X73000D02*
Y25476D01*
G01X73228Y34724D02*
Y172598D01*
G01X74331Y172146D02*
Y35177D01*
G01X74430Y25476D02*
Y28001D01*
G01X75170Y45315D02*
Y44528D01*
G01Y42165D02*
Y41378D01*
G01X75197Y45315D02*
Y44528D01*
G01Y42165D02*
Y41378D01*
G01X75573Y45315D02*
Y44528D01*
G01Y42165D02*
Y41378D01*
G01X75787Y41949D02*
Y40374D01*
G01X75823Y28406D02*
Y25476D01*
G01X76772Y47736D02*
Y44587D01*
G01Y42736D02*
Y39587D01*
G01Y32421D02*
Y34724D01*
G01X77756Y47736D02*
Y44587D01*
G01Y42736D02*
Y39587D01*
G01X78346Y172146D02*
Y35177D01*
G01X78740Y41949D02*
Y40374D01*
G01X78801Y169567D02*
Y37953D01*
G01X78935Y41378D02*
Y42165D01*
G01Y44528D02*
Y45315D01*
G01X79328Y34724D02*
Y34783D01*
G01X79967Y35177D02*
Y32421D01*
G01X80919Y41378D02*
Y42165D01*
G01Y44528D02*
Y45315D01*
G01X81622Y25476D02*
Y31230D01*
G01X81890Y40374D02*
Y41949D01*
G01X82570Y45315D02*
Y44528D01*
G01Y42165D02*
Y41378D01*
G01X83082Y31230D02*
Y25476D01*
G01X84298Y39705D02*
Y41378D01*
G01Y42165D02*
Y44528D01*
G01X85237Y45315D02*
Y44528D01*
G01Y42165D02*
Y41378D01*
G01X85384Y45315D02*
Y44528D01*
G01Y42165D02*
Y41378D01*
G01X86976Y45315D02*
Y44528D01*
G01Y42165D02*
Y41378D01*
G01X87331Y35177D02*
Y172146D01*
G01X87841Y35177D02*
Y32421D01*
G01X87918Y41378D02*
Y42165D01*
G01Y44528D02*
Y45315D01*
G01X90754Y41378D02*
Y42165D01*
G01Y44528D02*
Y45315D01*
G01X90943D02*
Y44528D01*
G01Y42165D02*
Y41378D01*
G01X92717Y45315D02*
Y44528D01*
G01Y42165D02*
Y41378D01*
G01X93696Y35177D02*
Y37953D01*
G01X94170Y32421D02*
Y37953D01*
G01X51428Y44724D02*
X51417Y44626D01*
X51389Y44554D01*
X51351Y44528D01*
G01X51428Y41575D02*
X51417Y41476D01*
X51389Y41404D01*
X51351Y41378D01*
G01X84041Y31575D02*
X84059Y31630D01*
X84111Y31796D01*
X84190Y32054D01*
X84285Y32381D01*
X84390Y32756D01*
G01X52112Y40965D02*
X51839Y40374D01*
G01X90453Y26754D02*
X89662Y25476D01*
G01X79328Y34783D02*
X79583Y35177D01*
G01X89697Y27623D02*
X88254Y25476D01*
G01X91339Y29483D02*
X90650Y28497D01*
G01X92721Y29483D02*
X91426Y27632D01*
G01X52529Y40374D02*
X52956Y40965D01*
G01X72893Y28932D02*
G03X70113Y28926I-1387J-1207D01*
G01X75529Y29077D02*
G03X72893Y28932I-1248J-1352D01*
G01X74430Y28001D02*
G03X73000I-715J0D01*
G01X71541D02*
G03X70110I-716J0D01*
G01X74724Y45374D02*
G03X74331Y44980I1J-394D01*
G01Y42343D02*
G03X74724Y41949I393J-1D01*
G01Y40374D02*
G03X74331Y39980I1J-394D01*
G01X80324Y29130D02*
G03X77277I-1523J-2362D01*
G01X80845Y26252D02*
G03X80844Y28565I-2163J1156D01*
G01X76756Y28564D02*
G03X76757Y26250I2163J-1156D01*
G01X79502Y26585D02*
G03Y28270I-2236J842D01*
G01X77277Y29130D02*
G03X76756Y28564I831J-1288D01*
G01X76757Y26250D02*
G03X77278Y25685I1351J724D01*
G01X75823Y28406D02*
G03X75529Y29077I-914J0D01*
G01X79502Y28270D02*
G03X78029I-736J-277D01*
G01Y26585D02*
G03X79502I737J278D01*
G01X78030Y28270D02*
G03Y26585I2236J-843D01*
G01X80844Y28565D02*
G03X80323Y29130I-1351J-723D01*
G01X80324Y25687D02*
G03X80845Y26252I-830J1288D01*
G01X85591Y28858D02*
G03I-3505J0D01*
G01X80132Y31575D02*
G03Y26142I1954J-2717D01*
G01X84041D02*
G03Y31575I-1954J2716D01*
G01X84252Y28858D02*
G03I-2166J0D01*
G01X83847Y28310D02*
G03X83673Y27649I4019J-1411D01*
G01D02*
G03Y27152I3525J-249D01*
G01X88228Y27076D02*
G03X87889Y28519I-3015J53D01*
G01X83673Y27154D02*
G03X83935Y26291I2971J431D01*
G01X86655Y29492D02*
G03X85012Y29448I-756J-2475D01*
G01X83934Y26294D02*
G03X85672Y25276I1807J1093D01*
G01X85012Y29448D02*
G03X83847Y28310I728J-1911D01*
G01X87889Y28519D02*
G03X86655Y29492I-1735J-931D01*
G01X87254Y25563D02*
G03X88098Y26632I-703J1423D01*
G01X85229Y27076D02*
G03X86003Y26267I792J-17D01*
G01Y26268D02*
G03X86594Y26633I10J645D01*
G01X86654Y27902D02*
G03X85229I-713J82D01*
G01X46753Y45315D02*
X52838D01*
G01X46784Y45374D02*
X52529D01*
G01X46369Y45965D02*
X52956D01*
G01Y46358D02*
X46369D01*
G01X52529Y46949D02*
X46784D01*
G01X46369Y45965D02*
X46506Y45767D01*
X46644Y45570D01*
X46784Y45374D01*
G01X50909Y46949D02*
X50987Y46358D01*
G01X46369Y45965D02*
Y46358D01*
G01X50987D02*
Y45965D01*
G01X50909Y45374D02*
X50987Y45965D01*
G01X46784Y46949D02*
X46644Y46753D01*
X46506Y46556D01*
X46369Y46358D01*
G01X42520Y34390D02*
X44488Y32421D01*
G01X42520D02*
X39236D01*
G01X44488D02*
X94488D01*
G01X42520Y36949D02*
X73228D01*
G01X44488Y37343D02*
X62992D01*
G01X46784Y40374D02*
X52529D01*
G01X46369Y40965D02*
X52956D01*
G01Y41358D02*
X46369D01*
G01X46753Y41378D02*
X52838D01*
G01X53118Y41575D02*
X46506D01*
G01X52529Y41949D02*
X46784D01*
G01X46506Y41969D02*
X53118D01*
G01X46753Y42165D02*
X52838D01*
G01X46753Y44528D02*
X52838D01*
G01X53118Y44724D02*
X46506D01*
G01Y45118D02*
X53118D01*
G01X46369Y40965D02*
X46506Y40767D01*
X46644Y40570D01*
X46784Y40374D01*
G01X46753Y42165D02*
X46626Y42137D01*
X46537Y42065D01*
X46506Y41969D01*
G01X46753Y45315D02*
X46626Y45287D01*
X46537Y45214D01*
X46506Y45118D01*
G01Y41575D02*
X46538Y41478D01*
X46626Y41406D01*
X46753Y41378D01*
G01X46506Y44724D02*
X46538Y44627D01*
X46626Y44555D01*
X46753Y44528D01*
G01X50987Y41358D02*
X50909Y41949D01*
G01X42520Y174902D02*
Y32421D01*
G01X43642Y36949D02*
Y170374D01*
G01X43701Y36555D02*
Y107461D01*
G01X44488Y169980D02*
Y37343D01*
G01X46369Y40965D02*
Y41358D01*
G01X46506Y45118D02*
Y44724D01*
G01Y41969D02*
Y41575D01*
G01X50987Y40965D02*
Y41358D01*
G01Y40965D02*
X50909Y40374D01*
G01X46784Y41949D02*
X46644Y41753D01*
X46506Y41556D01*
X46369Y41358D01*
G01X44488Y37343D02*
X42520Y35374D01*
G01X51351Y108307D02*
X51389Y108281D01*
X51417Y108209D01*
X51428Y108110D01*
G01X51351Y111457D02*
X51389Y111430D01*
X51417Y111358D01*
X51428Y111260D01*
G01X51351Y114606D02*
X51389Y114580D01*
X51417Y114508D01*
X51428Y114409D01*
G01X51724Y116474D02*
X51753Y116470D01*
X51781Y116459D01*
X51806Y116441D01*
X51829Y116417D01*
X51847Y116387D01*
X51861Y116353D01*
X51869Y116316D01*
X51872Y116277D01*
G01X51724Y119624D02*
X51753Y119620D01*
X51781Y119609D01*
X51806Y119591D01*
X51829Y119566D01*
X51847Y119536D01*
X51861Y119502D01*
X51869Y119466D01*
X51872Y119427D01*
G01X51351Y117756D02*
X51389Y117730D01*
X51417Y117657D01*
X51428Y117559D01*
G01X74724Y105374D02*
X81890D01*
G01X74724Y106949D02*
X81890D01*
G01X77756Y107146D02*
X76772D01*
G01X92717Y107520D02*
X85384D01*
G01X85237D02*
X73228D01*
G01X77756Y107539D02*
X76772D01*
G01X77756Y107736D02*
X76772D01*
G01X85237Y108307D02*
X73228D01*
G01X85384D02*
X92717D01*
G01X77756Y109587D02*
X76772D01*
G01X77756Y109783D02*
X76772D01*
G01X77756Y110177D02*
X76772D01*
G01X74724Y110374D02*
X81890D01*
G01X92717Y110669D02*
X85384D01*
G01X85237D02*
X73228D01*
G01X85237Y111457D02*
X73228D01*
G01X85384D02*
X92717D01*
G01X74724Y111949D02*
X81890D01*
G01X77756Y112146D02*
X76772D01*
G01X77756Y112539D02*
X76772D01*
G01X77756Y112736D02*
X76772D01*
G01X92717Y113819D02*
X85384D01*
G01X85237D02*
X73228D01*
G01X74331Y113898D02*
X73228D01*
G01Y114016D02*
X80763D01*
G01X76222Y114508D02*
X78346D01*
G01X85237Y114606D02*
X73228D01*
G01X85384D02*
X92717D01*
G01X76222Y114803D02*
X75237D01*
G01X76222Y115000D02*
X75237D01*
G01X74331Y115197D02*
X80356D01*
G01X74331Y116378D02*
X80356D01*
G01X76222Y116575D02*
X75237D01*
G01X76222Y116772D02*
X75237D01*
G01X92717Y116969D02*
X85384D01*
G01X85237D02*
X73228D01*
G01X85237Y117756D02*
X73228D01*
G01X85384D02*
X92717D01*
G01X82220Y117835D02*
X80337D01*
G01X76222Y117953D02*
X75237D01*
G01X76222Y118150D02*
X75237D01*
G01X74331Y118346D02*
X80356D01*
G01X74331Y119528D02*
X80356D01*
G01X76222Y119724D02*
X75237D01*
G01X76222Y119921D02*
X75237D01*
G01X82220Y120039D02*
X80337D01*
G01X92717Y120118D02*
X85384D01*
G01X85237D02*
X73228D01*
G01X52529Y106949D02*
X52956Y106358D01*
G01X52597Y111949D02*
X53021Y111358D01*
G01X51802Y107520D02*
X51829Y107523D01*
X51855Y107534D01*
X51879Y107552D01*
X51900Y107577D01*
X51917Y107607D01*
X51930Y107641D01*
X51938Y107678D01*
X51941Y107717D01*
G01X51802Y110669D02*
X51829Y110673D01*
X51855Y110684D01*
X51879Y110702D01*
X51900Y110727D01*
X51917Y110757D01*
X51930Y110791D01*
X51938Y110827D01*
X51941Y110866D01*
G01X51802Y113819D02*
X51829Y113822D01*
X51855Y113833D01*
X51879Y113852D01*
X51900Y113876D01*
X51917Y113906D01*
X51930Y113940D01*
X51938Y113977D01*
X51941Y114016D01*
G01X51802Y116969D02*
X51829Y116972D01*
X51855Y116983D01*
X51879Y117001D01*
X51900Y117026D01*
X51917Y117056D01*
X51930Y117090D01*
X51938Y117126D01*
X51941Y117165D01*
G01X51802Y120118D02*
X51829Y120122D01*
X51855Y120133D01*
X51879Y120151D01*
X51900Y120176D01*
X51917Y120206D01*
X51930Y120239D01*
X51938Y120276D01*
X51941Y120315D01*
G01X51839Y106949D02*
X52112Y106358D01*
G01X51839Y111949D02*
X52112Y111358D01*
G01X51941Y108110D02*
X51938Y108148D01*
X51930Y108185D01*
X51917Y108219D01*
X51900Y108249D01*
X51879Y108274D01*
X51856Y108292D01*
X51830Y108303D01*
X51802Y108307D01*
G01X51941Y111260D02*
X51938Y111298D01*
X51930Y111335D01*
X51917Y111369D01*
X51900Y111399D01*
X51879Y111423D01*
X51856Y111441D01*
X51830Y111453D01*
X51802Y111457D01*
G01X51941Y114409D02*
X51938Y114448D01*
X51930Y114484D01*
X51917Y114518D01*
X51900Y114548D01*
X51879Y114573D01*
X51856Y114591D01*
X51830Y114602D01*
X51802Y114606D01*
G01X51941Y117559D02*
X51938Y117597D01*
X51930Y117634D01*
X51917Y117668D01*
X51900Y117698D01*
X51879Y117722D01*
X51856Y117741D01*
X51830Y117752D01*
X51802Y117756D01*
G01X51428Y120709D02*
Y120315D01*
G01Y117559D02*
Y117165D01*
G01Y114409D02*
Y114016D01*
G01Y111260D02*
Y110866D01*
G01Y108110D02*
Y107717D01*
G01X51872Y119427D02*
Y118443D01*
G01Y116277D02*
Y115293D01*
G01X51941Y107717D02*
Y108110D01*
G01Y110866D02*
Y111260D01*
G01Y117165D02*
Y117559D01*
G01Y114016D02*
Y114409D01*
G01Y120315D02*
Y120709D01*
G01X52112Y111358D02*
Y110965D01*
G01Y106358D02*
Y105965D01*
G01X52814Y119427D02*
Y118443D01*
G01Y116277D02*
Y115293D01*
G01X52956Y106358D02*
Y105965D01*
G01X53021Y111358D02*
Y110965D01*
G01X53118Y107717D02*
Y108110D01*
G01Y110866D02*
Y111260D01*
G01Y117165D02*
Y117559D01*
G01Y114016D02*
Y114409D01*
G01Y120315D02*
Y120709D01*
G01X69213Y113917D02*
Y133406D01*
G01X74409Y114016D02*
Y133307D01*
G01X74724D02*
Y114016D01*
G01X75170Y120906D02*
Y120118D01*
G01Y114606D02*
Y113819D01*
G01Y117756D02*
Y116969D01*
G01Y111457D02*
Y110669D01*
G01Y108307D02*
Y107520D01*
G01X75197Y120906D02*
Y120118D01*
G01Y114606D02*
Y113819D01*
G01Y117756D02*
Y116969D01*
G01Y111457D02*
Y110669D01*
G01Y108307D02*
Y107520D01*
G01X75237Y120118D02*
Y117756D01*
G01Y116969D02*
Y114606D01*
G01X75512Y133307D02*
Y114016D01*
G01X75573Y120906D02*
Y120118D01*
G01Y114606D02*
Y113819D01*
G01Y117756D02*
Y116969D01*
G01Y111457D02*
Y110669D01*
G01Y108307D02*
Y107520D01*
G01X75787Y111949D02*
Y110374D01*
G01Y106949D02*
Y105374D01*
G01X76012Y114016D02*
Y133307D01*
G01X76222Y132815D02*
Y114508D01*
G01X76772Y112736D02*
Y109587D01*
G01X76929Y133307D02*
Y114016D01*
G01X77206Y119528D02*
Y118346D01*
G01Y116378D02*
Y115197D01*
G01X77756Y112736D02*
Y109587D01*
G01X78740Y111949D02*
Y110374D01*
G01Y106949D02*
Y105374D01*
G01X78935Y107520D02*
Y108307D01*
G01Y110669D02*
Y111457D01*
G01Y113819D02*
Y114606D01*
G01Y116969D02*
Y117756D01*
G01Y120118D02*
Y120906D01*
G01X80285Y133307D02*
Y114016D01*
G01X80337Y117835D02*
Y120039D01*
G01X80356Y115197D02*
Y116378D01*
G01Y118346D02*
Y119528D01*
G01X80763Y127283D02*
Y120039D01*
G01Y117835D02*
Y114016D01*
G01X80919Y107520D02*
Y108307D01*
G01Y110669D02*
Y111457D01*
G01Y113819D02*
Y114606D01*
G01Y116969D02*
Y117756D01*
G01Y120118D02*
Y120906D01*
G01X81890Y105374D02*
Y106949D01*
G01Y110374D02*
Y111949D01*
G01X82220Y120039D02*
Y117835D01*
G01X82570Y120906D02*
Y120118D01*
G01Y114606D02*
Y113819D01*
G01Y117756D02*
Y116969D01*
G01Y111457D02*
Y110669D01*
G01Y108307D02*
Y107520D01*
G01X84298Y108307D02*
Y110669D01*
G01Y111457D02*
Y113819D01*
G01Y114606D02*
Y116969D01*
G01Y117756D02*
Y120118D01*
G01X85237Y120906D02*
Y120118D01*
G01Y114606D02*
Y113819D01*
G01Y117756D02*
Y116969D01*
G01Y111457D02*
Y110669D01*
G01Y108307D02*
Y107520D01*
G01X85384Y120906D02*
Y120118D01*
G01Y114606D02*
Y113819D01*
G01Y117756D02*
Y116969D01*
G01Y111457D02*
Y110669D01*
G01Y108307D02*
Y107520D01*
G01X86976Y120906D02*
Y120118D01*
G01Y114606D02*
Y113819D01*
G01Y117756D02*
Y116969D01*
G01Y111457D02*
Y110669D01*
G01Y108307D02*
Y107520D01*
G01X87918D02*
Y108307D01*
G01Y110669D02*
Y111457D01*
G01Y113819D02*
Y114606D01*
G01Y116969D02*
Y117756D01*
G01Y120118D02*
Y120906D01*
G01X90754Y107520D02*
Y108307D01*
G01Y110669D02*
Y111457D01*
G01Y113819D02*
Y114606D01*
G01Y116969D02*
Y117756D01*
G01Y120118D02*
Y120906D01*
G01X90943D02*
Y120118D01*
G01Y114606D02*
Y113819D01*
G01Y117756D02*
Y116969D01*
G01Y111457D02*
Y110669D01*
G01Y108307D02*
Y107520D01*
G01X92717Y120906D02*
Y120118D01*
G01Y114606D02*
Y113819D01*
G01Y117756D02*
Y116969D01*
G01Y111457D02*
Y110669D01*
G01Y108307D02*
Y107520D01*
G01X51872Y118443D02*
X51869Y118404D01*
X51861Y118368D01*
X51847Y118334D01*
X51829Y118304D01*
X51807Y118279D01*
X51781Y118261D01*
X51754Y118250D01*
X51724Y118246D01*
G01X51872Y115293D02*
X51869Y115255D01*
X51861Y115218D01*
X51847Y115184D01*
X51829Y115154D01*
X51807Y115130D01*
X51781Y115111D01*
X51754Y115100D01*
X51724Y115096D01*
G01X51428Y117165D02*
X51417Y117067D01*
X51389Y116995D01*
X51351Y116969D01*
G01X51428Y114016D02*
X51417Y113917D01*
X51389Y113845D01*
X51351Y113819D01*
G01X51428Y110866D02*
X51417Y110768D01*
X51389Y110696D01*
X51351Y110669D01*
G01X51428Y107717D02*
X51417Y107618D01*
X51389Y107546D01*
X51351Y107520D01*
G01X52112Y110965D02*
X51839Y110374D01*
G01X52112Y105965D02*
X51839Y105374D01*
G01X52597Y110374D02*
X53021Y110965D01*
G01X52529Y105374D02*
X52956Y105965D01*
G01X51351Y120118D02*
X51389Y120144D01*
X51417Y120217D01*
X51428Y120315D01*
G01X74331Y112343D02*
G03X74724Y111949I393J-1D01*
G01Y110374D02*
G03X74331Y109980I1J-394D01*
G01Y107343D02*
G03X74724Y106949I393J-1D01*
G01X50687Y116474D02*
X50694Y116470D01*
X50700Y116459D01*
X50706Y116441D01*
X50711Y116417D01*
X50715Y116387D01*
X50718Y116353D01*
X50720Y116316D01*
Y116277D01*
G01X50687Y119624D02*
X50694Y119620D01*
X50700Y119609D01*
X50706Y119591D01*
X50711Y119566D01*
X50715Y119536D01*
X50718Y119502D01*
X50720Y119466D01*
Y119427D01*
G01X46784Y105374D02*
X52529D01*
G01X46369Y105965D02*
X52956D01*
G01Y106358D02*
X46369D01*
G01X52529Y106949D02*
X46784D01*
G01X43531Y107461D02*
X62992D01*
G01X46753Y107520D02*
X52838D01*
G01X53118Y107717D02*
X46506D01*
G01Y108110D02*
X53118D01*
G01X46753Y108307D02*
X52838D01*
G01X52597Y110374D02*
X46684D01*
G01X46753Y110669D02*
X52838D01*
G01X53118Y110866D02*
X46506D01*
G01X46279Y110965D02*
X53021D01*
G01X46506Y111260D02*
X53118D01*
G01X53021Y111358D02*
X46279D01*
G01X46753Y111457D02*
X52838D01*
G01X71181Y111555D02*
X44488D01*
G01X52597Y111949D02*
X46684D01*
G01X48989Y112736D02*
X42520D01*
G01X46753Y113819D02*
X52838D01*
G01X62992Y113898D02*
X44488D01*
G01X48989Y113917D02*
X71181D01*
G01X53118Y114016D02*
X46506D01*
G01Y114409D02*
X53118D01*
G01X46753Y114606D02*
X52838D01*
G01X52552Y115096D02*
X46744D01*
G01X46496Y115293D02*
X52814D01*
G01Y116277D02*
X46496D01*
G01X52552Y116474D02*
X46744D01*
G01X46753Y116969D02*
X52838D01*
G01X53118Y117165D02*
X46506D01*
G01Y117559D02*
X53118D01*
G01X46753Y117756D02*
X52838D01*
G01X52552Y118246D02*
X46744D01*
G01X46496Y118443D02*
X52814D01*
G01Y119427D02*
X46496D01*
G01X52552Y119624D02*
X46744D01*
G01X46753Y120118D02*
X52838D01*
G01X53118Y120315D02*
X46506D01*
G01X46369Y105965D02*
X46506Y105767D01*
X46644Y105570D01*
X46784Y105374D01*
G01X46279Y110965D02*
X46413Y110767D01*
X46548Y110570D01*
X46684Y110374D01*
G01X46753Y108307D02*
X46626Y108279D01*
X46537Y108206D01*
X46506Y108110D01*
G01X46753Y111457D02*
X46626Y111429D01*
X46537Y111356D01*
X46506Y111260D01*
G01X46753Y114606D02*
X46626Y114578D01*
X46537Y114506D01*
X46506Y114409D01*
G01X46753Y117756D02*
X46626Y117728D01*
X46537Y117655D01*
X46506Y117559D01*
G01X46744Y116474D02*
X46617Y116447D01*
X46528Y116374D01*
X46496Y116277D01*
G01X46744Y119624D02*
X46617Y119596D01*
X46528Y119524D01*
X46496Y119427D01*
G01Y115293D02*
X46530Y115194D01*
X46618Y115123D01*
X46744Y115096D01*
G01X46496Y118443D02*
X46530Y118344D01*
X46618Y118273D01*
X46744Y118246D01*
G01X46506Y107717D02*
X46538Y107619D01*
X46626Y107547D01*
X46753Y107520D01*
G01X46506Y110866D02*
X46538Y110769D01*
X46626Y110697D01*
X46753Y110669D01*
G01X46506Y114016D02*
X46538Y113919D01*
X46626Y113846D01*
X46753Y113819D01*
G01X46506Y117165D02*
X46538Y117068D01*
X46626Y116996D01*
X46753Y116969D01*
G01X46506Y120315D02*
X46538Y120218D01*
X46626Y120146D01*
X46753Y120118D01*
G01X50987Y106358D02*
X50909Y106949D01*
G01X50987Y111358D02*
X50909Y111949D01*
G01X43531Y107461D02*
Y112940D01*
G01X43701Y134587D02*
Y112736D01*
G01X46279Y110965D02*
Y111358D01*
G01X46369Y105965D02*
Y106358D01*
G01X46496Y115293D02*
Y116277D01*
G01Y118443D02*
Y119427D01*
G01X46506Y120709D02*
Y120315D01*
G01Y117559D02*
Y117165D01*
G01Y114409D02*
Y114016D01*
G01Y111260D02*
Y110866D01*
G01Y108110D02*
Y107717D01*
G01X48989Y112736D02*
Y113917D01*
G01X50720Y119427D02*
Y118443D01*
G01Y116277D02*
Y115293D01*
G01X50987Y105965D02*
Y106358D01*
G01Y110965D02*
Y111358D01*
G01X50720Y118443D02*
Y118404D01*
X50718Y118368D01*
X50715Y118334D01*
X50711Y118304D01*
X50706Y118279D01*
X50700Y118261D01*
X50694Y118250D01*
X50687Y118246D01*
G01X50720Y115293D02*
Y115255D01*
X50718Y115218D01*
X50715Y115184D01*
X50711Y115154D01*
X50706Y115130D01*
X50700Y115111D01*
X50694Y115100D01*
X50687Y115096D01*
G01X50987Y110965D02*
X50909Y110374D01*
G01X50987Y105965D02*
X50909Y105374D01*
G01X46684Y111949D02*
X46548Y111752D01*
X46413Y111556D01*
X46279Y111358D01*
G01X46784Y106949D02*
X46644Y106753D01*
X46506Y106556D01*
X46369Y106358D01*
G01X42520Y111929D02*
X44488Y113898D01*
G01X51351Y48465D02*
X51389Y48438D01*
X51417Y48366D01*
X51428Y48268D01*
G01X51351Y51614D02*
X51389Y51588D01*
X51417Y51516D01*
X51428Y51417D01*
G01X51351Y54764D02*
X51389Y54737D01*
X51417Y54665D01*
X51428Y54567D01*
G01X51351Y57913D02*
X51389Y57887D01*
X51417Y57815D01*
X51428Y57717D01*
G01X51351Y61063D02*
X51389Y61037D01*
X51417Y60965D01*
X51428Y60866D01*
G01X51351Y64213D02*
X51389Y64186D01*
X51417Y64114D01*
X51428Y64016D01*
G01X51351Y67362D02*
X51389Y67336D01*
X51417Y67264D01*
X51428Y67165D01*
G01X51351Y70512D02*
X51389Y70485D01*
X51417Y70413D01*
X51428Y70315D01*
G01X51351Y73661D02*
X51389Y73635D01*
X51417Y73563D01*
X51428Y73465D01*
G01X51351Y76811D02*
X51389Y76785D01*
X51417Y76713D01*
X51428Y76614D01*
G01X51351Y79961D02*
X51389Y79934D01*
X51417Y79862D01*
X51428Y79764D01*
G01X51351Y83110D02*
X51389Y83084D01*
X51417Y83012D01*
X51428Y82913D01*
G01X51351Y86260D02*
X51389Y86233D01*
X51417Y86161D01*
X51428Y86063D01*
G01X51351Y89409D02*
X51389Y89383D01*
X51417Y89311D01*
X51428Y89213D01*
G01X51351Y92559D02*
X51389Y92533D01*
X51417Y92461D01*
X51428Y92362D01*
G01X51351Y95709D02*
X51389Y95682D01*
X51417Y95610D01*
X51428Y95512D01*
G01X51351Y98858D02*
X51389Y98832D01*
X51417Y98760D01*
X51428Y98661D01*
G01X51351Y102008D02*
X51389Y101981D01*
X51417Y101909D01*
X51428Y101811D01*
G01X51351Y105157D02*
X51389Y105131D01*
X51417Y105059D01*
X51428Y104961D01*
G01X92717Y47677D02*
X85384D01*
G01X85237D02*
X73228D01*
G01X77756Y47736D02*
X76772D01*
G01X85237Y48465D02*
X73228D01*
G01X85384D02*
X92717D01*
G01X77756Y49587D02*
X76772D01*
G01X77756Y49783D02*
X76772D01*
G01X77756Y50177D02*
X76772D01*
G01X74724Y50374D02*
X81890D01*
G01X92717Y50827D02*
X85384D01*
G01X85237D02*
X73228D01*
G01X85237Y51614D02*
X73228D01*
G01X85384D02*
X92717D01*
G01X74724Y51949D02*
X81890D01*
G01X77756Y52146D02*
X76772D01*
G01X77756Y52539D02*
X76772D01*
G01X77756Y52736D02*
X76772D01*
G01X73228Y53957D02*
X74331D01*
G01X92717Y53976D02*
X85384D01*
G01X85237D02*
X73228D01*
G01X75787Y54587D02*
X74803D01*
G01X85237Y54764D02*
X73228D01*
G01X85384D02*
X92717D01*
G01X75787Y54783D02*
X74803D01*
G01X75787Y55177D02*
X74803D01*
G01X74331Y55374D02*
X79921D01*
G01X74331Y56949D02*
X79921D01*
G01X92717Y57126D02*
X85384D01*
G01X85237D02*
X73228D01*
G01X75787Y57146D02*
X74803D01*
G01X75787Y57539D02*
X74803D01*
G01X75787Y57736D02*
X74803D01*
G01X85237Y57913D02*
X73228D01*
G01X85384D02*
X92717D01*
G01X73228Y58366D02*
X74331D01*
G01X77756Y59587D02*
X76772D01*
G01X77756Y59783D02*
X76772D01*
G01X77756Y60177D02*
X76772D01*
G01X92717Y60276D02*
X85384D01*
G01X85237D02*
X73228D01*
G01X74724Y60374D02*
X81890D01*
G01X85237Y61063D02*
X73228D01*
G01X85384D02*
X92717D01*
G01X74724Y61949D02*
X81890D01*
G01X77756Y62146D02*
X76772D01*
G01X77756Y62539D02*
X76772D01*
G01X77756Y62736D02*
X76772D01*
G01X92717Y63425D02*
X85384D01*
G01X85237D02*
X73228D01*
G01X85237Y64213D02*
X73228D01*
G01X85384D02*
X92717D01*
G01X77756Y64587D02*
X76772D01*
G01X77756Y64783D02*
X76772D01*
G01X77756Y65177D02*
X76772D01*
G01X74724Y65374D02*
X81890D01*
G01X92717Y66575D02*
X85384D01*
G01X85237D02*
X73228D01*
G01X74724Y66949D02*
X81890D01*
G01X77756Y67146D02*
X76772D01*
G01X85237Y67362D02*
X73228D01*
G01X85384D02*
X92717D01*
G01X77756Y67539D02*
X76772D01*
G01X77756Y67736D02*
X76772D01*
G01X77756Y69587D02*
X76772D01*
G01X92717Y69724D02*
X85384D01*
G01X85237D02*
X73228D01*
G01X77756Y69783D02*
X76772D01*
G01X77756Y70177D02*
X76772D01*
G01X74724Y70374D02*
X81890D01*
G01X85237Y70512D02*
X73228D01*
G01X85384D02*
X92717D01*
G01X74724Y71949D02*
X81890D01*
G01X77756Y72146D02*
X76772D01*
G01X77756Y72539D02*
X76772D01*
G01X77756Y72736D02*
X76772D01*
G01X92717Y72874D02*
X85384D01*
G01X85237D02*
X73228D01*
G01X85237Y73661D02*
X73228D01*
G01X85384D02*
X92717D01*
G01X77756Y74587D02*
X76772D01*
G01X77756Y74783D02*
X76772D01*
G01X77756Y75177D02*
X76772D01*
G01X74724Y75374D02*
X81890D01*
G01X92717Y76024D02*
X85384D01*
G01X85237D02*
X73228D01*
G01X85237Y76811D02*
X73228D01*
G01X85384D02*
X92717D01*
G01X74724Y76949D02*
X81890D01*
G01X77756Y77146D02*
X76772D01*
G01X77756Y77539D02*
X76772D01*
G01X77756Y77736D02*
X76772D01*
G01X92717Y79173D02*
X85384D01*
G01X85237D02*
X73228D01*
G01X77756Y79587D02*
X76772D01*
G01X77756Y79783D02*
X76772D01*
G01X85237Y79961D02*
X73228D01*
G01X85384D02*
X92717D01*
G01X77756Y80177D02*
X76772D01*
G01X74724Y80374D02*
X81890D01*
G01X74724Y81949D02*
X81890D01*
G01X77756Y82146D02*
X76772D01*
G01X92717Y82323D02*
X85384D01*
G01X85237D02*
X73228D01*
G01X77756Y82539D02*
X76772D01*
G01X77756Y82736D02*
X76772D01*
G01X85237Y83110D02*
X73228D01*
G01X85384D02*
X92717D01*
G01X77756Y84587D02*
X76772D01*
G01X77756Y84783D02*
X76772D01*
G01X77756Y85177D02*
X76772D01*
G01X74724Y85374D02*
X81890D01*
G01X92717Y85472D02*
X85384D01*
G01X85237D02*
X73228D01*
G01X85237Y86260D02*
X73228D01*
G01X85384D02*
X92717D01*
G01X74724Y86949D02*
X81890D01*
G01X77756Y87146D02*
X76772D01*
G01X52529Y51949D02*
X52956Y51358D01*
G01X52529Y61949D02*
X52956Y61358D01*
G01X52529Y66949D02*
X52956Y66358D01*
G01X52529Y71949D02*
X52956Y71358D01*
G01X52529Y76949D02*
X52956Y76358D01*
G01X51802Y50827D02*
X51829Y50830D01*
X51855Y50841D01*
X51879Y50859D01*
X51900Y50884D01*
X51917Y50914D01*
X51930Y50948D01*
X51938Y50985D01*
X51941Y51024D01*
G01X51802Y53976D02*
X51829Y53980D01*
X51855Y53991D01*
X51879Y54009D01*
X51900Y54034D01*
X51917Y54064D01*
X51930Y54098D01*
X51938Y54134D01*
X51941Y54173D01*
G01X51802Y57126D02*
X51829Y57130D01*
X51855Y57141D01*
X51879Y57159D01*
X51900Y57183D01*
X51917Y57213D01*
X51930Y57247D01*
X51938Y57284D01*
X51941Y57323D01*
G01X51802Y60276D02*
X51829Y60279D01*
X51855Y60290D01*
X51879Y60308D01*
X51900Y60333D01*
X51917Y60363D01*
X51930Y60397D01*
X51938Y60433D01*
X51941Y60472D01*
G01X51802Y63425D02*
X51829Y63429D01*
X51855Y63440D01*
X51879Y63458D01*
X51900Y63483D01*
X51917Y63513D01*
X51930Y63546D01*
X51938Y63583D01*
X51941Y63622D01*
G01X51802Y66575D02*
X51829Y66578D01*
X51855Y66589D01*
X51879Y66607D01*
X51900Y66632D01*
X51917Y66662D01*
X51930Y66696D01*
X51938Y66733D01*
X51941Y66772D01*
G01X51802Y69724D02*
X51829Y69728D01*
X51855Y69739D01*
X51879Y69757D01*
X51900Y69782D01*
X51917Y69812D01*
X51930Y69846D01*
X51938Y69882D01*
X51941Y69921D01*
G01X51802Y72874D02*
X51829Y72878D01*
X51855Y72889D01*
X51879Y72907D01*
X51900Y72931D01*
X51917Y72961D01*
X51930Y72995D01*
X51938Y73032D01*
X51941Y73071D01*
G01X51802Y76024D02*
X51829Y76027D01*
X51855Y76038D01*
X51879Y76056D01*
X51900Y76081D01*
X51917Y76111D01*
X51930Y76145D01*
X51938Y76181D01*
X51941Y76220D01*
G01X51802Y79173D02*
X51829Y79177D01*
X51855Y79188D01*
X51879Y79206D01*
X51900Y79231D01*
X51917Y79261D01*
X51930Y79294D01*
X51938Y79331D01*
X51941Y79370D01*
G01X51802Y82323D02*
X51829Y82326D01*
X51855Y82337D01*
X51879Y82356D01*
X51900Y82380D01*
X51917Y82410D01*
X51930Y82444D01*
X51938Y82481D01*
X51941Y82520D01*
G01X51802Y85472D02*
X51829Y85476D01*
X51855Y85487D01*
X51879Y85505D01*
X51900Y85530D01*
X51917Y85560D01*
X51930Y85594D01*
X51938Y85630D01*
X51941Y85669D01*
G01X51802Y88622D02*
X51829Y88626D01*
X51855Y88637D01*
X51879Y88655D01*
X51900Y88680D01*
X51917Y88709D01*
X51930Y88743D01*
X51938Y88780D01*
X51941Y88819D01*
G01X77756Y87539D02*
X76772D01*
G01X77756Y87736D02*
X76772D01*
G01X92717Y88622D02*
X85384D01*
G01X85237D02*
X73228D01*
G01X85237Y89409D02*
X73228D01*
G01X85384D02*
X92717D01*
G01X77756Y89587D02*
X76772D01*
G01X77756Y89783D02*
X76772D01*
G01X77756Y90177D02*
X76772D01*
G01X74724Y90374D02*
X81890D01*
G01X92717Y91772D02*
X85384D01*
G01X85237D02*
X73228D01*
G01X74724Y91949D02*
X81890D01*
G01X77756Y92146D02*
X76772D01*
G01X77756Y92539D02*
X76772D01*
G01X85237Y92559D02*
X73228D01*
G01X85384D02*
X92717D01*
G01X77756Y92736D02*
X76772D01*
G01X74331Y93957D02*
X73228D01*
G01X75787Y94587D02*
X74803D01*
G01X75787Y94783D02*
X74803D01*
G01X92717Y94921D02*
X85384D01*
G01X85237D02*
X73228D01*
G01X75787Y95177D02*
X74803D01*
G01X74331Y95374D02*
X79921D01*
G01X85237Y95709D02*
X73228D01*
G01X85384D02*
X92717D01*
G01X74331Y96949D02*
X79921D01*
G01X75787Y97146D02*
X74803D01*
G01X75787Y97539D02*
X74803D01*
G01X75787Y97736D02*
X74803D01*
G01X92717Y98071D02*
X85384D01*
G01X85237D02*
X73228D01*
G01Y98366D02*
X74331D01*
G01X85237Y98858D02*
X73228D01*
G01X85384D02*
X92717D01*
G01X77756Y99587D02*
X76772D01*
G01X77756Y99783D02*
X76772D01*
G01X77756Y100177D02*
X76772D01*
G01X74724Y100374D02*
X81890D01*
G01X92717Y101220D02*
X85384D01*
G01X85237D02*
X73228D01*
G01X74724Y101949D02*
X81890D01*
G01X85237Y102008D02*
X73228D01*
G01X85384D02*
X92717D01*
G01X77756Y102146D02*
X76772D01*
G01X77756Y102539D02*
X76772D01*
G01X77756Y102736D02*
X76772D01*
G01X92717Y104370D02*
X85384D01*
G01X85237D02*
X73228D01*
G01X77756Y104587D02*
X76772D01*
G01X77756Y104783D02*
X76772D01*
G01X85237Y105157D02*
X73228D01*
G01X85384D02*
X92717D01*
G01X77756Y105177D02*
X76772D01*
G01X52529Y81949D02*
X52956Y81358D01*
G01X52529Y86949D02*
X52956Y86358D01*
G01X52529Y91949D02*
X52956Y91358D01*
G01X52529Y101949D02*
X52956Y101358D01*
G01X51802Y91772D02*
X51829Y91775D01*
X51855Y91786D01*
X51879Y91804D01*
X51900Y91829D01*
X51917Y91859D01*
X51930Y91893D01*
X51938Y91930D01*
X51941Y91969D01*
G01X51802Y94921D02*
X51829Y94925D01*
X51855Y94936D01*
X51879Y94954D01*
X51900Y94979D01*
X51917Y95009D01*
X51930Y95043D01*
X51938Y95079D01*
X51941Y95118D01*
G01X51802Y98071D02*
X51829Y98074D01*
X51855Y98085D01*
X51879Y98104D01*
X51900Y98128D01*
X51917Y98158D01*
X51930Y98192D01*
X51938Y98229D01*
X51941Y98268D01*
G01X51802Y101220D02*
X51829Y101224D01*
X51855Y101235D01*
X51879Y101253D01*
X51900Y101278D01*
X51917Y101308D01*
X51930Y101342D01*
X51938Y101378D01*
X51941Y101417D01*
G01X51802Y104370D02*
X51829Y104374D01*
X51855Y104385D01*
X51879Y104403D01*
X51900Y104428D01*
X51917Y104457D01*
X51930Y104491D01*
X51938Y104528D01*
X51941Y104567D01*
G01X51839Y51949D02*
X52112Y51358D01*
G01X51839Y61949D02*
X52112Y61358D01*
G01X51839Y66949D02*
X52112Y66358D01*
G01X51839Y71949D02*
X52112Y71358D01*
G01X51839Y76949D02*
X52112Y76358D01*
G01X51839Y81949D02*
X52112Y81358D01*
G01X51839Y86949D02*
X52112Y86358D01*
G01X51839Y91949D02*
X52112Y91358D01*
G01X51839Y101949D02*
X52112Y101358D01*
G01X51941Y48268D02*
X51938Y48306D01*
X51930Y48343D01*
X51917Y48376D01*
X51900Y48407D01*
X51879Y48431D01*
X51856Y48449D01*
X51830Y48461D01*
X51802Y48465D01*
G01X51941Y51417D02*
X51938Y51456D01*
X51930Y51492D01*
X51917Y51526D01*
X51900Y51556D01*
X51879Y51581D01*
X51856Y51599D01*
X51830Y51610D01*
X51802Y51614D01*
G01X51941Y54567D02*
X51938Y54605D01*
X51930Y54642D01*
X51917Y54676D01*
X51900Y54706D01*
X51879Y54730D01*
X51856Y54748D01*
X51830Y54760D01*
X51802Y54764D01*
G01X51941Y57717D02*
X51938Y57755D01*
X51930Y57791D01*
X51917Y57825D01*
X51900Y57856D01*
X51879Y57880D01*
X51856Y57898D01*
X51830Y57909D01*
X51802Y57913D01*
G01X51941Y60866D02*
X51938Y60904D01*
X51930Y60941D01*
X51917Y60975D01*
X51900Y61005D01*
X51879Y61030D01*
X51856Y61048D01*
X51830Y61059D01*
X51802Y61063D01*
G01X51941Y64016D02*
X51938Y64054D01*
X51930Y64091D01*
X51917Y64124D01*
X51900Y64155D01*
X51879Y64179D01*
X51856Y64197D01*
X51830Y64209D01*
X51802Y64213D01*
G01X51941Y67165D02*
X51938Y67204D01*
X51930Y67240D01*
X51917Y67274D01*
X51900Y67304D01*
X51879Y67329D01*
X51856Y67347D01*
X51830Y67358D01*
X51802Y67362D01*
G01X51941Y70315D02*
X51938Y70353D01*
X51930Y70390D01*
X51917Y70424D01*
X51900Y70454D01*
X51879Y70478D01*
X51856Y70496D01*
X51830Y70508D01*
X51802Y70512D01*
G01X51941Y73465D02*
X51938Y73503D01*
X51930Y73539D01*
X51917Y73573D01*
X51900Y73604D01*
X51879Y73628D01*
X51856Y73646D01*
X51830Y73657D01*
X51802Y73661D01*
G01X51941Y76614D02*
X51938Y76652D01*
X51930Y76689D01*
X51917Y76723D01*
X51900Y76753D01*
X51879Y76778D01*
X51856Y76796D01*
X51830Y76807D01*
X51802Y76811D01*
G01X51941Y79764D02*
X51938Y79802D01*
X51930Y79839D01*
X51917Y79872D01*
X51900Y79903D01*
X51879Y79927D01*
X51856Y79945D01*
X51830Y79957D01*
X51802Y79961D01*
G01X51941Y82913D02*
X51938Y82952D01*
X51930Y82988D01*
X51917Y83022D01*
X51900Y83052D01*
X51879Y83077D01*
X51856Y83095D01*
X51830Y83106D01*
X51802Y83110D01*
G01X51941Y86063D02*
X51938Y86101D01*
X51930Y86138D01*
X51917Y86172D01*
X51900Y86202D01*
X51879Y86226D01*
X51856Y86244D01*
X51830Y86256D01*
X51802Y86260D01*
G01X51941Y89213D02*
X51938Y89251D01*
X51930Y89287D01*
X51917Y89321D01*
X51900Y89352D01*
X51879Y89376D01*
X51856Y89394D01*
X51830Y89406D01*
X51802Y89409D01*
G01X51941Y92362D02*
X51938Y92400D01*
X51930Y92437D01*
X51917Y92471D01*
X51900Y92501D01*
X51879Y92526D01*
X51856Y92544D01*
X51830Y92555D01*
X51802Y92559D01*
G01X51941Y95512D02*
X51938Y95550D01*
X51930Y95587D01*
X51917Y95620D01*
X51900Y95651D01*
X51879Y95675D01*
X51856Y95693D01*
X51830Y95705D01*
X51802Y95709D01*
G01X51941Y98661D02*
X51938Y98700D01*
X51930Y98736D01*
X51917Y98770D01*
X51900Y98800D01*
X51879Y98825D01*
X51856Y98843D01*
X51830Y98854D01*
X51802Y98858D01*
G01X51941Y101811D02*
X51938Y101849D01*
X51930Y101886D01*
X51917Y101920D01*
X51900Y101950D01*
X51879Y101974D01*
X51856Y101993D01*
X51830Y102004D01*
X51802Y102008D01*
G01X51941Y104961D02*
X51938Y104999D01*
X51930Y105035D01*
X51917Y105069D01*
X51900Y105100D01*
X51879Y105124D01*
X51856Y105142D01*
X51830Y105154D01*
X51802Y105157D01*
G01X51428Y104961D02*
Y104567D01*
G01Y101811D02*
Y101417D01*
G01Y98661D02*
Y98268D01*
G01Y95512D02*
Y95118D01*
G01Y92362D02*
Y91969D01*
G01Y86063D02*
Y85669D01*
G01Y89213D02*
Y88819D01*
G01Y82913D02*
Y82520D01*
G01Y79764D02*
Y79370D01*
G01Y76614D02*
Y76220D01*
G01Y73465D02*
Y73071D01*
G01Y67165D02*
Y66772D01*
G01Y70315D02*
Y69921D01*
G01Y64016D02*
Y63622D01*
G01Y57717D02*
Y57323D01*
G01Y60866D02*
Y60472D01*
G01Y54567D02*
Y54173D01*
G01Y48268D02*
Y47874D01*
G01Y51417D02*
Y51024D01*
G01X51941Y47874D02*
Y48268D01*
G01Y51024D02*
Y51417D01*
G01Y54173D02*
Y54567D01*
G01Y57323D02*
Y57717D01*
G01Y60472D02*
Y60866D01*
G01Y63622D02*
Y64016D01*
G01Y66772D02*
Y67165D01*
G01Y69921D02*
Y70315D01*
G01Y73071D02*
Y73465D01*
G01Y79370D02*
Y79764D01*
G01Y76220D02*
Y76614D01*
G01Y82520D02*
Y82913D01*
G01Y85669D02*
Y86063D01*
G01Y88819D02*
Y89213D01*
G01Y91969D02*
Y92362D01*
G01Y98268D02*
Y98661D01*
G01Y95118D02*
Y95512D01*
G01Y101417D02*
Y101811D01*
G01Y104567D02*
Y104961D01*
G01X52112Y101358D02*
Y100965D01*
G01Y91358D02*
Y90965D01*
G01Y86358D02*
Y85965D01*
G01Y81358D02*
Y80965D01*
G01Y76358D02*
Y75965D01*
G01Y71358D02*
Y70965D01*
G01Y66358D02*
Y65965D01*
G01Y61358D02*
Y60965D01*
G01Y51358D02*
Y50965D01*
G01X52956Y101358D02*
Y100965D01*
G01Y91358D02*
Y90965D01*
G01Y86358D02*
Y85965D01*
G01Y81358D02*
Y80965D01*
G01Y76358D02*
Y75965D01*
G01Y71358D02*
Y70965D01*
G01Y66358D02*
Y65965D01*
G01Y61358D02*
Y60965D01*
G01Y51358D02*
Y50965D01*
G01X53118Y47874D02*
Y48268D01*
G01Y51024D02*
Y51417D01*
G01Y54173D02*
Y54567D01*
G01Y57323D02*
Y57717D01*
G01Y60472D02*
Y60866D01*
G01Y63622D02*
Y64016D01*
G01Y66772D02*
Y67165D01*
G01Y69921D02*
Y70315D01*
G01Y73071D02*
Y73465D01*
G01Y79370D02*
Y79764D01*
G01Y76220D02*
Y76614D01*
G01Y82520D02*
Y82913D01*
G01Y85669D02*
Y86063D01*
G01Y88819D02*
Y89213D01*
G01Y91969D02*
Y92362D01*
G01Y98268D02*
Y98661D01*
G01Y95118D02*
Y95512D01*
G01Y101417D02*
Y101811D01*
G01Y104567D02*
Y104961D01*
G01X69213Y111555D02*
Y95217D01*
G01Y92854D02*
Y76319D01*
G01Y73957D02*
Y57421D01*
G01X74803Y97736D02*
Y94587D01*
G01Y57736D02*
Y54587D01*
G01X75170Y105157D02*
Y104370D01*
G01Y102008D02*
Y101220D01*
G01Y95709D02*
Y94921D01*
G01Y98858D02*
Y98071D01*
G01Y92559D02*
Y91772D01*
G01Y86260D02*
Y85472D01*
G01Y89409D02*
Y88622D01*
G01Y83110D02*
Y82323D01*
G01Y76811D02*
Y76024D01*
G01Y79961D02*
Y79173D01*
G01Y73661D02*
Y72874D01*
G01Y67362D02*
Y66575D01*
G01Y70512D02*
Y69724D01*
G01Y64213D02*
Y63425D01*
G01Y57913D02*
Y57126D01*
G01Y61063D02*
Y60276D01*
G01Y54764D02*
Y53976D01*
G01Y48465D02*
Y47677D01*
G01Y51614D02*
Y50827D01*
G01X75197Y105157D02*
Y104370D01*
G01Y102008D02*
Y101220D01*
G01Y95709D02*
Y94921D01*
G01Y98858D02*
Y98071D01*
G01Y92559D02*
Y91772D01*
G01Y86260D02*
Y85472D01*
G01Y89409D02*
Y88622D01*
G01Y83110D02*
Y82323D01*
G01Y76811D02*
Y76024D01*
G01Y79961D02*
Y79173D01*
G01Y73661D02*
Y72874D01*
G01Y67362D02*
Y66575D01*
G01Y70512D02*
Y69724D01*
G01Y64213D02*
Y63425D01*
G01Y57913D02*
Y57126D01*
G01Y61063D02*
Y60276D01*
G01Y54764D02*
Y53976D01*
G01Y48465D02*
Y47677D01*
G01Y51614D02*
Y50827D01*
G01X75573Y105157D02*
Y104370D01*
G01Y102008D02*
Y101220D01*
G01Y95709D02*
Y94921D01*
G01Y98858D02*
Y98071D01*
G01Y92559D02*
Y91772D01*
G01Y86260D02*
Y85472D01*
G01Y89409D02*
Y88622D01*
G01Y83110D02*
Y82323D01*
G01Y76811D02*
Y76024D01*
G01Y79961D02*
Y79173D01*
G01Y73661D02*
Y72874D01*
G01Y67362D02*
Y66575D01*
G01Y70512D02*
Y69724D01*
G01Y64213D02*
Y63425D01*
G01Y57913D02*
Y57126D01*
G01Y61063D02*
Y60276D01*
G01Y54764D02*
Y53976D01*
G01Y48465D02*
Y47677D01*
G01Y51614D02*
Y50827D01*
G01X75787Y101949D02*
Y100374D01*
G01Y97736D02*
Y94587D01*
G01Y91949D02*
Y90374D01*
G01Y86949D02*
Y85374D01*
G01Y81949D02*
Y80374D01*
G01Y76949D02*
Y75374D01*
G01Y71949D02*
Y70374D01*
G01Y66949D02*
Y65374D01*
G01Y61949D02*
Y60374D01*
G01Y57736D02*
Y54587D01*
G01Y51949D02*
Y50374D01*
G01X76772Y107736D02*
Y104587D01*
G01Y102736D02*
Y99587D01*
G01Y96949D02*
Y95374D01*
G01Y92736D02*
Y89587D01*
G01Y87736D02*
Y84587D01*
G01Y82736D02*
Y79587D01*
G01Y77736D02*
Y74587D01*
G01Y72736D02*
Y69587D01*
G01Y67736D02*
Y64587D01*
G01Y62736D02*
Y59587D01*
G01Y56949D02*
Y55374D01*
G01Y52736D02*
Y49587D01*
G01X77756Y107736D02*
Y104587D01*
G01Y102736D02*
Y99587D01*
G01Y92736D02*
Y89587D01*
G01Y87736D02*
Y84587D01*
G01Y82736D02*
Y79587D01*
G01Y77736D02*
Y74587D01*
G01Y72736D02*
Y69587D01*
G01Y67736D02*
Y64587D01*
G01Y62736D02*
Y59587D01*
G01Y52736D02*
Y49587D01*
G01X78740Y101949D02*
Y100374D01*
G01Y91949D02*
Y90374D01*
G01Y86949D02*
Y85374D01*
G01Y81949D02*
Y80374D01*
G01Y76949D02*
Y75374D01*
G01Y71949D02*
Y70374D01*
G01Y66949D02*
Y65374D01*
G01Y61949D02*
Y60374D01*
G01Y51949D02*
Y50374D01*
G01X78935Y47677D02*
Y48465D01*
G01Y50827D02*
Y51614D01*
G01Y53976D02*
Y54764D01*
G01Y57126D02*
Y57913D01*
G01Y60276D02*
Y61063D01*
G01Y63425D02*
Y64213D01*
G01Y66575D02*
Y67362D01*
G01Y69724D02*
Y70512D01*
G01Y72874D02*
Y73661D01*
G01Y76024D02*
Y76811D01*
G01Y79173D02*
Y79961D01*
G01Y82323D02*
Y83110D01*
G01Y85472D02*
Y86260D01*
G01Y88622D02*
Y89409D01*
G01Y91772D02*
Y92559D01*
G01Y94921D02*
Y95709D01*
G01Y98071D02*
Y98858D01*
G01Y101220D02*
Y102008D01*
G01Y104370D02*
Y105157D01*
G01X79921Y55374D02*
Y56949D01*
G01Y95374D02*
Y96949D01*
G01X80919Y47677D02*
Y48465D01*
G01Y50827D02*
Y51614D01*
G01Y53976D02*
Y54764D01*
G01Y57126D02*
Y57913D01*
G01Y60276D02*
Y61063D01*
G01Y63425D02*
Y64213D01*
G01Y66575D02*
Y67362D01*
G01Y69724D02*
Y70512D01*
G01Y72874D02*
Y73661D01*
G01Y76024D02*
Y76811D01*
G01Y79173D02*
Y79961D01*
G01Y82323D02*
Y83110D01*
G01Y85472D02*
Y86260D01*
G01Y88622D02*
Y89409D01*
G01Y91772D02*
Y92559D01*
G01Y94921D02*
Y95709D01*
G01Y98071D02*
Y98858D01*
G01Y101220D02*
Y102008D01*
G01Y104370D02*
Y105157D01*
G01X81890Y50374D02*
Y51949D01*
G01Y60374D02*
Y61949D01*
G01Y65374D02*
Y66949D01*
G01Y70374D02*
Y71949D01*
G01Y75374D02*
Y76949D01*
G01Y80374D02*
Y81949D01*
G01Y85374D02*
Y86949D01*
G01Y90374D02*
Y91949D01*
G01Y100374D02*
Y101949D01*
G01X82570Y105157D02*
Y104370D01*
G01Y102008D02*
Y101220D01*
G01Y95709D02*
Y94921D01*
G01Y98858D02*
Y98071D01*
G01Y92559D02*
Y91772D01*
G01Y86260D02*
Y85472D01*
G01Y89409D02*
Y88622D01*
G01Y83110D02*
Y82323D01*
G01Y76811D02*
Y76024D01*
G01Y79961D02*
Y79173D01*
G01Y73661D02*
Y72874D01*
G01Y67362D02*
Y66575D01*
G01Y70512D02*
Y69724D01*
G01Y64213D02*
Y63425D01*
G01Y57913D02*
Y57126D01*
G01Y61063D02*
Y60276D01*
G01Y54764D02*
Y53976D01*
G01Y48465D02*
Y47677D01*
G01Y51614D02*
Y50827D01*
G01X84298Y48465D02*
Y50827D01*
G01Y51614D02*
Y53976D01*
G01Y54764D02*
Y57126D01*
G01Y57913D02*
Y60276D01*
G01Y61063D02*
Y63425D01*
G01Y64213D02*
Y66575D01*
G01Y67362D02*
Y69724D01*
G01Y70512D02*
Y72874D01*
G01Y73661D02*
Y76024D01*
G01Y76811D02*
Y79173D01*
G01Y79961D02*
Y82323D01*
G01Y83110D02*
Y85472D01*
G01Y86260D02*
Y88622D01*
G01Y89409D02*
Y91772D01*
G01Y92559D02*
Y94921D01*
G01Y95709D02*
Y98071D01*
G01Y98858D02*
Y101220D01*
G01Y102008D02*
Y104370D01*
G01Y105157D02*
Y107520D01*
G01X85237Y105157D02*
Y104370D01*
G01Y102008D02*
Y101220D01*
G01Y95709D02*
Y94921D01*
G01Y98858D02*
Y98071D01*
G01Y92559D02*
Y91772D01*
G01Y86260D02*
Y85472D01*
G01Y89409D02*
Y88622D01*
G01Y83110D02*
Y82323D01*
G01Y76811D02*
Y76024D01*
G01Y79961D02*
Y79173D01*
G01Y73661D02*
Y72874D01*
G01Y67362D02*
Y66575D01*
G01Y70512D02*
Y69724D01*
G01Y64213D02*
Y63425D01*
G01Y57913D02*
Y57126D01*
G01Y61063D02*
Y60276D01*
G01Y54764D02*
Y53976D01*
G01Y48465D02*
Y47677D01*
G01Y51614D02*
Y50827D01*
G01X85384Y105157D02*
Y104370D01*
G01Y102008D02*
Y101220D01*
G01Y95709D02*
Y94921D01*
G01Y98858D02*
Y98071D01*
G01Y92559D02*
Y91772D01*
G01Y86260D02*
Y85472D01*
G01Y89409D02*
Y88622D01*
G01Y83110D02*
Y82323D01*
G01Y76811D02*
Y76024D01*
G01Y79961D02*
Y79173D01*
G01Y73661D02*
Y72874D01*
G01Y67362D02*
Y66575D01*
G01Y70512D02*
Y69724D01*
G01Y64213D02*
Y63425D01*
G01Y57913D02*
Y57126D01*
G01Y61063D02*
Y60276D01*
G01Y54764D02*
Y53976D01*
G01Y48465D02*
Y47677D01*
G01Y51614D02*
Y50827D01*
G01X86976Y105157D02*
Y104370D01*
G01Y102008D02*
Y101220D01*
G01Y95709D02*
Y94921D01*
G01Y98858D02*
Y98071D01*
G01Y92559D02*
Y91772D01*
G01Y86260D02*
Y85472D01*
G01Y89409D02*
Y88622D01*
G01Y83110D02*
Y82323D01*
G01Y76811D02*
Y76024D01*
G01Y79961D02*
Y79173D01*
G01Y73661D02*
Y72874D01*
G01Y67362D02*
Y66575D01*
G01Y70512D02*
Y69724D01*
G01Y64213D02*
Y63425D01*
G01Y57913D02*
Y57126D01*
G01Y61063D02*
Y60276D01*
G01Y54764D02*
Y53976D01*
G01Y48465D02*
Y47677D01*
G01Y51614D02*
Y50827D01*
G01X87918Y47677D02*
Y48465D01*
G01Y50827D02*
Y51614D01*
G01Y53976D02*
Y54764D01*
G01Y57126D02*
Y57913D01*
G01Y60276D02*
Y61063D01*
G01Y63425D02*
Y64213D01*
G01Y66575D02*
Y67362D01*
G01Y69724D02*
Y70512D01*
G01Y72874D02*
Y73661D01*
G01Y76024D02*
Y76811D01*
G01Y79173D02*
Y79961D01*
G01Y82323D02*
Y83110D01*
G01Y85472D02*
Y86260D01*
G01Y88622D02*
Y89409D01*
G01Y91772D02*
Y92559D01*
G01Y94921D02*
Y95709D01*
G01Y98071D02*
Y98858D01*
G01Y101220D02*
Y102008D01*
G01Y104370D02*
Y105157D01*
G01X90754Y47677D02*
Y48465D01*
G01Y50827D02*
Y51614D01*
G01Y53976D02*
Y54764D01*
G01Y57126D02*
Y57913D01*
G01Y60276D02*
Y61063D01*
G01Y63425D02*
Y64213D01*
G01Y66575D02*
Y67362D01*
G01Y69724D02*
Y70512D01*
G01Y72874D02*
Y73661D01*
G01Y76024D02*
Y76811D01*
G01Y79173D02*
Y79961D01*
G01Y82323D02*
Y83110D01*
G01Y85472D02*
Y86260D01*
G01Y88622D02*
Y89409D01*
G01Y91772D02*
Y92559D01*
G01Y94921D02*
Y95709D01*
G01Y98071D02*
Y98858D01*
G01Y101220D02*
Y102008D01*
G01Y104370D02*
Y105157D01*
G01X90943D02*
Y104370D01*
G01Y102008D02*
Y101220D01*
G01Y95709D02*
Y94921D01*
G01Y98858D02*
Y98071D01*
G01Y92559D02*
Y91772D01*
G01Y86260D02*
Y85472D01*
G01Y89409D02*
Y88622D01*
G01Y83110D02*
Y82323D01*
G01Y76811D02*
Y76024D01*
G01Y79961D02*
Y79173D01*
G01Y73661D02*
Y72874D01*
G01Y67362D02*
Y66575D01*
G01Y70512D02*
Y69724D01*
G01Y64213D02*
Y63425D01*
G01Y57913D02*
Y57126D01*
G01Y61063D02*
Y60276D01*
G01Y54764D02*
Y53976D01*
G01Y48465D02*
Y47677D01*
G01Y51614D02*
Y50827D01*
G01X92717Y105157D02*
Y104370D01*
G01Y102008D02*
Y101220D01*
G01Y95709D02*
Y94921D01*
G01Y98858D02*
Y98071D01*
G01Y92559D02*
Y91772D01*
G01Y86260D02*
Y85472D01*
G01Y89409D02*
Y88622D01*
G01Y83110D02*
Y82323D01*
G01Y76811D02*
Y76024D01*
G01Y79961D02*
Y79173D01*
G01Y73661D02*
Y72874D01*
G01Y67362D02*
Y66575D01*
G01Y70512D02*
Y69724D01*
G01Y64213D02*
Y63425D01*
G01Y57913D02*
Y57126D01*
G01Y61063D02*
Y60276D01*
G01Y54764D02*
Y53976D01*
G01Y48465D02*
Y47677D01*
G01Y51614D02*
Y50827D01*
G01X51428Y104567D02*
X51417Y104469D01*
X51389Y104396D01*
X51351Y104370D01*
G01X51428Y101417D02*
X51417Y101319D01*
X51389Y101247D01*
X51351Y101220D01*
G01X51428Y98268D02*
X51417Y98169D01*
X51389Y98097D01*
X51351Y98071D01*
G01X51428Y95118D02*
X51417Y95020D01*
X51389Y94948D01*
X51351Y94921D01*
G01X51428Y91969D02*
X51417Y91870D01*
X51389Y91798D01*
X51351Y91772D01*
G01X51428Y88819D02*
X51417Y88720D01*
X51389Y88648D01*
X51351Y88622D01*
G01X51428Y85669D02*
X51417Y85571D01*
X51389Y85499D01*
X51351Y85472D01*
G01X51428Y82520D02*
X51417Y82421D01*
X51389Y82349D01*
X51351Y82323D01*
G01X51428Y79370D02*
X51417Y79272D01*
X51389Y79200D01*
X51351Y79173D01*
G01X51428Y76220D02*
X51417Y76122D01*
X51389Y76050D01*
X51351Y76024D01*
G01X51428Y73071D02*
X51417Y72972D01*
X51389Y72900D01*
X51351Y72874D01*
G01X51428Y69921D02*
X51417Y69823D01*
X51389Y69751D01*
X51351Y69724D01*
G01X51428Y66772D02*
X51417Y66673D01*
X51389Y66601D01*
X51351Y66575D01*
G01X51428Y63622D02*
X51417Y63524D01*
X51389Y63452D01*
X51351Y63425D01*
G01X51428Y60472D02*
X51417Y60374D01*
X51389Y60302D01*
X51351Y60276D01*
G01X51428Y57323D02*
X51417Y57224D01*
X51389Y57152D01*
X51351Y57126D01*
G01X51428Y54173D02*
X51417Y54075D01*
X51389Y54003D01*
X51351Y53976D01*
G01X51428Y51024D02*
X51417Y50925D01*
X51389Y50853D01*
X51351Y50827D01*
G01X52112Y100965D02*
X51839Y100374D01*
G01X52112Y90965D02*
X51839Y90374D01*
G01X52112Y85965D02*
X51839Y85374D01*
G01X52112Y80965D02*
X51839Y80374D01*
G01X52112Y75965D02*
X51839Y75374D01*
G01X52112Y70965D02*
X51839Y70374D01*
G01X52112Y65965D02*
X51839Y65374D01*
G01X52112Y60965D02*
X51839Y60374D01*
G01X52112Y50965D02*
X51839Y50374D01*
G01X52529Y100374D02*
X52956Y100965D01*
G01X52529Y90374D02*
X52956Y90965D01*
G01X52529Y85374D02*
X52956Y85965D01*
G01X52529Y80374D02*
X52956Y80965D01*
G01X52529Y75374D02*
X52956Y75965D01*
G01X52529Y70374D02*
X52956Y70965D01*
G01X52529Y65374D02*
X52956Y65965D01*
G01X52529Y60374D02*
X52956Y60965D01*
G01X52529Y50374D02*
X52956Y50965D01*
G01X74331Y52343D02*
G03X74724Y51949I393J-1D01*
G01Y50374D02*
G03X74331Y49980I1J-394D01*
G01Y62343D02*
G03X74724Y61949I393J-1D01*
G01Y60374D02*
G03X74331Y59980I1J-394D01*
G01Y87343D02*
G03X74724Y86949I393J-1D01*
G01Y85374D02*
G03X74331Y84980I1J-394D01*
G01Y72343D02*
G03X74724Y71949I393J-1D01*
G01Y70374D02*
G03X74331Y69980I1J-394D01*
G01Y67343D02*
G03X74724Y66949I393J-1D01*
G01Y65374D02*
G03X74331Y64980I1J-394D01*
G01Y77343D02*
G03X74724Y76949I393J-1D01*
G01Y75374D02*
G03X74331Y74980I1J-394D01*
G01Y82343D02*
G03X74724Y81949I393J-1D01*
G01Y80374D02*
G03X74331Y79980I1J-394D01*
G01Y102343D02*
G03X74724Y101949I393J-1D01*
G01Y100374D02*
G03X74331Y99980I1J-394D01*
G01X74724Y105374D02*
G03X74331Y104980I1J-394D01*
G01Y92343D02*
G03X74724Y91949I393J-1D01*
G01Y90374D02*
G03X74331Y89980I1J-394D01*
G01X46753Y53976D02*
X46627Y54004D01*
X46538Y54076D01*
X46506Y54173D01*
G01X46753Y82323D02*
X46627Y82350D01*
X46538Y82423D01*
X46506Y82520D01*
G01X46753Y47677D02*
X52838D01*
G01X53118Y47874D02*
X46506D01*
G01Y48268D02*
X53118D01*
G01X46753Y48465D02*
X52838D01*
G01X46784Y50374D02*
X52529D01*
G01X46753Y50827D02*
X52838D01*
G01X46369Y50965D02*
X52956D01*
G01X53118Y51024D02*
X46506D01*
G01X52956Y51358D02*
X46369D01*
G01X46506Y51417D02*
X53118D01*
G01X46753Y51614D02*
X52838D01*
G01X52529Y51949D02*
X46784D01*
G01X46753Y53976D02*
X52838D01*
G01X53118Y54173D02*
X46506D01*
G01Y54567D02*
X53118D01*
G01X46753Y54764D02*
X52838D01*
G01X71181Y55059D02*
X44488D01*
G01X44815Y55374D02*
X50560D01*
G01X44401Y55965D02*
X50987D01*
G01Y56358D02*
X44401D01*
G01X50560Y56949D02*
X44815D01*
G01X46753Y57126D02*
X52838D01*
G01X53118Y57323D02*
X46506D01*
G01X44488Y57421D02*
X71181D01*
G01X46506Y57717D02*
X53118D01*
G01X46753Y57913D02*
X52838D01*
G01X46753Y60276D02*
X52838D01*
G01X46784Y60374D02*
X52529D01*
G01X53118Y60472D02*
X46506D01*
G01Y60866D02*
X53118D01*
G01X46369Y60965D02*
X52956D01*
G01X46753Y61063D02*
X52838D01*
G01X52956Y61358D02*
X46369D01*
G01X52529Y61949D02*
X46784D01*
G01X46753Y63425D02*
X52838D01*
G01X53118Y63622D02*
X46506D01*
G01Y64016D02*
X53118D01*
G01X46753Y64213D02*
X52838D01*
G01X46784Y65374D02*
X52529D01*
G01X46369Y65965D02*
X52956D01*
G01Y66358D02*
X46369D01*
G01X46753Y66575D02*
X52838D01*
G01X53118Y66772D02*
X46506D01*
G01X52529Y66949D02*
X46784D01*
G01X46506Y67165D02*
X53118D01*
G01X46753Y67362D02*
X52838D01*
G01X46753Y69724D02*
X52838D01*
G01X53118Y69921D02*
X46506D01*
G01Y70315D02*
X53118D01*
G01X46784Y70374D02*
X52529D01*
G01X46753Y70512D02*
X52838D01*
G01X46369Y70965D02*
X52956D01*
G01Y71358D02*
X46369D01*
G01X52529Y71949D02*
X46784D01*
G01X46753Y72874D02*
X52838D01*
G01X53118Y73071D02*
X46506D01*
G01Y73465D02*
X53118D01*
G01X46753Y73661D02*
X52838D01*
G01X71181Y73957D02*
X44488D01*
G01X46784Y75374D02*
X52529D01*
G01X46369Y75965D02*
X52956D01*
G01X46753Y76024D02*
X52838D01*
G01X53118Y76220D02*
X46506D01*
G01X44488Y76319D02*
X71181D01*
G01X52956Y76358D02*
X46369D01*
G01X46506Y76614D02*
X53118D01*
G01X46753Y76811D02*
X52838D01*
G01X52529Y76949D02*
X46784D01*
G01X46753Y79173D02*
X52838D01*
G01X53118Y79370D02*
X46506D01*
G01Y79764D02*
X53118D01*
G01X46753Y79961D02*
X52838D01*
G01X46784Y80374D02*
X52529D01*
G01X46369Y80965D02*
X52956D01*
G01Y81358D02*
X46369D01*
G01X52529Y81949D02*
X46784D01*
G01X46753Y82323D02*
X52838D01*
G01X53118Y82520D02*
X46506D01*
G01Y82913D02*
X53118D01*
G01X46753Y83110D02*
X52838D01*
G01X46784Y85374D02*
X52529D01*
G01X46753Y85472D02*
X52838D01*
G01X53118Y85669D02*
X46506D01*
G01X46369Y85965D02*
X52956D01*
G01X46506Y86063D02*
X53118D01*
G01X46753Y86260D02*
X52838D01*
G01X52956Y86358D02*
X46369D01*
G01X52529Y86949D02*
X46784D01*
G01X50560Y56949D02*
X50987Y56358D01*
G01X46369Y50965D02*
X46506Y50767D01*
X46644Y50570D01*
X46784Y50374D01*
G01X44401Y55965D02*
X44538Y55767D01*
X44676Y55570D01*
X44815Y55374D01*
G01X46369Y60965D02*
X46506Y60767D01*
X46644Y60570D01*
X46784Y60374D01*
G01X46369Y65965D02*
X46506Y65767D01*
X46644Y65570D01*
X46784Y65374D01*
G01X46753Y88622D02*
X52838D01*
G01X53118Y88819D02*
X46506D01*
G01Y89213D02*
X53118D01*
G01X46753Y89409D02*
X52838D01*
G01X46784Y90374D02*
X52529D01*
G01X46369Y90965D02*
X52956D01*
G01Y91358D02*
X46369D01*
G01X46753Y91772D02*
X52838D01*
G01X52529Y91949D02*
X46784D01*
G01X53118Y91969D02*
X46506D01*
G01Y92362D02*
X53118D01*
G01X46753Y92559D02*
X52838D01*
G01X71181Y92854D02*
X44488D01*
G01X46753Y94921D02*
X52838D01*
G01X53118Y95118D02*
X46506D01*
G01X44488Y95217D02*
X71181D01*
G01X44815Y95374D02*
X50560D01*
G01X46506Y95512D02*
X53118D01*
G01X46753Y95709D02*
X52838D01*
G01X44401Y95965D02*
X50987D01*
G01Y96358D02*
X44401D01*
G01X50560Y96949D02*
X44815D01*
G01X46753Y98071D02*
X52838D01*
G01X53118Y98268D02*
X46506D01*
G01Y98661D02*
X53118D01*
G01X46753Y98858D02*
X52838D01*
G01X46784Y100374D02*
X52529D01*
G01X46369Y100965D02*
X52956D01*
G01X46753Y101220D02*
X52838D01*
G01X52956Y101358D02*
X46369D01*
G01X53118Y101417D02*
X46506D01*
G01Y101811D02*
X53118D01*
G01X52529Y101949D02*
X46784D01*
G01X46753Y102008D02*
X52838D01*
G01X46753Y104370D02*
X52838D01*
G01X53118Y104567D02*
X46506D01*
G01Y104961D02*
X53118D01*
G01X46753Y105157D02*
X52838D01*
G01X50560Y96949D02*
X50987Y96358D01*
G01X46369Y70965D02*
X46506Y70767D01*
X46644Y70570D01*
X46784Y70374D01*
G01X46369Y75965D02*
X46506Y75767D01*
X46644Y75570D01*
X46784Y75374D01*
G01X46369Y80965D02*
X46506Y80767D01*
X46644Y80570D01*
X46784Y80374D01*
G01X46369Y85965D02*
X46506Y85767D01*
X46644Y85570D01*
X46784Y85374D01*
G01X46369Y90965D02*
X46506Y90767D01*
X46644Y90570D01*
X46784Y90374D01*
G01X44401Y95965D02*
X44538Y95767D01*
X44676Y95570D01*
X44815Y95374D01*
G01X46369Y100965D02*
X46506Y100767D01*
X46644Y100570D01*
X46784Y100374D01*
G01X46753Y48465D02*
X46626Y48437D01*
X46537Y48364D01*
X46506Y48268D01*
G01X46753Y51614D02*
X46626Y51586D01*
X46537Y51513D01*
X46506Y51417D01*
G01X46753Y57913D02*
X46626Y57885D01*
X46537Y57813D01*
X46506Y57717D01*
G01X46753Y61063D02*
X46626Y61035D01*
X46537Y60962D01*
X46506Y60866D01*
G01X46753Y64213D02*
X46626Y64185D01*
X46537Y64112D01*
X46506Y64016D01*
G01X46753Y67362D02*
X46626Y67334D01*
X46537Y67261D01*
X46506Y67165D01*
G01X46753Y70512D02*
X46626Y70484D01*
X46537Y70411D01*
X46506Y70315D01*
G01X46753Y73661D02*
X46626Y73633D01*
X46537Y73561D01*
X46506Y73465D01*
G01X46753Y76811D02*
X46626Y76783D01*
X46537Y76710D01*
X46506Y76614D01*
G01X46753Y79961D02*
X46626Y79933D01*
X46537Y79860D01*
X46506Y79764D01*
G01X46753Y86260D02*
X46626Y86232D01*
X46537Y86159D01*
X46506Y86063D01*
G01X46753Y89409D02*
X46626Y89381D01*
X46537Y89309D01*
X46506Y89213D01*
G01X46753Y92559D02*
X46626Y92531D01*
X46537Y92458D01*
X46506Y92362D01*
G01X46753Y95709D02*
X46626Y95681D01*
X46537Y95608D01*
X46506Y95512D01*
G01X46753Y98858D02*
X46626Y98830D01*
X46537Y98757D01*
X46506Y98661D01*
G01X46753Y102008D02*
X46626Y101980D01*
X46537Y101907D01*
X46506Y101811D01*
G01X46753Y105157D02*
X46626Y105130D01*
X46537Y105057D01*
X46506Y104961D01*
G01X49871Y56949D02*
X50143Y56358D01*
G01X49871Y96949D02*
X50143Y96358D01*
G01X46506Y47874D02*
X46538Y47777D01*
X46626Y47705D01*
X46753Y47677D01*
G01X46506Y51024D02*
X46538Y50926D01*
X46626Y50854D01*
X46753Y50827D01*
G01X46506Y57323D02*
X46538Y57226D01*
X46626Y57154D01*
X46753Y57126D01*
G01X46506Y60472D02*
X46538Y60375D01*
X46626Y60303D01*
X46753Y60276D01*
G01X46506Y63622D02*
X46538Y63525D01*
X46626Y63453D01*
X46753Y63425D01*
G01X46506Y66772D02*
X46538Y66674D01*
X46626Y66602D01*
X46753Y66575D01*
G01X46506Y69921D02*
X46538Y69824D01*
X46626Y69752D01*
X46753Y69724D01*
G01X46506Y73071D02*
X46538Y72974D01*
X46626Y72902D01*
X46753Y72874D01*
G01X46506Y76220D02*
X46538Y76123D01*
X46626Y76051D01*
X46753Y76024D01*
G01X46506Y79370D02*
X46538Y79273D01*
X46626Y79201D01*
X46753Y79173D01*
G01X46506Y85669D02*
X46538Y85572D01*
X46626Y85500D01*
X46753Y85472D01*
G01X46506Y88819D02*
X46538Y88722D01*
X46626Y88650D01*
X46753Y88622D01*
G01X46506Y91969D02*
X46538Y91871D01*
X46626Y91799D01*
X46753Y91772D01*
G01X46506Y95118D02*
X46538Y95021D01*
X46626Y94949D01*
X46753Y94921D01*
G01X46506Y98268D02*
X46538Y98170D01*
X46626Y98098D01*
X46753Y98071D01*
G01X46506Y101417D02*
X46538Y101320D01*
X46626Y101248D01*
X46753Y101220D01*
G01X46506Y104567D02*
X46538Y104470D01*
X46626Y104398D01*
X46753Y104370D01*
G01X49019Y56358D02*
X48941Y56949D01*
G01X50987Y51358D02*
X50909Y51949D01*
G01X50987Y61358D02*
X50909Y61949D01*
G01X50987Y66358D02*
X50909Y66949D01*
G01X50987Y71358D02*
X50909Y71949D01*
G01X50987Y76358D02*
X50909Y76949D01*
G01X50987Y81358D02*
X50909Y81949D01*
G01X49019Y96358D02*
X48941Y96949D01*
G01X50987Y86358D02*
X50909Y86949D01*
G01X50987Y91358D02*
X50909Y91949D01*
G01X50987Y101358D02*
X50909Y101949D01*
G01X44401Y55965D02*
Y56358D01*
G01Y95965D02*
Y96358D01*
G01X46369Y50965D02*
Y51358D01*
G01Y60965D02*
Y61358D01*
G01Y65965D02*
Y66358D01*
G01Y70965D02*
Y71358D01*
G01Y75965D02*
Y76358D01*
G01Y80965D02*
Y81358D01*
G01Y85965D02*
Y86358D01*
G01Y90965D02*
Y91358D01*
G01Y100965D02*
Y101358D01*
G01X46506Y104961D02*
Y104567D01*
G01Y101811D02*
Y101417D01*
G01Y98661D02*
Y98268D01*
G01Y95512D02*
Y95118D01*
G01Y92362D02*
Y91969D01*
G01Y86063D02*
Y85669D01*
G01Y89213D02*
Y88819D01*
G01Y82913D02*
Y82520D01*
G01Y79764D02*
Y79370D01*
G01Y76614D02*
Y76220D01*
G01Y73465D02*
Y73071D01*
G01Y67165D02*
Y66772D01*
G01Y70315D02*
Y69921D01*
G01Y64016D02*
Y63622D01*
G01Y57717D02*
Y57323D01*
G01Y60866D02*
Y60472D01*
G01Y54567D02*
Y54173D01*
G01Y48268D02*
Y47874D01*
G01Y51417D02*
Y51024D01*
G01X49019Y55965D02*
Y56358D01*
G01Y95965D02*
Y96358D01*
G01X50143D02*
Y95965D01*
G01Y56358D02*
Y55965D01*
G01X50987Y96358D02*
Y95965D01*
G01Y56358D02*
Y55965D01*
G01Y50965D02*
Y51358D01*
G01Y60965D02*
Y61358D01*
G01Y65965D02*
Y66358D01*
G01Y70965D02*
Y71358D01*
G01Y75965D02*
Y76358D01*
G01Y80965D02*
Y81358D01*
G01Y85965D02*
Y86358D01*
G01Y90965D02*
Y91358D01*
G01Y100965D02*
Y101358D01*
G01X49019Y95965D02*
X48941Y95374D01*
G01X50987Y100965D02*
X50909Y100374D01*
G01X50987Y90965D02*
X50909Y90374D01*
G01X50987Y85965D02*
X50909Y85374D01*
G01X50987Y80965D02*
X50909Y80374D01*
G01X50987Y75965D02*
X50909Y75374D01*
G01X50987Y70965D02*
X50909Y70374D01*
G01X49019Y55965D02*
X48941Y55374D01*
G01X50987Y65965D02*
X50909Y65374D01*
G01X50987Y60965D02*
X50909Y60374D01*
G01X50987Y50965D02*
X50909Y50374D01*
G01X46506Y82913D02*
X46539Y83012D01*
X46628Y83083D01*
X46753Y83110D01*
G01X46506Y54567D02*
X46539Y54666D01*
X46628Y54737D01*
X46753Y54764D01*
G01X50143Y95965D02*
X49871Y95374D01*
G01X50143Y55965D02*
X49871Y55374D01*
G01X46784Y101949D02*
X46644Y101753D01*
X46506Y101556D01*
X46369Y101358D01*
G01X44815Y96949D02*
X44676Y96753D01*
X44538Y96556D01*
X44401Y96358D01*
G01X46784Y91949D02*
X46644Y91753D01*
X46506Y91556D01*
X46369Y91358D01*
G01X46784Y86949D02*
X46644Y86753D01*
X46506Y86556D01*
X46369Y86358D01*
G01X46784Y81949D02*
X46644Y81753D01*
X46506Y81556D01*
X46369Y81358D01*
G01X46784Y76949D02*
X46644Y76753D01*
X46506Y76556D01*
X46369Y76358D01*
G01X46784Y71949D02*
X46644Y71753D01*
X46506Y71556D01*
X46369Y71358D01*
G01X46784Y66949D02*
X46644Y66753D01*
X46506Y66556D01*
X46369Y66358D01*
G01X46784Y61949D02*
X46644Y61753D01*
X46506Y61556D01*
X46369Y61358D01*
G01X50560Y95374D02*
X50987Y95965D01*
G01X44815Y56949D02*
X44676Y56753D01*
X44538Y56556D01*
X44401Y56358D01*
G01X46784Y51949D02*
X46644Y51753D01*
X46506Y51556D01*
X46369Y51358D01*
G01X50560Y55374D02*
X50987Y55965D01*
G01X51724Y122773D02*
X51753Y122770D01*
X51781Y122758D01*
X51806Y122741D01*
X51829Y122716D01*
X51847Y122686D01*
X51861Y122652D01*
X51869Y122615D01*
X51872Y122576D01*
G01X51724Y125923D02*
X51753Y125919D01*
X51781Y125908D01*
X51806Y125890D01*
X51829Y125865D01*
X51847Y125835D01*
X51861Y125802D01*
X51869Y125765D01*
X51872Y125726D01*
G01X51724Y129072D02*
X51753Y129069D01*
X51781Y129057D01*
X51806Y129040D01*
X51829Y129015D01*
X51847Y128985D01*
X51861Y128951D01*
X51869Y128915D01*
X51872Y128876D01*
G01X51724Y132222D02*
X51753Y132219D01*
X51781Y132207D01*
X51806Y132189D01*
X51829Y132165D01*
X51847Y132135D01*
X51861Y132101D01*
X51869Y132064D01*
X51872Y132025D01*
G01X51351Y120906D02*
X51389Y120879D01*
X51417Y120807D01*
X51428Y120709D01*
G01X51351Y124055D02*
X51389Y124029D01*
X51417Y123957D01*
X51428Y123858D01*
G01X51351Y127205D02*
X51389Y127178D01*
X51417Y127106D01*
X51428Y127008D01*
G01X51351Y130354D02*
X51389Y130328D01*
X51417Y130256D01*
X51428Y130157D01*
G01X51351Y133504D02*
X51389Y133478D01*
X51417Y133406D01*
X51428Y133307D01*
G01X51351Y136654D02*
X51389Y136627D01*
X51417Y136555D01*
X51428Y136457D01*
G01X51351Y139803D02*
X51389Y139777D01*
X51417Y139705D01*
X51428Y139606D01*
G01X51351Y142953D02*
X51389Y142926D01*
X51417Y142854D01*
X51428Y142756D01*
G01X85237Y120906D02*
X73228D01*
G01X85384D02*
X92717D01*
G01X76222Y121102D02*
X75237D01*
G01X76222Y121299D02*
X75237D01*
G01X74331Y121496D02*
X80356D01*
G01X74331Y122677D02*
X80356D01*
G01X76222Y122874D02*
X75237D01*
G01X76222Y123071D02*
X75237D01*
G01X92717Y123268D02*
X85384D01*
G01X85237D02*
X73228D01*
G01X85237Y124055D02*
X73228D01*
G01X85384D02*
X92717D01*
G01X76222Y124252D02*
X75237D01*
G01X76222Y124449D02*
X75237D01*
G01X74331Y124646D02*
X80356D01*
G01X74331Y125827D02*
X80356D01*
G01X76222Y126024D02*
X75237D01*
G01X76222Y126220D02*
X75237D01*
G01X92717Y126417D02*
X85384D01*
G01X85237D02*
X73228D01*
G01X85237Y127205D02*
X73228D01*
G01X85384D02*
X92717D01*
G01X82220Y127283D02*
X80337D01*
G01X76222Y127402D02*
X75237D01*
G01X76222Y127598D02*
X75237D01*
G01X74331Y127795D02*
X80356D01*
G01X74331Y128976D02*
X80356D01*
G01X76222Y129173D02*
X75237D01*
G01X76222Y129370D02*
X75237D01*
G01X82220Y129488D02*
X80337D01*
G01X92717Y129567D02*
X85384D01*
G01X85237D02*
X73228D01*
G01X85237Y130354D02*
X73228D01*
G01X85384D02*
X92717D01*
G01X76222Y130551D02*
X75237D01*
G01X76222Y130748D02*
X75237D01*
G01X74331Y130945D02*
X80356D01*
G01X74331Y132126D02*
X80356D01*
G01X76222Y132323D02*
X75237D01*
G01X76222Y132520D02*
X75237D01*
G01X92717Y132717D02*
X85384D01*
G01X85237D02*
X73228D01*
G01X78346Y132815D02*
X76222D01*
G01X73228Y133307D02*
X80763D01*
G01X74331Y133425D02*
X73228D01*
G01X85237Y133504D02*
X73228D01*
G01X85384D02*
X92717D01*
G01X77756Y134587D02*
X76772D01*
G01X77756Y134783D02*
X76772D01*
G01X77756Y135177D02*
X76772D01*
G01X74724Y135374D02*
X81890D01*
G01X92717Y135866D02*
X85384D01*
G01X85237D02*
X73228D01*
G01X85237Y136654D02*
X73228D01*
G01X85384D02*
X92717D01*
G01X74724Y136949D02*
X81890D01*
G01X77756Y137146D02*
X76772D01*
G01X77756Y137539D02*
X76772D01*
G01X77756Y137736D02*
X76772D01*
G01X92717Y139016D02*
X85384D01*
G01X85237D02*
X73228D01*
G01X77756Y139587D02*
X76772D01*
G01X77756Y139783D02*
X76772D01*
G01X85237Y139803D02*
X73228D01*
G01X85384D02*
X92717D01*
G01X77756Y140177D02*
X76772D01*
G01X74724Y140374D02*
X81890D01*
G01X74724Y141949D02*
X81890D01*
G01X77756Y142146D02*
X76772D01*
G01X92717Y142165D02*
X85384D01*
G01X85237D02*
X73228D01*
G01X77756Y142539D02*
X76772D01*
G01X77756Y142736D02*
X76772D01*
G01X85237Y142953D02*
X73228D01*
G01X85384D02*
X92717D01*
G01X77756Y144587D02*
X76772D01*
G01X77756Y144783D02*
X76772D01*
G01X77756Y145177D02*
X76772D01*
G01X52529Y141949D02*
X52956Y141358D01*
G01X52597Y136949D02*
X53021Y136358D01*
G01X51802Y123268D02*
X51829Y123271D01*
X51855Y123282D01*
X51879Y123300D01*
X51900Y123325D01*
X51917Y123355D01*
X51930Y123389D01*
X51938Y123426D01*
X51941Y123465D01*
G01X51802Y126417D02*
X51829Y126421D01*
X51855Y126432D01*
X51879Y126450D01*
X51900Y126475D01*
X51917Y126505D01*
X51930Y126539D01*
X51938Y126575D01*
X51941Y126614D01*
G01X51802Y129567D02*
X51829Y129570D01*
X51855Y129581D01*
X51879Y129600D01*
X51900Y129624D01*
X51917Y129654D01*
X51930Y129688D01*
X51938Y129725D01*
X51941Y129764D01*
G01X51802Y132717D02*
X51829Y132720D01*
X51855Y132731D01*
X51879Y132749D01*
X51900Y132774D01*
X51917Y132804D01*
X51930Y132838D01*
X51938Y132874D01*
X51941Y132913D01*
G01X51802Y135866D02*
X51829Y135870D01*
X51855Y135881D01*
X51879Y135899D01*
X51900Y135924D01*
X51917Y135954D01*
X51930Y135987D01*
X51938Y136024D01*
X51941Y136063D01*
G01X51802Y139016D02*
X51829Y139019D01*
X51855Y139030D01*
X51879Y139048D01*
X51900Y139073D01*
X51917Y139103D01*
X51930Y139137D01*
X51938Y139174D01*
X51941Y139213D01*
G01X51802Y142165D02*
X51829Y142169D01*
X51855Y142180D01*
X51879Y142198D01*
X51900Y142223D01*
X51917Y142253D01*
X51930Y142287D01*
X51938Y142323D01*
X51941Y142362D01*
G01X51839Y136949D02*
X52112Y136358D01*
G01X51839Y141949D02*
X52112Y141358D01*
G01X51941Y120709D02*
X51938Y120747D01*
X51930Y120783D01*
X51917Y120817D01*
X51900Y120848D01*
X51879Y120872D01*
X51856Y120890D01*
X51830Y120902D01*
X51802Y120906D01*
G01X51941Y123858D02*
X51938Y123896D01*
X51930Y123933D01*
X51917Y123967D01*
X51900Y123997D01*
X51879Y124022D01*
X51856Y124040D01*
X51830Y124051D01*
X51802Y124055D01*
G01X51941Y127008D02*
X51938Y127046D01*
X51930Y127083D01*
X51917Y127117D01*
X51900Y127147D01*
X51879Y127171D01*
X51856Y127189D01*
X51830Y127201D01*
X51802Y127205D01*
G01X51941Y130157D02*
X51938Y130196D01*
X51930Y130232D01*
X51917Y130266D01*
X51900Y130296D01*
X51879Y130321D01*
X51856Y130339D01*
X51830Y130350D01*
X51802Y130354D01*
G01X51941Y133307D02*
X51938Y133345D01*
X51930Y133382D01*
X51917Y133416D01*
X51900Y133446D01*
X51879Y133470D01*
X51856Y133489D01*
X51830Y133500D01*
X51802Y133504D01*
G01X51941Y136457D02*
X51938Y136495D01*
X51930Y136531D01*
X51917Y136565D01*
X51900Y136596D01*
X51879Y136620D01*
X51856Y136638D01*
X51830Y136650D01*
X51802Y136654D01*
G01X51941Y139606D02*
X51938Y139644D01*
X51930Y139681D01*
X51917Y139715D01*
X51900Y139745D01*
X51879Y139770D01*
X51856Y139788D01*
X51830Y139799D01*
X51802Y139803D01*
G01X51941Y142756D02*
X51938Y142794D01*
X51930Y142831D01*
X51917Y142865D01*
X51900Y142895D01*
X51879Y142919D01*
X51856Y142937D01*
X51830Y142949D01*
X51802Y142953D01*
G01X51428Y142756D02*
Y142362D01*
G01Y139606D02*
Y139213D01*
G01Y133307D02*
Y132913D01*
G01Y136457D02*
Y136063D01*
G01Y130157D02*
Y129764D01*
G01Y127008D02*
Y126614D01*
G01Y123858D02*
Y123465D01*
G01X51872Y128876D02*
Y127891D01*
G01Y132025D02*
Y131041D01*
G01Y125726D02*
Y124742D01*
G01Y122576D02*
Y121592D01*
G01X51941Y126614D02*
Y127008D01*
G01Y123465D02*
Y123858D01*
G01Y129764D02*
Y130157D01*
G01Y132913D02*
Y133307D01*
G01Y136063D02*
Y136457D01*
G01Y139213D02*
Y139606D01*
G01Y142362D02*
Y142756D01*
G01X52112Y141358D02*
Y140965D01*
G01Y136358D02*
Y135965D01*
G01X52814Y128876D02*
Y127891D01*
G01Y132025D02*
Y131041D01*
G01Y125726D02*
Y124742D01*
G01Y122576D02*
Y121592D01*
G01X52956Y141358D02*
Y140965D01*
G01X53021Y136358D02*
Y135965D01*
G01X53118Y126614D02*
Y127008D01*
G01Y123465D02*
Y123858D01*
G01Y129764D02*
Y130157D01*
G01Y132913D02*
Y133307D01*
G01Y136063D02*
Y136457D01*
G01Y139213D02*
Y139606D01*
G01Y142362D02*
Y142756D01*
G01X69213Y135768D02*
Y151004D01*
G01X75170Y142953D02*
Y142165D01*
G01Y139803D02*
Y139016D01*
G01Y133504D02*
Y132717D01*
G01Y136654D02*
Y135866D01*
G01Y130354D02*
Y129567D01*
G01Y124055D02*
Y123268D01*
G01Y127205D02*
Y126417D01*
G01X75197Y142953D02*
Y142165D01*
G01Y139803D02*
Y139016D01*
G01Y133504D02*
Y132717D01*
G01Y136654D02*
Y135866D01*
G01Y130354D02*
Y129567D01*
G01Y124055D02*
Y123268D01*
G01Y127205D02*
Y126417D01*
G01X75237Y132717D02*
Y130354D01*
G01Y129567D02*
Y127205D01*
G01Y123268D02*
Y120906D01*
G01Y126417D02*
Y124055D01*
G01X75573Y142953D02*
Y142165D01*
G01Y139803D02*
Y139016D01*
G01Y133504D02*
Y132717D01*
G01Y136654D02*
Y135866D01*
G01Y130354D02*
Y129567D01*
G01Y124055D02*
Y123268D01*
G01Y127205D02*
Y126417D01*
G01X75787Y141949D02*
Y140374D01*
G01Y136949D02*
Y135374D01*
G01X76772Y147736D02*
Y144587D01*
G01Y142736D02*
Y139587D01*
G01Y137736D02*
Y134587D01*
G01X77206Y132126D02*
Y130945D01*
G01Y128976D02*
Y127795D01*
G01Y125827D02*
Y124646D01*
G01Y122677D02*
Y121496D01*
G01X77756Y147736D02*
Y144587D01*
G01Y142736D02*
Y139587D01*
G01Y137736D02*
Y134587D01*
G01X78740Y141949D02*
Y140374D01*
G01Y136949D02*
Y135374D01*
G01X78935Y123268D02*
Y124055D01*
G01Y126417D02*
Y127205D01*
G01Y129567D02*
Y130354D01*
G01Y132717D02*
Y133504D01*
G01Y135866D02*
Y136654D01*
G01Y139016D02*
Y139803D01*
G01Y142165D02*
Y142953D01*
G01X80337Y127283D02*
Y129488D01*
G01X80356Y121496D02*
Y122677D01*
G01Y124646D02*
Y125827D01*
G01Y127795D02*
Y128976D01*
G01Y130945D02*
Y132126D01*
G01X80763Y133307D02*
Y129488D01*
G01X80919Y123268D02*
Y124055D01*
G01Y126417D02*
Y127205D01*
G01Y129567D02*
Y130354D01*
G01Y132717D02*
Y133504D01*
G01Y135866D02*
Y136654D01*
G01Y139016D02*
Y139803D01*
G01Y142165D02*
Y142953D01*
G01X81890Y135374D02*
Y136949D01*
G01Y140374D02*
Y141949D01*
G01X82220Y129488D02*
Y127283D01*
G01X82570Y142953D02*
Y142165D01*
G01Y139803D02*
Y139016D01*
G01Y133504D02*
Y132717D01*
G01Y136654D02*
Y135866D01*
G01Y130354D02*
Y129567D01*
G01Y124055D02*
Y123268D01*
G01Y127205D02*
Y126417D01*
G01X84298Y120906D02*
Y123268D01*
G01Y124055D02*
Y126417D01*
G01Y127205D02*
Y129567D01*
G01Y130354D02*
Y132717D01*
G01Y133504D02*
Y135866D01*
G01Y136654D02*
Y139016D01*
G01Y139803D02*
Y142165D01*
G01Y142953D02*
Y145315D01*
G01X85237Y142953D02*
Y142165D01*
G01Y139803D02*
Y139016D01*
G01Y133504D02*
Y132717D01*
G01Y136654D02*
Y135866D01*
G01Y130354D02*
Y129567D01*
G01Y124055D02*
Y123268D01*
G01Y127205D02*
Y126417D01*
G01X85384Y142953D02*
Y142165D01*
G01Y139803D02*
Y139016D01*
G01Y133504D02*
Y132717D01*
G01Y136654D02*
Y135866D01*
G01Y130354D02*
Y129567D01*
G01Y124055D02*
Y123268D01*
G01Y127205D02*
Y126417D01*
G01X86976Y142953D02*
Y142165D01*
G01Y139803D02*
Y139016D01*
G01Y133504D02*
Y132717D01*
G01Y136654D02*
Y135866D01*
G01Y130354D02*
Y129567D01*
G01Y124055D02*
Y123268D01*
G01Y127205D02*
Y126417D01*
G01X87918Y123268D02*
Y124055D01*
G01Y126417D02*
Y127205D01*
G01Y129567D02*
Y130354D01*
G01Y132717D02*
Y133504D01*
G01Y135866D02*
Y136654D01*
G01Y139016D02*
Y139803D01*
G01Y142165D02*
Y142953D01*
G01X90754Y123268D02*
Y124055D01*
G01Y126417D02*
Y127205D01*
G01Y129567D02*
Y130354D01*
G01Y132717D02*
Y133504D01*
G01Y135866D02*
Y136654D01*
G01Y139016D02*
Y139803D01*
G01Y142165D02*
Y142953D01*
G01X90943D02*
Y142165D01*
G01Y139803D02*
Y139016D01*
G01Y133504D02*
Y132717D01*
G01Y136654D02*
Y135866D01*
G01Y130354D02*
Y129567D01*
G01Y124055D02*
Y123268D01*
G01Y127205D02*
Y126417D01*
G01X92717Y142953D02*
Y142165D01*
G01Y139803D02*
Y139016D01*
G01Y133504D02*
Y132717D01*
G01Y136654D02*
Y135866D01*
G01Y130354D02*
Y129567D01*
G01Y124055D02*
Y123268D01*
G01Y127205D02*
Y126417D01*
G01X51872Y131041D02*
X51869Y131003D01*
X51861Y130966D01*
X51847Y130932D01*
X51829Y130902D01*
X51807Y130878D01*
X51781Y130859D01*
X51754Y130848D01*
X51724Y130844D01*
G01X51872Y127891D02*
X51869Y127853D01*
X51861Y127817D01*
X51847Y127783D01*
X51829Y127752D01*
X51807Y127728D01*
X51781Y127710D01*
X51754Y127698D01*
X51724Y127694D01*
G01X51872Y124742D02*
X51869Y124704D01*
X51861Y124667D01*
X51847Y124633D01*
X51829Y124603D01*
X51807Y124578D01*
X51781Y124560D01*
X51754Y124549D01*
X51724Y124545D01*
G01X51872Y121592D02*
X51869Y121554D01*
X51861Y121517D01*
X51847Y121483D01*
X51829Y121453D01*
X51807Y121429D01*
X51781Y121411D01*
X51754Y121399D01*
X51724Y121395D01*
G01X51428Y142362D02*
X51417Y142264D01*
X51389Y142192D01*
X51351Y142165D01*
G01X51428Y132913D02*
X51417Y132815D01*
X51389Y132743D01*
X51351Y132717D01*
G01X51428Y129764D02*
X51417Y129665D01*
X51389Y129593D01*
X51351Y129567D01*
G01X51428Y126614D02*
X51417Y126516D01*
X51389Y126444D01*
X51351Y126417D01*
G01X51428Y123465D02*
X51417Y123366D01*
X51389Y123294D01*
X51351Y123268D01*
G01X52112Y140965D02*
X51839Y140374D01*
G01X52112Y135965D02*
X51839Y135374D01*
G01X52597D02*
X53021Y135965D01*
G01X52529Y140374D02*
X52956Y140965D01*
G01X51351Y139016D02*
X51389Y139042D01*
X51417Y139114D01*
X51428Y139213D01*
G01X51351Y135866D02*
X51389Y135893D01*
X51417Y135965D01*
X51428Y136063D01*
G01X74724Y145374D02*
G03X74331Y144980I1J-394D01*
G01Y142343D02*
G03X74724Y141949I393J-1D01*
G01Y140374D02*
G03X74331Y139980I1J-394D01*
G01Y137343D02*
G03X74724Y136949I393J-1D01*
G01Y135374D02*
G03X74331Y134980I1J-394D01*
G01X50687Y122773D02*
X50694Y122770D01*
X50700Y122758D01*
X50706Y122741D01*
X50711Y122716D01*
X50715Y122686D01*
X50718Y122652D01*
X50720Y122615D01*
Y122576D01*
G01X50687Y125923D02*
X50694Y125919D01*
X50700Y125908D01*
X50706Y125890D01*
X50711Y125865D01*
X50715Y125835D01*
X50718Y125802D01*
X50720Y125765D01*
Y125726D01*
G01X50687Y129072D02*
X50694Y129069D01*
X50700Y129057D01*
X50706Y129040D01*
X50711Y129015D01*
X50715Y128985D01*
X50718Y128951D01*
X50720Y128915D01*
Y128876D01*
G01X50687Y132222D02*
X50694Y132219D01*
X50700Y132207D01*
X50706Y132189D01*
X50711Y132165D01*
X50715Y132135D01*
X50718Y132101D01*
X50720Y132064D01*
Y132025D01*
G01X44488Y133425D02*
X42520Y135394D01*
G01X46506Y120709D02*
X53118D01*
G01X46753Y120906D02*
X52838D01*
G01X52552Y121395D02*
X46744D01*
G01X46496Y121592D02*
X52814D01*
G01Y122576D02*
X46496D01*
G01X52552Y122773D02*
X46744D01*
G01X46753Y123268D02*
X52838D01*
G01X53118Y123465D02*
X46506D01*
G01Y123858D02*
X53118D01*
G01X46753Y124055D02*
X52838D01*
G01X52552Y124545D02*
X46744D01*
G01X46496Y124742D02*
X52814D01*
G01Y125726D02*
X46496D01*
G01X52552Y125923D02*
X46744D01*
G01X46753Y126417D02*
X52838D01*
G01X53118Y126614D02*
X46506D01*
G01Y127008D02*
X53118D01*
G01X46753Y127205D02*
X52838D01*
G01X52552Y127694D02*
X46744D01*
G01X46496Y127891D02*
X52814D01*
G01Y128876D02*
X46496D01*
G01X52552Y129072D02*
X46744D01*
G01X46753Y129567D02*
X52838D01*
G01X53118Y129764D02*
X46506D01*
G01Y130157D02*
X53118D01*
G01X46753Y130354D02*
X52838D01*
G01X52552Y130844D02*
X46744D01*
G01X46496Y131041D02*
X52814D01*
G01Y132025D02*
X46496D01*
G01X52552Y132222D02*
X46744D01*
G01X46753Y132717D02*
X52838D01*
G01X53118Y132913D02*
X46506D01*
G01Y133307D02*
X53118D01*
G01X71181Y133406D02*
X48989D01*
G01X62992Y133425D02*
X44488D01*
G01X46753Y133504D02*
X52838D01*
G01X42520Y134587D02*
X48989D01*
G01X52597Y135374D02*
X46684D01*
G01X44488Y135768D02*
X71181D01*
G01X46753Y135866D02*
X52838D01*
G01X46279Y135965D02*
X53021D01*
G01X53118Y136063D02*
X46506D01*
G01X53021Y136358D02*
X46279D01*
G01X46506Y136457D02*
X53118D01*
G01X46753Y136654D02*
X52838D01*
G01X52597Y136949D02*
X46684D01*
G01X46753Y139016D02*
X52838D01*
G01X53118Y139213D02*
X46506D01*
G01Y139606D02*
X53118D01*
G01X62992Y139764D02*
X43531D01*
G01X46753Y139803D02*
X52838D01*
G01X46784Y140374D02*
X52529D01*
G01X46369Y140965D02*
X52956D01*
G01Y141358D02*
X46369D01*
G01X52529Y141949D02*
X46784D01*
G01X46753Y142165D02*
X52838D01*
G01X53118Y142362D02*
X46506D01*
G01Y142756D02*
X53118D01*
G01X46753Y142953D02*
X52838D01*
G01X46369Y140965D02*
X46506Y140767D01*
X46644Y140570D01*
X46784Y140374D01*
G01X46279Y135965D02*
X46413Y135767D01*
X46548Y135570D01*
X46684Y135374D01*
G01X46753Y120906D02*
X46626Y120878D01*
X46537Y120805D01*
X46506Y120709D01*
G01X46744Y122773D02*
X46617Y122746D01*
X46528Y122673D01*
X46496Y122576D01*
G01X46753Y124055D02*
X46626Y124027D01*
X46537Y123954D01*
X46506Y123858D01*
G01X46753Y127205D02*
X46626Y127177D01*
X46537Y127104D01*
X46506Y127008D01*
G01X46753Y130354D02*
X46626Y130326D01*
X46537Y130254D01*
X46506Y130157D01*
G01X46753Y133504D02*
X46626Y133476D01*
X46537Y133403D01*
X46506Y133307D01*
G01X46753Y136654D02*
X46626Y136626D01*
X46537Y136553D01*
X46506Y136457D01*
G01X46753Y139803D02*
X46626Y139775D01*
X46537Y139702D01*
X46506Y139606D01*
G01X46753Y142953D02*
X46626Y142925D01*
X46537Y142852D01*
X46506Y142756D01*
G01X46744Y125923D02*
X46617Y125896D01*
X46528Y125823D01*
X46496Y125726D01*
G01X46744Y129072D02*
X46617Y129045D01*
X46528Y128972D01*
X46496Y128876D01*
G01X46744Y132222D02*
X46617Y132195D01*
X46528Y132122D01*
X46496Y132025D01*
G01Y121592D02*
X46530Y121493D01*
X46618Y121422D01*
X46744Y121395D01*
G01X46496Y124742D02*
X46530Y124643D01*
X46618Y124572D01*
X46744Y124545D01*
G01X46496Y127891D02*
X46530Y127793D01*
X46618Y127722D01*
X46744Y127694D01*
G01X46496Y131041D02*
X46530Y130942D01*
X46618Y130871D01*
X46744Y130844D01*
G01X46506Y123465D02*
X46538Y123367D01*
X46626Y123295D01*
X46753Y123268D01*
G01X46506Y126614D02*
X46538Y126517D01*
X46626Y126445D01*
X46753Y126417D01*
G01X46506Y129764D02*
X46538Y129667D01*
X46626Y129594D01*
X46753Y129567D01*
G01X46506Y132913D02*
X46538Y132816D01*
X46626Y132744D01*
X46753Y132717D01*
G01X46506Y136063D02*
X46538Y135966D01*
X46626Y135894D01*
X46753Y135866D01*
G01X46506Y139213D02*
X46538Y139115D01*
X46626Y139043D01*
X46753Y139016D01*
G01X46506Y142362D02*
X46538Y142265D01*
X46626Y142193D01*
X46753Y142165D01*
G01X50987Y136358D02*
X50909Y136949D01*
G01X50987Y141358D02*
X50909Y141949D01*
G01X43531Y134382D02*
Y139764D01*
G01X43701D02*
Y170768D01*
G01X46279Y135965D02*
Y136358D01*
G01X46369Y140965D02*
Y141358D01*
G01X46496Y121592D02*
Y122576D01*
G01Y124742D02*
Y125726D01*
G01Y127891D02*
Y128876D01*
G01Y131041D02*
Y132025D01*
G01X46506Y142756D02*
Y142362D01*
G01Y139606D02*
Y139213D01*
G01Y133307D02*
Y132913D01*
G01Y136457D02*
Y136063D01*
G01Y130157D02*
Y129764D01*
G01Y127008D02*
Y126614D01*
G01Y123858D02*
Y123465D01*
G01X48989Y133406D02*
Y134587D01*
G01X50720Y128876D02*
Y127891D01*
G01Y132025D02*
Y131041D01*
G01Y125726D02*
Y124742D01*
G01Y122576D02*
Y121592D01*
G01X50987Y135965D02*
Y136358D01*
G01Y140965D02*
Y141358D01*
G01X50720Y131041D02*
Y131003D01*
X50718Y130966D01*
X50715Y130932D01*
X50711Y130902D01*
X50706Y130878D01*
X50700Y130859D01*
X50694Y130848D01*
X50687Y130844D01*
G01X50720Y127891D02*
Y127853D01*
X50718Y127817D01*
X50715Y127783D01*
X50711Y127752D01*
X50706Y127728D01*
X50700Y127710D01*
X50694Y127698D01*
X50687Y127694D01*
G01X50720Y124742D02*
Y124704D01*
X50718Y124667D01*
X50715Y124633D01*
X50711Y124603D01*
X50706Y124578D01*
X50700Y124560D01*
X50694Y124549D01*
X50687Y124545D01*
G01X50720Y121592D02*
Y121554D01*
X50718Y121517D01*
X50715Y121483D01*
X50711Y121453D01*
X50706Y121429D01*
X50700Y121411D01*
X50694Y121399D01*
X50687Y121395D01*
G01X50987Y140965D02*
X50909Y140374D01*
G01X50987Y135965D02*
X50909Y135374D01*
G01X46684Y136949D02*
X46548Y136752D01*
X46413Y136556D01*
X46279Y136358D01*
G01X46784Y141949D02*
X46644Y141753D01*
X46506Y141556D01*
X46369Y141358D01*
G01X71218Y167894D02*
X71480Y167808D01*
G01X68779Y165676D02*
X69128Y165505D01*
G01X80323Y176925D02*
X80040Y177103D01*
X79853Y177368D01*
X79786Y177670D01*
X79850Y177970D01*
X80036Y178237D01*
X80321Y178419D01*
X80672Y178484D01*
G01X81020Y178419D02*
X81303Y178241D01*
X81490Y177976D01*
X81557Y177674D01*
X81493Y177374D01*
X81307Y177107D01*
X81022Y176926D01*
X80672Y176860D01*
G01X85490Y176925D02*
X85207Y177103D01*
X85020Y177368D01*
X84953Y177670D01*
X85018Y177970D01*
X85203Y178237D01*
X85489Y178419D01*
X85839Y178484D01*
G01X86188Y178419D02*
X86470Y178241D01*
X86657Y177976D01*
X86724Y177674D01*
X86660Y177374D01*
X86475Y177107D01*
X86189Y176926D01*
X85839Y176860D01*
G01X75145Y176929D02*
X74865Y177110D01*
G01X69215Y166017D02*
X68953Y166187D01*
G01X80249Y179226D02*
X79888Y179462D01*
X79650Y179813D01*
X79565Y180216D01*
X79647Y180618D01*
X79883Y180970D01*
X80247Y181211D01*
X80672Y181295D01*
G01X81094Y181211D02*
X81455Y180975D01*
X81693Y180625D01*
X81779Y180222D01*
X81696Y179819D01*
X81460Y179467D01*
X81096Y179227D01*
X80672Y179142D01*
G01X85416Y179226D02*
X85056Y179462D01*
X84817Y179813D01*
X84732Y180216D01*
X84814Y180618D01*
X85051Y180970D01*
X85414Y181211D01*
X85839Y181295D01*
G01X86262Y181211D02*
X86622Y180975D01*
X86861Y180625D01*
X86946Y180222D01*
X86864Y179819D01*
X86627Y179467D01*
X86264Y179227D01*
X85839Y179142D01*
G01X75492Y176860D02*
X75144Y176930D01*
G01X71654Y168320D02*
X71306Y168406D01*
G01X79474Y178771D02*
X79022Y179211D01*
X78752Y179747D01*
X78682Y180317D01*
X78824Y180881D01*
X79170Y181406D01*
X79698Y181799D01*
X80340Y182003D01*
X81019Y182000D01*
X81659Y181792D01*
X82182Y181396D01*
X82524Y180872D01*
X82662Y180311D01*
X82590Y179744D01*
X82320Y179209D01*
G01X84641Y178771D02*
X84189Y179211D01*
X83919Y179747D01*
X83849Y180317D01*
X83991Y180881D01*
X84337Y181406D01*
X84865Y181799D01*
X85507Y182003D01*
X86187Y182000D01*
X86827Y181792D01*
X87350Y181396D01*
X87691Y180872D01*
X87829Y180311D01*
X87757Y179744D01*
X87487Y179209D01*
G01X68430Y166017D02*
X68779Y165676D01*
G01X72002Y167979D02*
X71654Y168320D01*
G01X81869Y178771D02*
X82192Y178352D01*
X82355Y177868D01*
X82333Y177363D01*
X82130Y176887D01*
X81763Y176483D01*
X81257Y176216D01*
X80666Y176122D01*
X80077Y176219D01*
X79574Y176488D01*
X79210Y176892D01*
X79009Y177370D01*
X78989Y177875D01*
X79154Y178356D01*
X79474Y178771D01*
G01X87037D02*
X87359Y178352D01*
X87522Y177868D01*
X87500Y177363D01*
X87297Y176887D01*
X86930Y176483D01*
X86424Y176216D01*
X85833Y176122D01*
X85244Y176219D01*
X84742Y176488D01*
X84377Y176892D01*
X84176Y177370D01*
X84157Y177875D01*
X84321Y178356D01*
X84641Y178771D01*
G01X52529Y166949D02*
X52956Y166358D01*
G01X74724Y165374D02*
X81890D01*
G01X69128Y165505D02*
X69563D01*
G01X69476Y166017D02*
X69215D01*
G01X74724Y166949D02*
X81890D01*
G01X82854Y167126D02*
X74783D01*
G01X77756Y167146D02*
X76772D01*
G01X77756Y167539D02*
X76772D01*
G01X78346Y167579D02*
X87331D01*
G01X77756Y167736D02*
X76772D01*
G01X71044Y167894D02*
X71218D01*
G01X71306Y168406D02*
X70957D01*
G01X74331Y169193D02*
X64961D01*
G01X74331Y169567D02*
X94488D01*
G01X64646Y169783D02*
X71181D01*
G01X74331Y170965D02*
X64961D01*
G01X93696Y172146D02*
X73228D01*
G01X79328Y172539D02*
X73228D01*
G01X79328Y172598D02*
X73228D01*
G01X70866Y173091D02*
X94488D01*
G01Y175531D02*
X70866D01*
G01X68565Y176122D02*
X72404D01*
G01X89013D02*
X92852D01*
G01Y176860D02*
X89899D01*
G01X72404D02*
X69451D01*
G01X70866Y177500D02*
X94488D01*
G01X77202Y177820D02*
X76390D01*
G01X94488Y181280D02*
X70866D01*
G01X73585Y181289D02*
X76464D01*
G01X92113Y182028D02*
X91228D01*
G01X77497D02*
X73585D01*
G01X71666D02*
X70780D01*
G01X81024Y186004D02*
X64646D01*
G01X75000Y188701D02*
X70669D01*
G01X75625Y189488D02*
X70044D01*
G01Y191063D02*
X75625D01*
G01X70669Y191850D02*
X75000D01*
G01X74866Y177110D02*
X74683Y177374D01*
X74619Y177674D01*
X74683Y177970D01*
G01X68953Y166187D02*
X68779Y166443D01*
G01X71480Y167808D02*
X71654Y167552D01*
G01X79583Y172146D02*
X79328Y172539D01*
G01X68256Y166358D02*
X68430Y166017D01*
G01X72176Y167638D02*
X72002Y167979D01*
G01X51839Y166949D02*
X52112Y166358D01*
G01X70957Y168406D02*
X70608Y168320D01*
G01X69302Y168661D02*
X68953Y168576D01*
G01X71654Y167552D02*
X71741Y167296D01*
G01X68779Y166443D02*
X68692Y166785D01*
G01X72264Y167296D02*
X72176Y167638D01*
G01X68169Y166785D02*
X68256Y166358D01*
G01X52112D02*
Y165965D01*
G01X52956Y166358D02*
Y165965D01*
G01X64646Y169783D02*
Y196181D01*
G01X64961Y170965D02*
Y169193D01*
G01X66929Y183248D02*
Y174902D01*
G01X68169Y167467D02*
Y166785D01*
G01X68565Y176786D02*
Y176122D01*
G01X68692Y166785D02*
Y167467D01*
G01X69302Y168150D02*
Y168661D01*
G01X69998Y167296D02*
Y166785D01*
G01X70044Y191063D02*
Y189488D01*
G01X70079D02*
Y191063D01*
G01X70103Y189488D02*
Y191063D01*
G01X70521Y166785D02*
Y167296D01*
G01X70866Y181280D02*
Y177500D01*
G01Y173091D02*
Y175531D01*
G01X71306Y166273D02*
Y165761D01*
G01X71426Y191063D02*
Y189488D01*
G01X71741Y167296D02*
Y166785D01*
G01X71796Y189488D02*
Y191063D01*
G01X72264Y166870D02*
Y167296D01*
G01X72404Y176122D02*
Y176860D01*
G01X73585Y182028D02*
Y181289D01*
G01X73873Y191063D02*
Y189488D01*
G01X74243D02*
Y191063D01*
G01X75567D02*
Y189488D01*
G01X75591Y191063D02*
Y189488D01*
G01X75625D02*
Y191063D01*
G01X75787Y166949D02*
Y165374D01*
G01X76390Y177820D02*
Y177672D01*
G01X76772Y172598D02*
Y174902D01*
G01X77202Y177672D02*
Y177820D01*
G01X77497Y181585D02*
Y182028D01*
G01X78740Y166949D02*
Y165374D01*
G01X79328Y172539D02*
Y172598D01*
G01X79967Y174902D02*
Y172146D01*
G01X81024Y196181D02*
Y183248D01*
G01X81890Y165374D02*
Y166949D01*
G01X87841Y174902D02*
Y172146D01*
G01X89013Y176786D02*
Y176122D01*
G01X92852D02*
Y176860D01*
G01X93696Y169567D02*
Y172146D01*
G01X94170Y169567D02*
Y174902D01*
G01X94488Y169567D02*
Y183248D01*
G01X77202Y177672D02*
X77115Y177195D01*
X76868Y176753D01*
X76480Y176401D01*
X75973Y176181D01*
X75395Y176125D01*
X74832Y176247D01*
X74356Y176530D01*
X74017Y176934D01*
X73837Y177391D01*
X73822Y177871D01*
X73979Y178342D01*
X74294Y178759D01*
G01X68256Y167894D02*
X68169Y167467D01*
G01X70434Y166358D02*
X70521Y166785D01*
G01X72176Y166443D02*
X72264Y166870D01*
G01X76323Y177367D02*
X76390Y177672D01*
G01X68692Y167467D02*
X68779Y167808D01*
G01X70086Y167638D02*
X69998Y167296D01*
G01Y166785D02*
X69911Y166443D01*
G01X70521Y167296D02*
X70608Y167552D01*
G01X71741Y166785D02*
X71654Y166529D01*
G01X52112Y165965D02*
X51839Y165374D01*
G01X70260Y167979D02*
X70086Y167638D01*
G01X70260Y166017D02*
X70434Y166358D01*
G01X68518Y168320D02*
X68256Y167894D01*
G01X70608Y167552D02*
X70783Y167808D01*
G01X69911Y166443D02*
X69737Y166187D01*
G01X74865Y178234D02*
X74682Y177969D01*
X74619Y177671D01*
X74683Y177373D01*
G01X76133Y177100D02*
X76323Y177368D01*
G01X52529Y165374D02*
X52956Y165965D01*
G01X74294Y178759D02*
X73956Y178297D01*
X73811Y177779D01*
X73871Y177261D01*
X74122Y176777D01*
X74559Y176382D01*
X75132Y176159D01*
X75767Y176140D01*
X76351Y176326D01*
X76806Y176679D01*
X77098Y177151D01*
X77202Y177672D01*
G01X71915Y166102D02*
X72176Y166443D01*
G01X79474Y178771D02*
X79151Y178352D01*
X78989Y177868D01*
X79010Y177363D01*
X79213Y176887D01*
X79580Y176483D01*
X80086Y176216D01*
X80678Y176122D01*
X81267Y176219D01*
X81769Y176488D01*
X82133Y176892D01*
X82334Y177370D01*
X82354Y177875D01*
X82190Y178356D01*
X81869Y178771D01*
G01X84641D02*
X84319Y178352D01*
X84156Y177868D01*
X84178Y177363D01*
X84381Y176887D01*
X84748Y176483D01*
X85254Y176216D01*
X85845Y176122D01*
X86434Y176219D01*
X86936Y176488D01*
X87300Y176892D01*
X87502Y177370D01*
X87521Y177875D01*
X87357Y178356D01*
X87037Y178771D01*
G01X68779Y167808D02*
X69040Y168064D01*
G01X70608Y168320D02*
X70260Y167979D01*
G01X69911Y165676D02*
X70260Y166017D01*
G01X71654Y166529D02*
X71480Y166358D01*
G01X76428Y179761D02*
X74865Y178234D01*
G01X81869Y178771D02*
X82321Y179211D01*
X82591Y179747D01*
X82661Y180317D01*
X82520Y180881D01*
X82173Y181406D01*
X81646Y181799D01*
X81003Y182003D01*
X80324Y182000D01*
X79684Y181792D01*
X79161Y181396D01*
X78820Y180872D01*
X78681Y180311D01*
X78753Y179744D01*
X79024Y179209D01*
G01X87037Y178771D02*
X87488Y179211D01*
X87759Y179747D01*
X87829Y180317D01*
X87687Y180881D01*
X87341Y181406D01*
X86813Y181799D01*
X86170Y182003D01*
X85491Y182000D01*
X84851Y181792D01*
X84328Y181396D01*
X83987Y180872D01*
X83849Y180311D01*
X83920Y179744D01*
X84191Y179209D01*
G01X75922Y180306D02*
X74294Y178759D01*
G01X71567Y165846D02*
X71915Y166102D01*
G01X80249Y181211D02*
X79888Y180975D01*
X79650Y180625D01*
X79565Y180222D01*
X79647Y179819D01*
X79883Y179467D01*
X80247Y179227D01*
X80672Y179142D01*
G01X81094Y179226D02*
X81455Y179462D01*
X81693Y179813D01*
X81779Y180216D01*
X81696Y180618D01*
X81460Y180970D01*
X81096Y181211D01*
X80672Y181295D01*
G01X85416Y181211D02*
X85056Y180975D01*
X84817Y180625D01*
X84732Y180222D01*
X84814Y179819D01*
X85051Y179467D01*
X85414Y179227D01*
X85839Y179142D01*
G01X86262Y179226D02*
X86622Y179462D01*
X86861Y179813D01*
X86946Y180216D01*
X86864Y180618D01*
X86627Y180970D01*
X86264Y181211D01*
X85839Y181295D01*
G01X69737Y166187D02*
X69476Y166017D01*
G01X80323Y178419D02*
X80040Y178241D01*
X79853Y177976D01*
X79786Y177674D01*
X79850Y177374D01*
X80036Y177107D01*
X80321Y176926D01*
X80672Y176860D01*
G01X81020Y176925D02*
X81303Y177103D01*
X81490Y177368D01*
X81557Y177670D01*
X81493Y177970D01*
X81307Y178237D01*
X81022Y178419D01*
X80672Y178484D01*
G01X85490Y178419D02*
X85207Y178241D01*
X85020Y177976D01*
X84953Y177674D01*
X85018Y177374D01*
X85203Y177107D01*
X85489Y176926D01*
X85839Y176860D01*
G01X86188Y176925D02*
X86470Y177103D01*
X86657Y177368D01*
X86724Y177670D01*
X86660Y177970D01*
X86475Y178237D01*
X86189Y178419D01*
X85839Y178484D01*
G01X76133Y177101D02*
X75846Y176922D01*
X75492Y176860D01*
G01X68953Y168576D02*
X68518Y168320D01*
G01X69563Y165505D02*
X69911Y165676D01*
G01X71480Y166358D02*
X71306Y166273D01*
G01X69040Y168064D02*
X69302Y168150D01*
G01X70783Y167808D02*
X71044Y167894D01*
G01X71306Y165761D02*
X71567Y165846D01*
G01X68565Y176786D02*
G03X70780Y182028I-7141J6107D01*
G01X69451Y176860D02*
G03X71666Y182028I-6937J6032D01*
G01X74331Y167343D02*
G03X74724Y166949I393J-1D01*
G01X76428Y179761D02*
G03X77498Y181585I-2810J2874D01*
G01X75922Y180306D02*
G03X76464Y181289I-1275J1344D01*
G01X70669Y191850D02*
G03Y188701I0J-1574D01*
G01X75000D02*
G03Y191850I0J1575D01*
G01X89013Y176786D02*
G03X91228Y182028I-7142J6107D01*
G01X89899Y176860D02*
G03X92113Y182028I-6938J6030D01*
G01X86614Y178464D02*
G03I-4528J0D01*
G01X85591D02*
G03I-3505J0D01*
G01X85433D02*
G03I-3347J0D01*
G01X84252D02*
G03I-2166J0D01*
G01X51351Y146102D02*
X51389Y146076D01*
X51417Y146004D01*
X51428Y145906D01*
G01X51351Y149252D02*
X51389Y149226D01*
X51417Y149154D01*
X51428Y149055D01*
G01X51351Y152402D02*
X51389Y152375D01*
X51417Y152303D01*
X51428Y152205D01*
G01X51351Y155551D02*
X51389Y155525D01*
X51417Y155453D01*
X51428Y155354D01*
G01X51351Y158701D02*
X51389Y158674D01*
X51417Y158602D01*
X51428Y158504D01*
G01X51351Y161850D02*
X51389Y161824D01*
X51417Y161752D01*
X51428Y161654D01*
G01X51351Y165000D02*
X51389Y164974D01*
X51417Y164902D01*
X51428Y164803D01*
G01X71567Y164311D02*
X70957Y164823D01*
G01X71654D02*
X72264Y164311D01*
G01X92717Y145315D02*
X85384D01*
G01X85237D02*
X73228D01*
G01X74724Y145374D02*
X81890D01*
G01X85237Y146102D02*
X73228D01*
G01X85384D02*
X92717D01*
G01X74724Y146949D02*
X81890D01*
G01X77756Y147146D02*
X76772D01*
G01X77756Y147539D02*
X76772D01*
G01X77756Y147736D02*
X76772D01*
G01X92717Y148465D02*
X85384D01*
G01X85237D02*
X73228D01*
G01X85237Y149252D02*
X73228D01*
G01X85384D02*
X92717D01*
G01X77756Y149587D02*
X76772D01*
G01X77756Y149783D02*
X76772D01*
G01X77756Y150177D02*
X76772D01*
G01X74724Y150374D02*
X81890D01*
G01X92717Y151614D02*
X85384D01*
G01X85237D02*
X73228D01*
G01X74724Y151949D02*
X81890D01*
G01X77756Y152146D02*
X76772D01*
G01X85237Y152402D02*
X73228D01*
G01X85384D02*
X92717D01*
G01X77756Y152539D02*
X76772D01*
G01X77756Y152736D02*
X76772D01*
G01X77756Y154587D02*
X76772D01*
G01X92717Y154764D02*
X85384D01*
G01X85237D02*
X73228D01*
G01X77756Y154783D02*
X76772D01*
G01X77756Y155177D02*
X76772D01*
G01X74724Y155374D02*
X81890D01*
G01X85237Y155551D02*
X73228D01*
G01X85384D02*
X92717D01*
G01X74724Y156949D02*
X81890D01*
G01X77756Y157146D02*
X76772D01*
G01X77756Y157539D02*
X76772D01*
G01X77756Y157736D02*
X76772D01*
G01X92717Y157913D02*
X85384D01*
G01X85237D02*
X73228D01*
G01X85237Y158701D02*
X73228D01*
G01X85384D02*
X92717D01*
G01X77756Y159587D02*
X76772D01*
G01X77756Y159783D02*
X76772D01*
G01X77756Y160177D02*
X76772D01*
G01X74724Y160374D02*
X81890D01*
G01X92717Y161063D02*
X85384D01*
G01X85237D02*
X73228D01*
G01X85237Y161850D02*
X73228D01*
G01X85384D02*
X92717D01*
G01X74724Y161949D02*
X81890D01*
G01X77756Y162146D02*
X76772D01*
G01X77756Y162539D02*
X76772D01*
G01X77756Y162736D02*
X76772D01*
G01X52529Y146949D02*
X52956Y146358D01*
G01X52529Y151949D02*
X52956Y151358D01*
G01X52529Y156949D02*
X52956Y156358D01*
G01X52529Y161949D02*
X52956Y161358D01*
G01X51802Y145315D02*
X51829Y145319D01*
X51855Y145330D01*
X51879Y145348D01*
X51900Y145372D01*
X51917Y145402D01*
X51930Y145436D01*
X51938Y145473D01*
X51941Y145512D01*
G01X51802Y148465D02*
X51829Y148468D01*
X51855Y148479D01*
X51879Y148497D01*
X51900Y148522D01*
X51917Y148552D01*
X51930Y148586D01*
X51938Y148622D01*
X51941Y148661D01*
G01X51802Y151614D02*
X51829Y151618D01*
X51855Y151629D01*
X51879Y151647D01*
X51900Y151672D01*
X51917Y151702D01*
X51930Y151735D01*
X51938Y151772D01*
X51941Y151811D01*
G01X51802Y154764D02*
X51829Y154767D01*
X51855Y154778D01*
X51879Y154796D01*
X51900Y154821D01*
X51917Y154851D01*
X51930Y154885D01*
X51938Y154922D01*
X51941Y154961D01*
G01X51802Y157913D02*
X51829Y157917D01*
X51855Y157928D01*
X51879Y157946D01*
X51900Y157971D01*
X51917Y158001D01*
X51930Y158035D01*
X51938Y158071D01*
X51941Y158110D01*
G01X51802Y161063D02*
X51829Y161067D01*
X51855Y161078D01*
X51879Y161096D01*
X51900Y161120D01*
X51917Y161150D01*
X51930Y161184D01*
X51938Y161221D01*
X51941Y161260D01*
G01X51802Y164213D02*
X51829Y164216D01*
X51855Y164227D01*
X51879Y164245D01*
X51900Y164270D01*
X51917Y164300D01*
X51930Y164334D01*
X51938Y164370D01*
X51941Y164409D01*
G01X72264Y163799D02*
X68169D01*
G01X92717Y164213D02*
X85384D01*
G01X85237D02*
X73228D01*
G01X68169Y164311D02*
X71567D01*
G01X77756Y164587D02*
X76772D01*
G01X77756Y164783D02*
X76772D01*
G01X70957Y164823D02*
X71654D01*
G01X85237Y165000D02*
X73228D01*
G01X85384D02*
X92717D01*
G01X74783Y165157D02*
X82854D01*
G01X77756Y165177D02*
X76772D01*
G01X51839Y146949D02*
X52112Y146358D01*
G01X51839Y151949D02*
X52112Y151358D01*
G01X51839Y156949D02*
X52112Y156358D01*
G01X51839Y161949D02*
X52112Y161358D01*
G01X51941Y145906D02*
X51938Y145944D01*
X51930Y145980D01*
X51917Y146014D01*
X51900Y146044D01*
X51879Y146069D01*
X51856Y146087D01*
X51830Y146098D01*
X51802Y146102D01*
G01X51941Y149055D02*
X51938Y149093D01*
X51930Y149130D01*
X51917Y149164D01*
X51900Y149194D01*
X51879Y149219D01*
X51856Y149237D01*
X51830Y149248D01*
X51802Y149252D01*
G01X51941Y152205D02*
X51938Y152243D01*
X51930Y152280D01*
X51917Y152313D01*
X51900Y152344D01*
X51879Y152368D01*
X51856Y152386D01*
X51830Y152398D01*
X51802Y152402D01*
G01X51941Y155354D02*
X51938Y155393D01*
X51930Y155429D01*
X51917Y155463D01*
X51900Y155493D01*
X51879Y155518D01*
X51856Y155536D01*
X51830Y155547D01*
X51802Y155551D01*
G01X51941Y158504D02*
X51938Y158542D01*
X51930Y158579D01*
X51917Y158613D01*
X51900Y158643D01*
X51879Y158667D01*
X51856Y158685D01*
X51830Y158697D01*
X51802Y158701D01*
G01X51941Y161654D02*
X51938Y161692D01*
X51930Y161728D01*
X51917Y161762D01*
X51900Y161793D01*
X51879Y161817D01*
X51856Y161835D01*
X51830Y161846D01*
X51802Y161850D01*
G01X51941Y164803D02*
X51938Y164841D01*
X51930Y164878D01*
X51917Y164912D01*
X51900Y164942D01*
X51879Y164967D01*
X51856Y164985D01*
X51830Y164996D01*
X51802Y165000D01*
G01X51428Y161654D02*
Y161260D01*
G01Y164803D02*
Y164409D01*
G01Y158504D02*
Y158110D01*
G01Y155354D02*
Y154961D01*
G01Y152205D02*
Y151811D01*
G01Y149055D02*
Y148661D01*
G01Y145906D02*
Y145512D01*
G01X51941D02*
Y145906D01*
G01Y148661D02*
Y149055D01*
G01Y154961D02*
Y155354D01*
G01Y151811D02*
Y152205D01*
G01Y158110D02*
Y158504D01*
G01Y161260D02*
Y161654D01*
G01Y164409D02*
Y164803D01*
G01X52112Y161358D02*
Y160965D01*
G01Y156358D02*
Y155965D01*
G01Y151358D02*
Y150965D01*
G01Y146358D02*
Y145965D01*
G01X52956Y161358D02*
Y160965D01*
G01Y156358D02*
Y155965D01*
G01Y151358D02*
Y150965D01*
G01Y146358D02*
Y145965D01*
G01X53118Y145512D02*
Y145906D01*
G01Y148661D02*
Y149055D01*
G01Y154961D02*
Y155354D01*
G01Y151811D02*
Y152205D01*
G01Y158110D02*
Y158504D01*
G01Y161260D02*
Y161654D01*
G01Y164409D02*
Y164803D01*
G01X68169Y163799D02*
Y164311D01*
G01X69213Y153366D02*
Y169783D01*
G01X72264Y164311D02*
Y163799D01*
G01X74783Y167126D02*
Y165157D01*
G01X75170Y165000D02*
Y164213D01*
G01Y161850D02*
Y161063D01*
G01Y155551D02*
Y154764D01*
G01Y158701D02*
Y157913D01*
G01Y152402D02*
Y151614D01*
G01Y149252D02*
Y148465D01*
G01Y146102D02*
Y145315D01*
G01X75197Y165000D02*
Y164213D01*
G01Y161850D02*
Y161063D01*
G01Y155551D02*
Y154764D01*
G01Y158701D02*
Y157913D01*
G01Y152402D02*
Y151614D01*
G01Y149252D02*
Y148465D01*
G01Y146102D02*
Y145315D01*
G01X75573Y165000D02*
Y164213D01*
G01Y161850D02*
Y161063D01*
G01Y155551D02*
Y154764D01*
G01Y158701D02*
Y157913D01*
G01Y152402D02*
Y151614D01*
G01Y149252D02*
Y148465D01*
G01Y146102D02*
Y145315D01*
G01X75787Y161949D02*
Y160374D01*
G01Y156949D02*
Y155374D01*
G01Y151949D02*
Y150374D01*
G01Y146949D02*
Y145374D01*
G01X76772Y167736D02*
Y164587D01*
G01Y162736D02*
Y159587D01*
G01Y157736D02*
Y154587D01*
G01Y152736D02*
Y149587D01*
G01X77756Y167736D02*
Y164587D01*
G01Y162736D02*
Y159587D01*
G01Y157736D02*
Y154587D01*
G01Y152736D02*
Y149587D01*
G01X78740Y161949D02*
Y160374D01*
G01Y156949D02*
Y155374D01*
G01Y151949D02*
Y150374D01*
G01Y146949D02*
Y145374D01*
G01X78935Y145315D02*
Y146102D01*
G01Y148465D02*
Y149252D01*
G01Y151614D02*
Y152402D01*
G01Y154764D02*
Y155551D01*
G01Y157913D02*
Y158701D01*
G01Y161063D02*
Y161850D01*
G01Y164213D02*
Y165000D01*
G01X80919Y145315D02*
Y146102D01*
G01Y148465D02*
Y149252D01*
G01Y151614D02*
Y152402D01*
G01Y154764D02*
Y155551D01*
G01Y157913D02*
Y158701D01*
G01Y161063D02*
Y161850D01*
G01Y164213D02*
Y165000D01*
G01X81890Y145374D02*
Y146949D01*
G01Y150374D02*
Y151949D01*
G01Y155374D02*
Y156949D01*
G01Y160374D02*
Y161949D01*
G01X82570Y165000D02*
Y164213D01*
G01Y161850D02*
Y161063D01*
G01Y155551D02*
Y154764D01*
G01Y158701D02*
Y157913D01*
G01Y152402D02*
Y151614D01*
G01Y149252D02*
Y148465D01*
G01Y146102D02*
Y145315D01*
G01X82854Y165157D02*
Y167126D01*
G01X84298Y146102D02*
Y148465D01*
G01Y149252D02*
Y151614D01*
G01Y152402D02*
Y154764D01*
G01Y155551D02*
Y157913D01*
G01Y158701D02*
Y161063D01*
G01Y161850D02*
Y164213D01*
G01Y165000D02*
Y167579D01*
G01X85237Y165000D02*
Y164213D01*
G01Y161850D02*
Y161063D01*
G01Y155551D02*
Y154764D01*
G01Y158701D02*
Y157913D01*
G01Y152402D02*
Y151614D01*
G01Y149252D02*
Y148465D01*
G01Y146102D02*
Y145315D01*
G01X85384Y165000D02*
Y164213D01*
G01Y161850D02*
Y161063D01*
G01Y155551D02*
Y154764D01*
G01Y158701D02*
Y157913D01*
G01Y152402D02*
Y151614D01*
G01Y149252D02*
Y148465D01*
G01Y146102D02*
Y145315D01*
G01X86976Y165000D02*
Y164213D01*
G01Y161850D02*
Y161063D01*
G01Y155551D02*
Y154764D01*
G01Y158701D02*
Y157913D01*
G01Y152402D02*
Y151614D01*
G01Y149252D02*
Y148465D01*
G01Y146102D02*
Y145315D01*
G01X87918D02*
Y146102D01*
G01Y148465D02*
Y149252D01*
G01Y151614D02*
Y152402D01*
G01Y154764D02*
Y155551D01*
G01Y157913D02*
Y158701D01*
G01Y161063D02*
Y161850D01*
G01Y164213D02*
Y165000D01*
G01X90754Y145315D02*
Y146102D01*
G01Y148465D02*
Y149252D01*
G01Y151614D02*
Y152402D01*
G01Y154764D02*
Y155551D01*
G01Y157913D02*
Y158701D01*
G01Y161063D02*
Y161850D01*
G01Y164213D02*
Y165000D01*
G01X90943D02*
Y164213D01*
G01Y161850D02*
Y161063D01*
G01Y155551D02*
Y154764D01*
G01Y158701D02*
Y157913D01*
G01Y152402D02*
Y151614D01*
G01Y149252D02*
Y148465D01*
G01Y146102D02*
Y145315D01*
G01X92717Y165000D02*
Y164213D01*
G01Y161850D02*
Y161063D01*
G01Y155551D02*
Y154764D01*
G01Y158701D02*
Y157913D01*
G01Y152402D02*
Y151614D01*
G01Y149252D02*
Y148465D01*
G01Y146102D02*
Y145315D01*
G01X51428Y161260D02*
X51417Y161161D01*
X51389Y161089D01*
X51351Y161063D01*
G01X51428Y158110D02*
X51417Y158012D01*
X51389Y157940D01*
X51351Y157913D01*
G01X51428Y145512D02*
X51417Y145413D01*
X51389Y145341D01*
X51351Y145315D01*
G01X52112Y160965D02*
X51839Y160374D01*
G01X52112Y155965D02*
X51839Y155374D01*
G01X52112Y150965D02*
X51839Y150374D01*
G01X52112Y145965D02*
X51839Y145374D01*
G01X52529Y160374D02*
X52956Y160965D01*
G01X52529Y155374D02*
X52956Y155965D01*
G01X52529Y150374D02*
X52956Y150965D01*
G01X52529Y145374D02*
X52956Y145965D01*
G01X51351Y164213D02*
X51389Y164239D01*
X51417Y164311D01*
X51428Y164409D01*
G01X51351Y154764D02*
X51389Y154790D01*
X51417Y154862D01*
X51428Y154961D01*
G01X51351Y151614D02*
X51389Y151641D01*
X51417Y151713D01*
X51428Y151811D01*
G01X51351Y148465D02*
X51389Y148491D01*
X51417Y148563D01*
X51428Y148661D01*
G01X74331Y162343D02*
G03X74724Y161949I393J-1D01*
G01Y160374D02*
G03X74331Y159980I1J-394D01*
G01Y152343D02*
G03X74724Y151949I393J-1D01*
G01Y150374D02*
G03X74331Y149980I1J-394D01*
G01Y157343D02*
G03X74724Y156949I393J-1D01*
G01Y155374D02*
G03X74331Y154980I1J-394D01*
G01Y147343D02*
G03X74724Y146949I393J-1D01*
G01Y165374D02*
G03X74331Y164980I1J-394D01*
G01X42520Y171949D02*
X44488Y169980D01*
G01X46369Y165965D02*
X46506Y165767D01*
X46644Y165570D01*
X46784Y165374D01*
G01D02*
X52529D01*
G01X46369Y165965D02*
X52956D01*
G01Y166358D02*
X46369D01*
G01X52529Y166949D02*
X46784D01*
G01X62992Y169980D02*
X44488D01*
G01X73228Y170374D02*
X42520D01*
G01Y174902D02*
X39236D01*
G01X44488D02*
X94488D01*
G01X66929Y182067D02*
X40551D01*
G01Y183248D02*
X94488D01*
G01X40492Y182526D02*
X40547Y182141D01*
G01X50987Y166358D02*
X50909Y166949D01*
G01X40551Y182067D02*
Y174902D01*
G01X46369Y165965D02*
Y166358D01*
G01X50987Y165965D02*
Y166358D01*
G01Y165965D02*
X50909Y165374D01*
G01X40519Y183217D02*
X40462Y183077D01*
X40457Y182837D01*
G01X40519Y183217D02*
X40463Y183082D01*
X40456Y182847D01*
X40493Y182518D01*
G01X46784Y166949D02*
X46644Y166753D01*
X46506Y166556D01*
X46369Y166358D01*
G01X44488Y174902D02*
X42520Y172933D01*
G01X46753Y145315D02*
X52838D01*
G01X46784Y145374D02*
X52529D01*
G01X53118Y145512D02*
X46506D01*
G01Y145906D02*
X53118D01*
G01X46369Y145965D02*
X52956D01*
G01X46753Y146102D02*
X52838D01*
G01X52956Y146358D02*
X46369D01*
G01X52529Y146949D02*
X46784D01*
G01X46753Y148465D02*
X52838D01*
G01X53118Y148661D02*
X46506D01*
G01Y149055D02*
X53118D01*
G01X46753Y149252D02*
X52838D01*
G01X46784Y150374D02*
X52529D01*
G01X46369Y150965D02*
X52956D01*
G01X71181Y151004D02*
X44488D01*
G01X52956Y151358D02*
X46369D01*
G01X46753Y151614D02*
X52838D01*
G01X53118Y151811D02*
X46506D01*
G01X52529Y151949D02*
X46784D01*
G01X46506Y152205D02*
X53118D01*
G01X46753Y152402D02*
X52838D01*
G01X44488Y153366D02*
X71181D01*
G01X46753Y154764D02*
X52838D01*
G01X53118Y154961D02*
X46506D01*
G01Y155354D02*
X53118D01*
G01X46784Y155374D02*
X52529D01*
G01X46753Y155551D02*
X52838D01*
G01X46369Y155965D02*
X52956D01*
G01Y156358D02*
X46369D01*
G01X52529Y156949D02*
X46784D01*
G01X46753Y157913D02*
X52838D01*
G01X53118Y158110D02*
X46506D01*
G01Y158504D02*
X53118D01*
G01X46753Y158701D02*
X52838D01*
G01X46784Y160374D02*
X52529D01*
G01X46369Y160965D02*
X52956D01*
G01X46753Y161063D02*
X52838D01*
G01X53118Y161260D02*
X46506D01*
G01X52956Y161358D02*
X46369D01*
G01X46506Y161654D02*
X53118D01*
G01X46753Y161850D02*
X52838D01*
G01X52529Y161949D02*
X46784D01*
G01X46369Y145965D02*
X46506Y145767D01*
X46644Y145570D01*
X46784Y145374D01*
G01X46369Y150965D02*
X46506Y150767D01*
X46644Y150570D01*
X46784Y150374D01*
G01X46369Y155965D02*
X46506Y155767D01*
X46644Y155570D01*
X46784Y155374D01*
G01X46369Y160965D02*
X46506Y160767D01*
X46644Y160570D01*
X46784Y160374D01*
G01X46753Y164213D02*
X52838D01*
G01X53118Y164409D02*
X46506D01*
G01Y164803D02*
X53118D01*
G01X46753Y165000D02*
X52838D01*
G01X46753Y146102D02*
X46626Y146074D01*
X46537Y146002D01*
X46506Y145906D01*
G01X46753Y149252D02*
X46626Y149224D01*
X46537Y149151D01*
X46506Y149055D01*
G01X46753Y152402D02*
X46626Y152374D01*
X46537Y152301D01*
X46506Y152205D01*
G01X46753Y155551D02*
X46626Y155523D01*
X46537Y155450D01*
X46506Y155354D01*
G01X46753Y158701D02*
X46626Y158673D01*
X46537Y158600D01*
X46506Y158504D01*
G01X46753Y161850D02*
X46626Y161822D01*
X46537Y161750D01*
X46506Y161654D01*
G01X46753Y165000D02*
X46626Y164972D01*
X46537Y164899D01*
X46506Y164803D01*
G01Y145512D02*
X46538Y145415D01*
X46626Y145343D01*
X46753Y145315D01*
G01X46506Y148661D02*
X46538Y148564D01*
X46626Y148492D01*
X46753Y148465D01*
G01X46506Y151811D02*
X46538Y151714D01*
X46626Y151642D01*
X46753Y151614D01*
G01X46506Y154961D02*
X46538Y154863D01*
X46626Y154791D01*
X46753Y154764D01*
G01X46506Y158110D02*
X46538Y158013D01*
X46626Y157941D01*
X46753Y157913D01*
G01X46506Y161260D02*
X46538Y161163D01*
X46626Y161091D01*
X46753Y161063D01*
G01X46506Y164409D02*
X46538Y164312D01*
X46626Y164240D01*
X46753Y164213D01*
G01X50987Y146358D02*
X50909Y146949D01*
G01X50987Y151358D02*
X50909Y151949D01*
G01X50987Y156358D02*
X50909Y156949D01*
G01X50987Y161358D02*
X50909Y161949D01*
G01X46369Y145965D02*
Y146358D01*
G01Y150965D02*
Y151358D01*
G01Y155965D02*
Y156358D01*
G01Y160965D02*
Y161358D01*
G01X46506Y161654D02*
Y161260D01*
G01Y164803D02*
Y164409D01*
G01Y158504D02*
Y158110D01*
G01Y155354D02*
Y154961D01*
G01Y152205D02*
Y151811D01*
G01Y149055D02*
Y148661D01*
G01Y145906D02*
Y145512D01*
G01X50987Y145965D02*
Y146358D01*
G01Y150965D02*
Y151358D01*
G01Y155965D02*
Y156358D01*
G01Y160965D02*
Y161358D01*
G01Y160965D02*
X50909Y160374D01*
G01X50987Y155965D02*
X50909Y155374D01*
G01X50987Y150965D02*
X50909Y150374D01*
G01X50987Y145965D02*
X50909Y145374D01*
G01X46784Y161949D02*
X46644Y161753D01*
X46506Y161556D01*
X46369Y161358D01*
G01X46784Y156949D02*
X46644Y156753D01*
X46506Y156556D01*
X46369Y156358D01*
G01X46784Y151949D02*
X46644Y151753D01*
X46506Y151556D01*
X46369Y151358D01*
G01X46784Y146949D02*
X46644Y146753D01*
X46506Y146556D01*
X46369Y146358D01*
G01X81024Y196181D02*
X64646D01*
G01X69685Y205709D02*
X75984D01*
G01X71260Y206004D02*
X68110D01*
G01X74409D02*
X77559D01*
G01X69789Y206480D02*
X69696D01*
G01Y207228D02*
X69789D01*
G01X77559Y207972D02*
X74409D01*
G01X68110D02*
X71260D01*
G01X77559Y208563D02*
X74409D01*
G01X68110D02*
X71260D01*
G01Y210531D02*
X68110D01*
G01X74409D02*
X77559D01*
G01X75984Y210827D02*
X69685D01*
G01X68110Y210531D02*
Y208563D01*
G01Y206004D02*
Y207972D01*
G01X69602Y206989D02*
Y207117D01*
G01X69685Y210827D02*
Y210236D01*
G01Y209055D02*
Y207480D01*
G01Y206299D02*
Y205709D01*
G01X69696Y206480D02*
Y207101D01*
G01X69789Y207228D02*
Y206480D01*
G01X70669Y205709D02*
Y210827D01*
G01X70866D02*
Y205709D01*
G01X71260Y207972D02*
Y206004D01*
G01Y208563D02*
Y210531D01*
G01X74409Y207972D02*
Y206004D01*
G01Y208563D02*
Y210531D01*
G01X74803Y210827D02*
Y205709D01*
G01X75000D02*
Y210827D01*
G01X75984Y205709D02*
Y206299D01*
G01Y210236D02*
Y210827D01*
G01Y207480D02*
Y209055D01*
G01X77559Y210531D02*
Y208563D01*
G01Y206004D02*
Y207972D01*
G01X69602Y207117D02*
X69696Y207228D01*
G01Y207101D02*
X69602Y206989D01*
G01X75984Y210236D02*
G03Y209055I0J-590D01*
G01X69685D02*
G03Y210236I0J590D01*
G01Y206299D02*
G03Y207480I0J591D01*
G01X75984D02*
G03Y206299I0J-591D01*
G01X44494Y281491D02*
G03I-985J0D01*
G01X39373Y277358D02*
G03X40499Y274602I3937J0D01*
G01X49218Y267712D02*
Y281491D01*
G01Y267712D02*
Y281491D01*
G01Y267712D02*
Y281491D01*
G01X47249Y279129D02*
Y281491D01*
G01X41344Y279129D02*
Y281491D01*
G01X39375D02*
Y279129D01*
G01X39373Y277358D02*
Y281491D01*
G01X39375Y279129D02*
X47249D01*
G01X43149Y286511D02*
G03I-985J0D01*
G01X51351Y466575D02*
X51389Y466548D01*
X51417Y466476D01*
X51428Y466378D01*
G01X51351Y469724D02*
X51389Y469698D01*
X51417Y469626D01*
X51428Y469528D01*
G01X51351Y472874D02*
X51389Y472848D01*
X51417Y472776D01*
X51428Y472677D01*
G01X51351Y476024D02*
X51389Y475997D01*
X51417Y475925D01*
X51428Y475827D01*
G01X51351Y479173D02*
X51389Y479147D01*
X51417Y479075D01*
X51428Y478976D01*
G01X51351Y482323D02*
X51389Y482296D01*
X51417Y482224D01*
X51428Y482126D01*
G01X52529Y467461D02*
X52956Y466870D01*
G01X52529Y472461D02*
X52956Y471870D01*
G01X52529Y477461D02*
X52956Y476870D01*
G01X52529Y482461D02*
X52956Y481870D01*
G01X51839Y467461D02*
X52112Y466870D01*
G01X51839Y472461D02*
X52112Y471870D01*
G01X51839Y477461D02*
X52112Y476870D01*
G01X51839Y482461D02*
X52112Y481870D01*
G01X77756Y465295D02*
X76772D01*
G01X77756Y465689D02*
X76772D01*
G01X92717Y465787D02*
X85384D01*
G01X85237D02*
X73228D01*
G01X74724Y465886D02*
X81890D01*
G01X85237Y466575D02*
X73228D01*
G01X85384D02*
X92717D01*
G01X74724Y467461D02*
X81890D01*
G01X77756Y467657D02*
X76772D01*
G01X77756Y468051D02*
X76772D01*
G01X77756Y468248D02*
X76772D01*
G01X92717Y468937D02*
X85384D01*
G01X85237D02*
X73228D01*
G01X85237Y469724D02*
X73228D01*
G01X85384D02*
X92717D01*
G01X77756Y470098D02*
X76772D01*
G01X51941Y466378D02*
X51938Y466416D01*
X51930Y466453D01*
X51917Y466487D01*
X51900Y466517D01*
X51879Y466541D01*
X51856Y466559D01*
X51830Y466571D01*
X51802Y466575D01*
G01X51941Y469528D02*
X51938Y469566D01*
X51930Y469602D01*
X51917Y469636D01*
X51900Y469667D01*
X51879Y469691D01*
X51856Y469709D01*
X51830Y469720D01*
X51802Y469724D01*
G01X51941Y472677D02*
X51938Y472715D01*
X51930Y472752D01*
X51917Y472786D01*
X51900Y472816D01*
X51879Y472841D01*
X51856Y472859D01*
X51830Y472870D01*
X51802Y472874D01*
G01X51941Y475827D02*
X51938Y475865D01*
X51930Y475902D01*
X51917Y475935D01*
X51900Y475966D01*
X51879Y475990D01*
X51856Y476008D01*
X51830Y476020D01*
X51802Y476024D01*
G01X51941Y478976D02*
X51938Y479015D01*
X51930Y479051D01*
X51917Y479085D01*
X51900Y479115D01*
X51879Y479140D01*
X51856Y479158D01*
X51830Y479169D01*
X51802Y479173D01*
G01X51941Y482126D02*
X51938Y482164D01*
X51930Y482201D01*
X51917Y482235D01*
X51900Y482265D01*
X51879Y482289D01*
X51856Y482307D01*
X51830Y482319D01*
X51802Y482323D01*
G01X51428Y482126D02*
Y481732D01*
G01Y478976D02*
Y478583D01*
G01Y475827D02*
Y475433D01*
G01Y472677D02*
Y472283D01*
G01Y469528D02*
Y469134D01*
G01Y466378D02*
Y465984D01*
G01X51941D02*
Y466378D01*
G01Y472283D02*
Y472677D01*
G01Y469134D02*
Y469528D01*
G01Y475433D02*
Y475827D01*
G01Y481732D02*
Y482126D01*
G01Y478583D02*
Y478976D01*
G01X52112Y481870D02*
Y481476D01*
G01Y476870D02*
Y476476D01*
G01Y471870D02*
Y471476D01*
G01Y466870D02*
Y466476D01*
G01X52956Y481870D02*
Y481476D01*
G01Y476870D02*
Y476476D01*
G01Y471870D02*
Y471476D01*
G01Y466870D02*
Y466476D01*
G01X53118Y465984D02*
Y466378D01*
G01Y472283D02*
Y472677D01*
G01Y469134D02*
Y469528D01*
G01Y475433D02*
Y475827D01*
G01Y481732D02*
Y482126D01*
G01Y478583D02*
Y478976D01*
G01X51802Y465787D02*
X51829Y465791D01*
X51855Y465802D01*
X51879Y465820D01*
X51900Y465845D01*
X51917Y465875D01*
X51930Y465909D01*
X51938Y465945D01*
X51941Y465984D01*
G01X51802Y468937D02*
X51829Y468941D01*
X51855Y468952D01*
X51879Y468970D01*
X51900Y468994D01*
X51917Y469024D01*
X51930Y469058D01*
X51938Y469095D01*
X51941Y469134D01*
G01X51802Y472087D02*
X51829Y472090D01*
X51855Y472101D01*
X51879Y472119D01*
X51900Y472144D01*
X51917Y472174D01*
X51930Y472208D01*
X51938Y472244D01*
X51941Y472283D01*
G01X51802Y475236D02*
X51829Y475240D01*
X51855Y475251D01*
X51879Y475269D01*
X51900Y475294D01*
X51917Y475324D01*
X51930Y475357D01*
X51938Y475394D01*
X51941Y475433D01*
G01X51802Y478386D02*
X51829Y478389D01*
X51855Y478400D01*
X51879Y478419D01*
X51900Y478443D01*
X51917Y478473D01*
X51930Y478507D01*
X51938Y478544D01*
X51941Y478583D01*
G01X77756Y470295D02*
X76772D01*
G01X77756Y470689D02*
X76772D01*
G01X74724Y470886D02*
X81890D01*
G01X92717Y472087D02*
X85384D01*
G01X85237D02*
X73228D01*
G01X74724Y472461D02*
X81890D01*
G01X77756Y472657D02*
X76772D01*
G01X85237Y472874D02*
X73228D01*
G01X85384D02*
X92717D01*
G01X77756Y473051D02*
X76772D01*
G01X77756Y473248D02*
X76772D01*
G01X77756Y475098D02*
X76772D01*
G01X92717Y475236D02*
X85384D01*
G01X85237D02*
X73228D01*
G01X77756Y475295D02*
X76772D01*
G01X77756Y475689D02*
X76772D01*
G01X74724Y475886D02*
X81890D01*
G01X85237Y476024D02*
X73228D01*
G01X85384D02*
X92717D01*
G01X74724Y477461D02*
X81890D01*
G01X77756Y477657D02*
X76772D01*
G01X77756Y478051D02*
X76772D01*
G01X77756Y478248D02*
X76772D01*
G01X92717Y478386D02*
X85384D01*
G01X85237D02*
X73228D01*
G01X85237Y479173D02*
X73228D01*
G01X85384D02*
X92717D01*
G01X77756Y480098D02*
X76772D01*
G01X77756Y480295D02*
X76772D01*
G01X77756Y480689D02*
X76772D01*
G01X74724Y480886D02*
X81890D01*
G01X92717Y481535D02*
X85384D01*
G01X85237D02*
X73228D01*
G01X85237Y482323D02*
X73228D01*
G01X85384D02*
X92717D01*
G01X74724Y482461D02*
X81890D01*
G01X77756Y482657D02*
X76772D01*
G01X77756Y483051D02*
X76772D01*
G01X77756Y483248D02*
X76772D01*
G01X69213Y498366D02*
Y481831D01*
G01X75170Y479173D02*
Y478386D01*
G01Y482323D02*
Y481535D01*
G01Y476024D02*
Y475236D01*
G01Y469724D02*
Y468937D01*
G01Y472874D02*
Y472087D01*
G01Y466575D02*
Y465787D01*
G01X75197Y479173D02*
Y478386D01*
G01Y482323D02*
Y481535D01*
G01Y476024D02*
Y475236D01*
G01Y469724D02*
Y468937D01*
G01Y472874D02*
Y472087D01*
G01Y466575D02*
Y465787D01*
G01X75573Y479173D02*
Y478386D01*
G01Y482323D02*
Y481535D01*
G01Y476024D02*
Y475236D01*
G01Y469724D02*
Y468937D01*
G01Y472874D02*
Y472087D01*
G01Y466575D02*
Y465787D01*
G01X75787Y482461D02*
Y480886D01*
G01Y477461D02*
Y475886D01*
G01Y472461D02*
Y470886D01*
G01Y467461D02*
Y465886D01*
G01X76772Y483248D02*
Y480098D01*
G01Y478248D02*
Y475098D01*
G01Y473248D02*
Y470098D01*
G01X77756Y483248D02*
Y480098D01*
G01Y478248D02*
Y475098D01*
G01Y473248D02*
Y470098D01*
G01X78740Y482461D02*
Y480886D01*
G01Y477461D02*
Y475886D01*
G01Y472461D02*
Y470886D01*
G01Y467461D02*
Y465886D01*
G01X78935Y465787D02*
Y466575D01*
G01Y468937D02*
Y469724D01*
G01Y472087D02*
Y472874D01*
G01Y475236D02*
Y476024D01*
G01Y478386D02*
Y479173D01*
G01Y481535D02*
Y482323D01*
G01X80919Y465787D02*
Y466575D01*
G01Y468937D02*
Y469724D01*
G01Y472087D02*
Y472874D01*
G01Y475236D02*
Y476024D01*
G01Y478386D02*
Y479173D01*
G01Y481535D02*
Y482323D01*
G01X81890Y465886D02*
Y467461D01*
G01Y470886D02*
Y472461D01*
G01Y475886D02*
Y477461D01*
G01Y480886D02*
Y482461D01*
G01X82570Y479173D02*
Y478386D01*
G01Y482323D02*
Y481535D01*
G01Y476024D02*
Y475236D01*
G01Y469724D02*
Y468937D01*
G01Y472874D02*
Y472087D01*
G01Y466575D02*
Y465787D01*
G01X84298Y466575D02*
Y468937D01*
G01Y469724D02*
Y472087D01*
G01Y472874D02*
Y475236D01*
G01Y476024D02*
Y478386D01*
G01Y479173D02*
Y481535D01*
G01Y482323D02*
Y484685D01*
G01X85237Y479173D02*
Y478386D01*
G01Y482323D02*
Y481535D01*
G01Y476024D02*
Y475236D01*
G01Y469724D02*
Y468937D01*
G01Y472874D02*
Y472087D01*
G01Y466575D02*
Y465787D01*
G01X85384Y479173D02*
Y478386D01*
G01Y482323D02*
Y481535D01*
G01Y476024D02*
Y475236D01*
G01Y469724D02*
Y468937D01*
G01Y472874D02*
Y472087D01*
G01Y466575D02*
Y465787D01*
G01X86976Y479173D02*
Y478386D01*
G01Y482323D02*
Y481535D01*
G01Y476024D02*
Y475236D01*
G01Y469724D02*
Y468937D01*
G01Y472874D02*
Y472087D01*
G01Y466575D02*
Y465787D01*
G01X87918D02*
Y466575D01*
G01Y468937D02*
Y469724D01*
G01Y472087D02*
Y472874D01*
G01Y475236D02*
Y476024D01*
G01Y478386D02*
Y479173D01*
G01Y481535D02*
Y482323D01*
G01X90754Y465787D02*
Y466575D01*
G01Y468937D02*
Y469724D01*
G01Y472087D02*
Y472874D01*
G01Y475236D02*
Y476024D01*
G01Y478386D02*
Y479173D01*
G01Y481535D02*
Y482323D01*
G01X90943Y479173D02*
Y478386D01*
G01Y482323D02*
Y481535D01*
G01Y476024D02*
Y475236D01*
G01Y469724D02*
Y468937D01*
G01Y472874D02*
Y472087D01*
G01Y466575D02*
Y465787D01*
G01X92717Y479173D02*
Y478386D01*
G01Y482323D02*
Y481535D01*
G01Y476024D02*
Y475236D01*
G01Y469724D02*
Y468937D01*
G01Y472874D02*
Y472087D01*
G01Y466575D02*
Y465787D01*
G01X51428Y481732D02*
X51417Y481634D01*
X51389Y481562D01*
X51351Y481535D01*
G01X51428Y478583D02*
X51417Y478484D01*
X51389Y478412D01*
X51351Y478386D01*
G01X51428Y475433D02*
X51417Y475335D01*
X51389Y475263D01*
X51351Y475236D01*
G01X51428Y472283D02*
X51417Y472185D01*
X51389Y472113D01*
X51351Y472087D01*
G01X51428Y469134D02*
X51417Y469035D01*
X51389Y468963D01*
X51351Y468937D01*
G01X51428Y465984D02*
X51417Y465886D01*
X51389Y465814D01*
X51351Y465787D01*
G01X51802Y481535D02*
X51829Y481539D01*
X51855Y481550D01*
X51879Y481568D01*
X51900Y481593D01*
X51917Y481623D01*
X51930Y481657D01*
X51938Y481693D01*
X51941Y481732D01*
G01X52112Y481476D02*
X51839Y480886D01*
G01X52112Y476476D02*
X51839Y475886D01*
G01X52112Y471476D02*
X51839Y470886D01*
G01X52112Y466476D02*
X51839Y465886D01*
G01X52529Y480886D02*
X52956Y481476D01*
G01X52529Y475886D02*
X52956Y476476D01*
G01X52529Y470886D02*
X52956Y471476D01*
G01X52529Y465886D02*
X52956Y466476D01*
G01X74331Y477854D02*
G03X74724Y477461I393J0D01*
G01Y475886D02*
G03X74331Y475492I1J-394D01*
G01Y472854D02*
G03X74724Y472461I393J0D01*
G01Y470886D02*
G03X74331Y470492I1J-394D01*
G01Y467854D02*
G03X74724Y467461I393J0D01*
G01Y465886D02*
G03X74331Y465492I1J-394D01*
G01Y482854D02*
G03X74724Y482461I393J0D01*
G01Y480886D02*
G03X74331Y480492I1J-394D01*
G01X46369Y466476D02*
X46506Y466279D01*
X46644Y466082D01*
X46784Y465886D01*
G01X46369Y471476D02*
X46506Y471279D01*
X46644Y471082D01*
X46784Y470886D01*
G01X46369Y476476D02*
X46506Y476279D01*
X46644Y476082D01*
X46784Y475886D01*
G01X46369Y481476D02*
X46506Y481279D01*
X46644Y481082D01*
X46784Y480886D01*
G01X46506Y465984D02*
X46538Y465887D01*
X46626Y465815D01*
X46753Y465787D01*
G01X46506Y469134D02*
X46538Y469037D01*
X46626Y468965D01*
X46753Y468937D01*
G01X46506Y472283D02*
X46538Y472186D01*
X46626Y472114D01*
X46753Y472087D01*
G01X46506Y475433D02*
X46538Y475336D01*
X46626Y475264D01*
X46753Y475236D01*
G01Y465787D02*
X52838D01*
G01X46784Y465886D02*
X52529D01*
G01X53118Y465984D02*
X46506D01*
G01Y466378D02*
X53118D01*
G01X46369Y466476D02*
X52956D01*
G01X46753Y466575D02*
X52838D01*
G01X52956Y466870D02*
X46369D01*
G01X52529Y467461D02*
X46784D01*
G01X46753Y468937D02*
X52838D01*
G01X53118Y469134D02*
X46506D01*
G01Y469528D02*
X53118D01*
G01X46753Y469724D02*
X52838D01*
G01X46506Y478583D02*
X46538Y478485D01*
X46626Y478413D01*
X46753Y478386D01*
G01X46506Y481732D02*
X46538Y481635D01*
X46626Y481563D01*
X46753Y481535D01*
G01X46369Y466476D02*
Y466870D01*
G01Y471476D02*
Y471870D01*
G01Y476476D02*
Y476870D01*
G01Y481476D02*
Y481870D01*
G01X46506Y482126D02*
Y481732D01*
G01Y478976D02*
Y478583D01*
G01Y475827D02*
Y475433D01*
G01Y472677D02*
Y472283D01*
G01Y469528D02*
Y469134D01*
G01Y466378D02*
Y465984D01*
G01X50987Y466476D02*
Y466870D01*
G01Y471476D02*
Y471870D01*
G01Y476476D02*
Y476870D01*
G01Y481476D02*
Y481870D01*
G01X46784Y470886D02*
X52529D01*
G01X46369Y471476D02*
X52956D01*
G01Y471870D02*
X46369D01*
G01X46753Y472087D02*
X52838D01*
G01X53118Y472283D02*
X46506D01*
G01X52529Y472461D02*
X46784D01*
G01X46506Y472677D02*
X53118D01*
G01X46753Y472874D02*
X52838D01*
G01X46753Y475236D02*
X52838D01*
G01X53118Y475433D02*
X46506D01*
G01Y475827D02*
X53118D01*
G01X46784Y475886D02*
X52529D01*
G01X46753Y476024D02*
X52838D01*
G01X46369Y476476D02*
X52956D01*
G01Y476870D02*
X46369D01*
G01X52529Y477461D02*
X46784D01*
G01X46753Y478386D02*
X52838D01*
G01X53118Y478583D02*
X46506D01*
G01Y478976D02*
X53118D01*
G01X46753Y479173D02*
X52838D01*
G01X71181Y479469D02*
X44488D01*
G01X46784Y480886D02*
X52529D01*
G01X46369Y481476D02*
X52956D01*
G01X46753Y481535D02*
X52838D01*
G01X53118Y481732D02*
X46506D01*
G01X44488Y481831D02*
X71181D01*
G01X52956Y481870D02*
X46369D01*
G01X46506Y482126D02*
X53118D01*
G01X46753Y482323D02*
X52838D01*
G01X52529Y482461D02*
X46784D01*
G01X50987Y466870D02*
X50909Y467461D01*
G01X50987Y471870D02*
X50909Y472461D01*
G01X50987Y476870D02*
X50909Y477461D01*
G01X50987Y481870D02*
X50909Y482461D01*
G01X50987Y481476D02*
X50909Y480886D01*
G01X50987Y476476D02*
X50909Y475886D01*
G01X50987Y471476D02*
X50909Y470886D01*
G01X50987Y466476D02*
X50909Y465886D01*
G01X46753Y466575D02*
X46626Y466547D01*
X46537Y466474D01*
X46506Y466378D01*
G01X46753Y469724D02*
X46626Y469696D01*
X46537Y469624D01*
X46506Y469528D01*
G01X46753Y472874D02*
X46626Y472846D01*
X46537Y472773D01*
X46506Y472677D01*
G01X46753Y476024D02*
X46626Y475996D01*
X46537Y475923D01*
X46506Y475827D01*
G01X46753Y479173D02*
X46626Y479145D01*
X46537Y479072D01*
X46506Y478976D01*
G01X46753Y482323D02*
X46626Y482295D01*
X46537Y482222D01*
X46506Y482126D01*
G01X46784Y482461D02*
X46644Y482265D01*
X46506Y482068D01*
X46369Y481870D01*
G01X46784Y477461D02*
X46644Y477265D01*
X46506Y477068D01*
X46369Y476870D01*
G01X46784Y472461D02*
X46644Y472265D01*
X46506Y472068D01*
X46369Y471870D01*
G01X46784Y467461D02*
X46644Y467265D01*
X46506Y467068D01*
X46369Y466870D01*
G01X51351Y447677D02*
X51389Y447651D01*
X51417Y447579D01*
X51428Y447480D01*
G01X51351Y450827D02*
X51389Y450800D01*
X51417Y450728D01*
X51428Y450630D01*
G01X51351Y453976D02*
X51389Y453950D01*
X51417Y453878D01*
X51428Y453780D01*
G01X51351Y457126D02*
X51389Y457100D01*
X51417Y457028D01*
X51428Y456929D01*
G01X51351Y460276D02*
X51389Y460249D01*
X51417Y460177D01*
X51428Y460079D01*
G01X51351Y463425D02*
X51389Y463399D01*
X51417Y463327D01*
X51428Y463228D01*
G01X52529Y447461D02*
X52956Y446870D01*
G01X52529Y452461D02*
X52956Y451870D01*
G01X52529Y457461D02*
X52956Y456870D01*
G01X88428Y434995D02*
X89697Y433135D01*
G01X90044Y434995D02*
X90650Y434009D01*
G01X91426Y433144D02*
X92747Y430988D01*
G01X90453Y432266D02*
X91198Y430988D01*
G01X51839Y447461D02*
X52112Y446870D01*
G01X51839Y452461D02*
X52112Y451870D01*
G01X51839Y457461D02*
X52112Y456870D01*
G01X64646Y416654D02*
X81024D01*
G01X75000Y420984D02*
X70669D01*
G01X75625Y421772D02*
X70044D01*
G01Y423346D02*
X75625D01*
G01X70669Y424134D02*
X75000D01*
G01X81024Y426831D02*
X64646D01*
G01X79783Y430472D02*
X84390D01*
G01X89662Y430988D02*
X88254D01*
G01X92747D02*
X91198D01*
G01X83082D02*
X81622D01*
G01X75823D02*
X74430D01*
G01X73000D02*
X71541D01*
G01X70110D02*
X68670D01*
G01X94488Y431555D02*
X70866D01*
G01X84041Y431654D02*
X80132D01*
G01X88097Y432144D02*
X86594D01*
G01X88228Y432587D02*
X85228D01*
G01X86655Y433413D02*
X85229D01*
G01X90044Y434995D02*
X88428D01*
G01X92721D02*
X91339D01*
G01X70113D02*
X68670D01*
G01X94488Y435335D02*
X70866D01*
G01X83082Y436742D02*
X81622D01*
G01X80132Y437087D02*
X84041D01*
G01X94488Y437303D02*
X70866D01*
G01X84390Y438268D02*
X79783D01*
G01X94488Y439705D02*
X70866D01*
G01X79328Y440236D02*
X73228D01*
G01X79328Y440295D02*
X73228D01*
G01X93696Y440689D02*
X73228D01*
G01X74331Y441870D02*
X64961D01*
G01X64646Y443051D02*
X71181D01*
G01X94488Y443465D02*
X74331D01*
G01Y443642D02*
X64961D01*
G01X77756Y445098D02*
X76772D01*
G01X87331Y445217D02*
X78346D01*
G01X77756Y445295D02*
X76772D01*
G01X77756Y445689D02*
X76772D01*
G01X74724Y445886D02*
X81890D01*
G01X92717Y446890D02*
X85384D01*
G01X85237D02*
X73228D01*
G01X74724Y447461D02*
X81890D01*
G01X77756Y447657D02*
X76772D01*
G01X85237Y447677D02*
X73228D01*
G01X85384D02*
X92717D01*
G01X77756Y448051D02*
X76772D01*
G01X77756Y448248D02*
X76772D01*
G01X92717Y450039D02*
X85384D01*
G01X85237D02*
X73228D01*
G01X77756Y450098D02*
X76772D01*
G01X77756Y450295D02*
X76772D01*
G01X77756Y450689D02*
X76772D01*
G01X85237Y450827D02*
X73228D01*
G01X85384D02*
X92717D01*
G01X81890Y450886D02*
X74724D01*
G01X81890Y452461D02*
X74724D01*
G01X77756Y452657D02*
X76772D01*
G01X77756Y453051D02*
X76772D01*
G01X92717Y453189D02*
X85384D01*
G01X85237D02*
X73228D01*
G01X77756Y453248D02*
X76772D01*
G01X85237Y453976D02*
X73228D01*
G01X85384D02*
X92717D01*
G01X77756Y455098D02*
X76772D01*
G01X77756Y455295D02*
X76772D01*
G01X77756Y455689D02*
X76772D01*
G01X74724Y455886D02*
X81890D01*
G01X92717Y456339D02*
X85384D01*
G01X85237D02*
X73228D01*
G01X85237Y457126D02*
X73228D01*
G01X85384D02*
X92717D01*
G01X74724Y457461D02*
X81890D01*
G01X77756Y457657D02*
X76772D01*
G01X77756Y458051D02*
X76772D01*
G01X77756Y458248D02*
X76772D01*
G01X73228Y459469D02*
X74331D01*
G01X92717Y459488D02*
X85384D01*
G01X85237D02*
X73228D01*
G01X75787Y460098D02*
X74803D01*
G01X85237Y460276D02*
X73228D01*
G01X85384D02*
X92717D01*
G01X75787Y460295D02*
X74803D01*
G01X75787Y460689D02*
X74803D01*
G01X74331Y460886D02*
X79921D01*
G01X74331Y462461D02*
X79921D01*
G01X92717Y462638D02*
X85384D01*
G01X85237D02*
X73228D01*
G01X75787Y462657D02*
X74803D01*
G01X75787Y463051D02*
X74803D01*
G01X75787Y463248D02*
X74803D01*
G01X85237Y463425D02*
X73228D01*
G01X85384D02*
X92717D01*
G01X73228Y463878D02*
X74331D01*
G01X77756Y465098D02*
X76772D01*
G01X80132Y437087D02*
X80114Y437143D01*
X80062Y437308D01*
X79983Y437567D01*
X79887Y437894D01*
X79783Y438268D01*
G01X84041Y431654D02*
X84059Y431598D01*
X84111Y431432D01*
X84190Y431174D01*
X84285Y430846D01*
X84390Y430472D01*
G01X51941Y447480D02*
X51938Y447519D01*
X51930Y447555D01*
X51917Y447589D01*
X51900Y447619D01*
X51879Y447644D01*
X51856Y447662D01*
X51830Y447673D01*
X51802Y447677D01*
G01X51941Y450630D02*
X51938Y450668D01*
X51930Y450705D01*
X51917Y450739D01*
X51900Y450769D01*
X51879Y450793D01*
X51856Y450811D01*
X51830Y450823D01*
X51802Y450827D01*
G01X51941Y453780D02*
X51938Y453818D01*
X51930Y453854D01*
X51917Y453888D01*
X51900Y453919D01*
X51879Y453943D01*
X51856Y453961D01*
X51830Y453972D01*
X51802Y453976D01*
G01X51941Y456929D02*
X51938Y456967D01*
X51930Y457004D01*
X51917Y457038D01*
X51900Y457068D01*
X51879Y457093D01*
X51856Y457111D01*
X51830Y457122D01*
X51802Y457126D01*
G01X51941Y460079D02*
X51938Y460117D01*
X51930Y460154D01*
X51917Y460187D01*
X51900Y460218D01*
X51879Y460242D01*
X51856Y460260D01*
X51830Y460272D01*
X51802Y460276D01*
G01X51941Y463228D02*
X51938Y463267D01*
X51930Y463303D01*
X51917Y463337D01*
X51900Y463367D01*
X51879Y463392D01*
X51856Y463410D01*
X51830Y463421D01*
X51802Y463425D01*
G01X51428Y460079D02*
Y459685D01*
G01Y463228D02*
Y462835D01*
G01Y456929D02*
Y456535D01*
G01Y453780D02*
Y453386D01*
G01Y450630D02*
Y450236D01*
G01Y447480D02*
Y447087D01*
G01X51941D02*
Y447480D01*
G01Y453386D02*
Y453780D01*
G01Y450236D02*
Y450630D01*
G01Y456535D02*
Y456929D01*
G01Y459685D02*
Y460079D01*
G01Y462835D02*
Y463228D01*
G01X52112Y456870D02*
Y456476D01*
G01Y451870D02*
Y451476D01*
G01Y446870D02*
Y446476D01*
G01X52956Y456870D02*
Y456476D01*
G01Y451870D02*
Y451476D01*
G01Y446870D02*
Y446476D01*
G01X53118Y447087D02*
Y447480D01*
G01Y453386D02*
Y453780D01*
G01Y450236D02*
Y450630D01*
G01Y456535D02*
Y456929D01*
G01Y459685D02*
Y460079D01*
G01Y462835D02*
Y463228D01*
G01X51802Y446890D02*
X51829Y446893D01*
X51855Y446904D01*
X51879Y446922D01*
X51900Y446947D01*
X51917Y446977D01*
X51930Y447011D01*
X51938Y447048D01*
X51941Y447087D01*
G01X51802Y450039D02*
X51829Y450043D01*
X51855Y450054D01*
X51879Y450072D01*
X51900Y450097D01*
X51917Y450127D01*
X51930Y450161D01*
X51938Y450197D01*
X51941Y450236D01*
G01X51802Y453189D02*
X51829Y453193D01*
X51855Y453204D01*
X51879Y453222D01*
X51900Y453246D01*
X51917Y453276D01*
X51930Y453310D01*
X51938Y453347D01*
X51941Y453386D01*
G01X51802Y456339D02*
X51829Y456342D01*
X51855Y456353D01*
X51879Y456371D01*
X51900Y456396D01*
X51917Y456426D01*
X51930Y456460D01*
X51938Y456496D01*
X51941Y456535D01*
G01X51802Y459488D02*
X51829Y459492D01*
X51855Y459503D01*
X51879Y459521D01*
X51900Y459546D01*
X51917Y459576D01*
X51930Y459609D01*
X51938Y459646D01*
X51941Y459685D01*
G01X51802Y462638D02*
X51829Y462641D01*
X51855Y462652D01*
X51879Y462670D01*
X51900Y462695D01*
X51917Y462725D01*
X51930Y462759D01*
X51938Y462796D01*
X51941Y462835D01*
G01X62992Y442854D02*
Y575492D01*
G01X64646Y443051D02*
Y416654D01*
G01X64961Y443642D02*
Y441870D01*
G01X66929Y429587D02*
Y437933D01*
G01X68670Y434995D02*
Y430988D01*
G01X69213Y479469D02*
Y462933D01*
G01Y460571D02*
Y443051D01*
G01X70044Y423346D02*
Y421772D01*
G01X70079D02*
Y423346D01*
G01X70103Y421772D02*
Y423346D01*
G01X70110Y433513D02*
Y430988D01*
G01X70113Y434995D02*
Y434438D01*
G01X70866Y439705D02*
Y437303D01*
G01Y435335D02*
Y431555D01*
G01X71181Y575295D02*
Y443051D01*
G01X71426Y423346D02*
Y421772D01*
G01X71541Y430988D02*
Y433513D01*
G01X71796Y421772D02*
Y423346D01*
G01X73000Y433513D02*
Y430988D01*
G01X73228Y440236D02*
Y578110D01*
G01X73873Y423346D02*
Y421772D01*
G01X74243D02*
Y423346D01*
G01X74331Y577657D02*
Y440689D01*
G01X74430Y430988D02*
Y433513D01*
G01X74803Y463248D02*
Y460098D01*
G01X75170Y460276D02*
Y459488D01*
G01Y463425D02*
Y462638D01*
G01Y457126D02*
Y456339D01*
G01Y450827D02*
Y450039D01*
G01Y453976D02*
Y453189D01*
G01Y447677D02*
Y446890D01*
G01X75197Y460276D02*
Y459488D01*
G01Y463425D02*
Y462638D01*
G01Y457126D02*
Y456339D01*
G01Y450827D02*
Y450039D01*
G01Y453976D02*
Y453189D01*
G01Y447677D02*
Y446890D01*
G01X75567Y423346D02*
Y421772D01*
G01X75573Y460276D02*
Y459488D01*
G01Y463425D02*
Y462638D01*
G01Y457126D02*
Y456339D01*
G01Y450827D02*
Y450039D01*
G01Y453976D02*
Y453189D01*
G01Y447677D02*
Y446890D01*
G01X75591Y423346D02*
Y421772D01*
G01X75625D02*
Y423346D01*
G01X75787Y463248D02*
Y460098D01*
G01Y457461D02*
Y455886D01*
G01Y452461D02*
Y450886D01*
G01Y447461D02*
Y445886D01*
G01X75823Y433917D02*
Y430988D01*
G01X76772Y468248D02*
Y465098D01*
G01Y462461D02*
Y460886D01*
G01Y458248D02*
Y455098D01*
G01Y453248D02*
Y450098D01*
G01Y448248D02*
Y445098D01*
G01Y437933D02*
Y440236D01*
G01X77756Y468248D02*
Y465098D01*
G01Y458248D02*
Y455098D01*
G01Y453248D02*
Y450098D01*
G01Y448248D02*
Y445098D01*
G01X78346Y577657D02*
Y440689D01*
G01X78740Y457461D02*
Y455886D01*
G01Y452461D02*
Y450886D01*
G01Y447461D02*
Y445886D01*
G01X78801Y575079D02*
Y443465D01*
G01X78935Y446890D02*
Y447677D01*
G01Y450039D02*
Y450827D01*
G01Y453189D02*
Y453976D01*
G01Y456339D02*
Y457126D01*
G01Y459488D02*
Y460276D01*
G01Y462638D02*
Y463425D01*
G01X79328Y440236D02*
Y440295D01*
G01X79921Y460886D02*
Y462461D01*
G01X79967Y440689D02*
Y437933D01*
G01X80919Y446890D02*
Y447677D01*
G01Y450039D02*
Y450827D01*
G01Y453189D02*
Y453976D01*
G01Y456339D02*
Y457126D01*
G01Y459488D02*
Y460276D01*
G01Y462638D02*
Y463425D01*
G01X81024Y429587D02*
Y416654D01*
G01X81622Y430988D02*
Y436742D01*
G01X81890Y445886D02*
Y447461D01*
G01Y450886D02*
Y452461D01*
G01Y455886D02*
Y457461D01*
G01X82570Y460276D02*
Y459488D01*
G01Y463425D02*
Y462638D01*
G01Y457126D02*
Y456339D01*
G01Y450827D02*
Y450039D01*
G01Y453976D02*
Y453189D01*
G01Y447677D02*
Y446890D01*
G01X83082Y436742D02*
Y430988D01*
G01X84298Y445217D02*
Y446890D01*
G01Y447677D02*
Y450039D01*
G01Y450827D02*
Y453189D01*
G01Y453976D02*
Y456339D01*
G01Y457126D02*
Y459488D01*
G01Y460276D02*
Y462638D01*
G01Y463425D02*
Y465787D01*
G01X85237Y460276D02*
Y459488D01*
G01Y463425D02*
Y462638D01*
G01Y457126D02*
Y456339D01*
G01Y450827D02*
Y450039D01*
G01Y453976D02*
Y453189D01*
G01Y447677D02*
Y446890D01*
G01X85384Y460276D02*
Y459488D01*
G01Y463425D02*
Y462638D01*
G01Y457126D02*
Y456339D01*
G01Y450827D02*
Y450039D01*
G01Y453976D02*
Y453189D01*
G01Y447677D02*
Y446890D01*
G01X86976Y460276D02*
Y459488D01*
G01Y463425D02*
Y462638D01*
G01Y457126D02*
Y456339D01*
G01Y450827D02*
Y450039D01*
G01Y453976D02*
Y453189D01*
G01Y447677D02*
Y446890D01*
G01X87331Y440689D02*
Y577657D01*
G01X87841Y440689D02*
Y437933D01*
G01X87918Y446890D02*
Y447677D01*
G01Y450039D02*
Y450827D01*
G01Y453189D02*
Y453976D01*
G01Y456339D02*
Y457126D01*
G01Y459488D02*
Y460276D01*
G01Y462638D02*
Y463425D01*
G01X90754Y446890D02*
Y447677D01*
G01Y450039D02*
Y450827D01*
G01Y453189D02*
Y453976D01*
G01Y456339D02*
Y457126D01*
G01Y459488D02*
Y460276D01*
G01Y462638D02*
Y463425D01*
G01X90943Y460276D02*
Y459488D01*
G01Y463425D02*
Y462638D01*
G01Y457126D02*
Y456339D01*
G01Y450827D02*
Y450039D01*
G01Y453976D02*
Y453189D01*
G01Y447677D02*
Y446890D01*
G01X92717Y460276D02*
Y459488D01*
G01Y463425D02*
Y462638D01*
G01Y457126D02*
Y456339D01*
G01Y450827D02*
Y450039D01*
G01Y453976D02*
Y453189D01*
G01Y447677D02*
Y446890D01*
G01X93696Y440689D02*
Y443465D01*
G01X94170Y437933D02*
Y443465D01*
G01X94488Y429587D02*
Y443465D01*
G01X51428Y462835D02*
X51417Y462736D01*
X51389Y462664D01*
X51351Y462638D01*
G01X51428Y459685D02*
X51417Y459587D01*
X51389Y459515D01*
X51351Y459488D01*
G01X51428Y456535D02*
X51417Y456437D01*
X51389Y456365D01*
X51351Y456339D01*
G01X51428Y453386D02*
X51417Y453287D01*
X51389Y453215D01*
X51351Y453189D01*
G01X51428Y450236D02*
X51417Y450138D01*
X51389Y450066D01*
X51351Y450039D01*
G01X51428Y447087D02*
X51417Y446988D01*
X51389Y446916D01*
X51351Y446890D01*
G01X79783Y430472D02*
X79886Y430841D01*
X79982Y431171D01*
X80063Y431433D01*
X80115Y431599D01*
X80132Y431654D01*
G01X84041Y437087D02*
X84059Y437142D01*
X84111Y437307D01*
X84190Y437566D01*
X84285Y437893D01*
X84390Y438268D01*
G01X52112Y456476D02*
X51839Y455886D01*
G01X52112Y451476D02*
X51839Y450886D01*
G01X52112Y446476D02*
X51839Y445886D01*
G01X90453Y432266D02*
X89662Y430988D01*
G01X79328Y440295D02*
X79583Y440689D01*
G01X89697Y433135D02*
X88254Y430988D01*
G01X91339Y434995D02*
X90650Y434009D01*
G01X92721Y434995D02*
X91426Y433144D01*
G01X52529Y455886D02*
X52956Y456476D01*
G01X52529Y450886D02*
X52956Y451476D01*
G01X52529Y445886D02*
X52956Y446476D01*
G01X72893Y434444D02*
G03X70113Y434438I-1387J-1207D01*
G01X75529Y434589D02*
G03X72893Y434444I-1248J-1352D01*
G01X70669Y424134D02*
G03Y420984I0J-1575D01*
G01X74430Y433513D02*
G03X73000I-715J0D01*
G01X71541D02*
G03X70110I-716J0D01*
G01X74331Y452854D02*
G03X74724Y452461I393J0D01*
G01Y450886D02*
G03X74331Y450492I1J-394D01*
G01Y457854D02*
G03X74724Y457461I393J0D01*
G01Y455886D02*
G03X74331Y455492I1J-394D01*
G01Y447854D02*
G03X74724Y447461I393J0D01*
G01Y445886D02*
G03X74331Y445492I1J-394D01*
G01X80324Y434642D02*
G03X77277Y434641I-1523J-2362D01*
G01X77278Y431197D02*
G03X80324Y431198I1522J2362D01*
G01X80845Y431764D02*
G03X80844Y434076I-2163J1155D01*
G01X76756D02*
G03X76757Y431762I2163J-1156D01*
G01X79502Y432097D02*
G03Y433782I-2236J843D01*
G01X75000Y420984D02*
G03Y424134I0J1575D01*
G01X77277Y434641D02*
G03X76756Y434076I830J-1288D01*
G01X76757Y431762D02*
G03X77278Y431197I1351J723D01*
G01X75823Y433917D02*
G03X75529Y434589I-914J1D01*
G01X79502Y433782D02*
G03X78029I-736J-278D01*
G01Y432097D02*
G03X79502I737J278D01*
G01X78030Y433782D02*
G03Y432097I2236J-842D01*
G01X80844Y434076D02*
G03X80323Y434642I-1352J-722D01*
G01X80324Y431199D02*
G03X80845Y431764I-830J1288D01*
G01X84390Y430472D02*
G03Y438268I-2303J3898D01*
G01X79783D02*
G03Y430472I2303J-3898D01*
G01X85591Y434370D02*
G03I-3505J0D01*
G01X80132Y437087D02*
G03Y431654I1954J-2717D01*
G01X84041D02*
G03Y437087I-1954J2717D01*
G01X84252Y434370D02*
G03I-2166J0D01*
G01X83847Y433822D02*
G03X83673Y433161I4019J-1411D01*
G01D02*
G03Y432664I3525J-248D01*
G01X88228Y432587D02*
G03X87889Y434030I-3015J53D01*
G01X83673Y432666D02*
G03X83935Y431803I2971J431D01*
G01X86655Y435004D02*
G03X85012Y434960I-756J-2475D01*
G01X83934Y431806D02*
G03X85672Y430788I1807J1093D01*
G01X85012Y434960D02*
G03X83847Y433822I729J-1911D01*
G01X87889Y434030D02*
G03X86655Y435004I-1735J-930D01*
G01X87254Y431075D02*
G03X88098Y432144I-703J1423D01*
G01X85229Y432587D02*
G03X86003Y431779I792J-16D01*
G01Y431780D02*
G03X86594Y432144I10J646D01*
G01X85669Y430789D02*
G03X87254Y431075I264J3073D01*
G01X86654Y433413D02*
G03X85229I-713J83D01*
G01X42520Y439902D02*
X44488Y437933D01*
G01X50560Y462461D02*
X50987Y461870D01*
G01X46369Y446476D02*
X46506Y446279D01*
X46644Y446082D01*
X46784Y445886D01*
G01X46369Y451476D02*
X46506Y451279D01*
X46644Y451082D01*
X46784Y450886D01*
G01X46369Y456476D02*
X46506Y456279D01*
X46644Y456082D01*
X46784Y455886D01*
G01X44401Y461476D02*
X44538Y461279D01*
X44676Y461082D01*
X44815Y460886D01*
G01X46753Y459488D02*
X46627Y459515D01*
X46538Y459588D01*
X46506Y459685D01*
G01X49871Y462461D02*
X50143Y461870D01*
G01X40519Y429618D02*
X40462Y429757D01*
X40457Y429998D01*
G01X46506Y447087D02*
X46538Y446989D01*
X46626Y446917D01*
X46753Y446890D01*
G01X46506Y450236D02*
X46538Y450139D01*
X46626Y450067D01*
X46753Y450039D01*
G01X46506Y453386D02*
X46538Y453289D01*
X46626Y453217D01*
X46753Y453189D01*
G01X46506Y456535D02*
X46538Y456438D01*
X46626Y456366D01*
X46753Y456339D01*
G01X46506Y462835D02*
X46538Y462737D01*
X46626Y462665D01*
X46753Y462638D01*
G01X94488Y429587D02*
X40551D01*
G01Y430768D02*
X66929D01*
G01X42520Y437933D02*
X39236D01*
G01X44488D02*
X94488D01*
G01X42520Y442461D02*
X73228D01*
G01X44488Y442854D02*
X62992D01*
G01X46784Y445886D02*
X52529D01*
G01X46369Y446476D02*
X52956D01*
G01Y446870D02*
X46369D01*
G01X46753Y446890D02*
X52838D01*
G01X53118Y447087D02*
X46506D01*
G01X52529Y447461D02*
X46784D01*
G01X46506Y447480D02*
X53118D01*
G01X46753Y447677D02*
X52838D01*
G01X46753Y450039D02*
X52838D01*
G01X53118Y450236D02*
X46506D01*
G01Y450630D02*
X53118D01*
G01X46753Y450827D02*
X52838D01*
G01X46784Y450886D02*
X52529D01*
G01X46369Y451476D02*
X52956D01*
G01Y451870D02*
X46369D01*
G01X52529Y452461D02*
X46784D01*
G01X46753Y453189D02*
X52838D01*
G01X53118Y453386D02*
X46506D01*
G01Y453780D02*
X53118D01*
G01X46753Y453976D02*
X52838D01*
G01X46784Y455886D02*
X52529D01*
G01X46753Y456339D02*
X52838D01*
G01X46369Y456476D02*
X52956D01*
G01X53118Y456535D02*
X46506D01*
G01X52956Y456870D02*
X46369D01*
G01X46506Y456929D02*
X53118D01*
G01X46753Y457126D02*
X52838D01*
G01X52529Y457461D02*
X46784D01*
G01X46753Y459488D02*
X52838D01*
G01X53118Y459685D02*
X46506D01*
G01Y460079D02*
X53118D01*
G01X46753Y460276D02*
X52838D01*
G01X71181Y460571D02*
X44488D01*
G01X44815Y460886D02*
X50560D01*
G01X44401Y461476D02*
X50987D01*
G01Y461870D02*
X44401D01*
G01X50560Y462461D02*
X44815D01*
G01X46753Y462638D02*
X52838D01*
G01X53118Y462835D02*
X46506D01*
G01X44488Y462933D02*
X71181D01*
G01X46506Y463228D02*
X53118D01*
G01X46753Y463425D02*
X52838D01*
G01X50987Y446870D02*
X50909Y447461D01*
G01X49019Y461870D02*
X48941Y462461D01*
G01X50909Y452461D02*
X50987Y451870D01*
G01Y456870D02*
X50909Y457461D01*
G01X40551Y437933D02*
Y430768D01*
G01X42520Y580413D02*
Y437933D01*
G01X43642Y442461D02*
Y575886D01*
G01X43701Y442067D02*
Y512972D01*
G01X44401Y461476D02*
Y461870D01*
G01X44488Y575492D02*
Y442854D01*
G01X46369Y446476D02*
Y446870D01*
G01Y451476D02*
Y451870D01*
G01Y456476D02*
Y456870D01*
G01X46506Y460079D02*
Y459685D01*
G01Y463228D02*
Y462835D01*
G01Y456929D02*
Y456535D01*
G01Y453780D02*
Y453386D01*
G01Y450630D02*
Y450236D01*
G01Y447480D02*
Y447087D01*
G01X49019Y461476D02*
Y461870D01*
G01X50143D02*
Y461476D01*
G01X50987Y461870D02*
Y461476D01*
G01Y451870D02*
Y451476D01*
G01Y446476D02*
Y446870D01*
G01Y456476D02*
Y456870D01*
G01X40493Y430319D02*
X40457Y429994D01*
X40463Y429754D01*
X40519Y429618D01*
G01X49019Y461476D02*
X48941Y460886D01*
G01X50987Y456476D02*
X50909Y455886D01*
G01Y450886D02*
X50987Y451476D01*
G01Y446476D02*
X50909Y445886D01*
G01X40493Y430317D02*
X40547Y430694D01*
G01X46753Y447677D02*
X46626Y447649D01*
X46537Y447576D01*
X46506Y447480D01*
G01X46753Y450827D02*
X46626Y450799D01*
X46537Y450726D01*
X46506Y450630D01*
G01X46753Y453976D02*
X46626Y453948D01*
X46537Y453876D01*
X46506Y453780D01*
G01X46753Y457126D02*
X46626Y457098D01*
X46537Y457025D01*
X46506Y456929D01*
G01X46753Y463425D02*
X46626Y463397D01*
X46537Y463324D01*
X46506Y463228D01*
G01Y460079D02*
X46539Y460178D01*
X46628Y460248D01*
X46753Y460276D01*
G01X50143Y461476D02*
X49871Y460886D01*
G01X44815Y462461D02*
X44676Y462265D01*
X44538Y462068D01*
X44401Y461870D01*
G01X46784Y457461D02*
X46644Y457265D01*
X46506Y457068D01*
X46369Y456870D01*
G01X46784Y452461D02*
X46644Y452265D01*
X46506Y452068D01*
X46369Y451870D01*
G01X46784Y447461D02*
X46644Y447265D01*
X46506Y447068D01*
X46369Y446870D01*
G01X50560Y460886D02*
X50987Y461476D01*
G01X44488Y442854D02*
X42520Y440886D01*
G01X51351Y485472D02*
X51389Y485446D01*
X51417Y485374D01*
X51428Y485276D01*
G01X51351Y488622D02*
X51389Y488596D01*
X51417Y488524D01*
X51428Y488425D01*
G01X51351Y491772D02*
X51389Y491745D01*
X51417Y491673D01*
X51428Y491575D01*
G01X51351Y494921D02*
X51389Y494895D01*
X51417Y494823D01*
X51428Y494724D01*
G01X51351Y498071D02*
X51389Y498044D01*
X51417Y497972D01*
X51428Y497874D01*
G01X51351Y501220D02*
X51389Y501194D01*
X51417Y501122D01*
X51428Y501024D01*
G01X51351Y504370D02*
X51389Y504344D01*
X51417Y504272D01*
X51428Y504173D01*
G01X52529Y487461D02*
X52956Y486870D01*
G01X52529Y492461D02*
X52956Y491870D01*
G01X52529Y497461D02*
X52956Y496870D01*
G01X51839Y487461D02*
X52112Y486870D01*
G01X51839Y492461D02*
X52112Y491870D01*
G01X51839Y497461D02*
X52112Y496870D01*
G01X51941Y485276D02*
X51938Y485314D01*
X51930Y485350D01*
X51917Y485384D01*
X51900Y485415D01*
X51879Y485439D01*
X51856Y485457D01*
X51830Y485469D01*
X51802Y485472D01*
G01X51941Y488425D02*
X51938Y488463D01*
X51930Y488500D01*
X51917Y488534D01*
X51900Y488564D01*
X51879Y488589D01*
X51856Y488607D01*
X51830Y488618D01*
X51802Y488622D01*
G01X51941Y491575D02*
X51938Y491613D01*
X51930Y491650D01*
X51917Y491683D01*
X51900Y491714D01*
X51879Y491738D01*
X51856Y491756D01*
X51830Y491768D01*
X51802Y491772D01*
G01X51941Y494724D02*
X51938Y494763D01*
X51930Y494799D01*
X51917Y494833D01*
X51900Y494863D01*
X51879Y494888D01*
X51856Y494906D01*
X51830Y494917D01*
X51802Y494921D01*
G01X51941Y497874D02*
X51938Y497912D01*
X51930Y497949D01*
X51917Y497983D01*
X51900Y498013D01*
X51879Y498037D01*
X51856Y498056D01*
X51830Y498067D01*
X51802Y498071D01*
G01X51941Y501024D02*
X51938Y501062D01*
X51930Y501098D01*
X51917Y501132D01*
X51900Y501163D01*
X51879Y501187D01*
X51856Y501205D01*
X51830Y501217D01*
X51802Y501220D01*
G01X51941Y504173D02*
X51938Y504211D01*
X51930Y504248D01*
X51917Y504282D01*
X51900Y504312D01*
X51879Y504337D01*
X51856Y504355D01*
X51830Y504366D01*
X51802Y504370D01*
G01X51428Y504173D02*
Y503780D01*
G01Y501024D02*
Y500630D01*
G01Y497874D02*
Y497480D01*
G01Y494724D02*
Y494331D01*
G01Y491575D02*
Y491181D01*
G01Y488425D02*
Y488031D01*
G01Y485276D02*
Y484882D01*
G01X51941D02*
Y485276D01*
G01Y491181D02*
Y491575D01*
G01Y488031D02*
Y488425D01*
G01Y494331D02*
Y494724D01*
G01Y500630D02*
Y501024D01*
G01Y497480D02*
Y497874D01*
G01Y503780D02*
Y504173D01*
G01X52112Y496870D02*
Y496476D01*
G01Y491870D02*
Y491476D01*
G01Y486870D02*
Y486476D01*
G01X52956Y496870D02*
Y496476D01*
G01Y491870D02*
Y491476D01*
G01Y486870D02*
Y486476D01*
G01X53118Y484882D02*
Y485276D01*
G01Y491181D02*
Y491575D01*
G01Y488031D02*
Y488425D01*
G01Y494331D02*
Y494724D01*
G01Y500630D02*
Y501024D01*
G01Y497480D02*
Y497874D01*
G01Y503780D02*
Y504173D01*
G01X92717Y484685D02*
X85384D01*
G01X85237D02*
X73228D01*
G01X77756Y485098D02*
X76772D01*
G01X77756Y485295D02*
X76772D01*
G01X85237Y485472D02*
X73228D01*
G01X85384D02*
X92717D01*
G01X77756Y485689D02*
X76772D01*
G01X74724Y485886D02*
X81890D01*
G01X74724Y487461D02*
X81890D01*
G01X77756Y487657D02*
X76772D01*
G01X92717Y487835D02*
X85384D01*
G01X85237D02*
X73228D01*
G01X77756Y488051D02*
X76772D01*
G01X77756Y488248D02*
X76772D01*
G01X85237Y488622D02*
X73228D01*
G01X85384D02*
X92717D01*
G01X77756Y490098D02*
X76772D01*
G01X77756Y490295D02*
X76772D01*
G01X77756Y490689D02*
X76772D01*
G01X74724Y490886D02*
X81890D01*
G01X92717Y490984D02*
X85384D01*
G01X85237D02*
X73228D01*
G01X85237Y491772D02*
X73228D01*
G01X85384D02*
X92717D01*
G01X74724Y492461D02*
X81890D01*
G01X77756Y492657D02*
X76772D01*
G01X77756Y493051D02*
X76772D01*
G01X77756Y493248D02*
X76772D01*
G01X92717Y494134D02*
X85384D01*
G01X85237D02*
X73228D01*
G01X85237Y494921D02*
X73228D01*
G01X85384D02*
X92717D01*
G01X77756Y495098D02*
X76772D01*
G01X77756Y495295D02*
X76772D01*
G01X77756Y495689D02*
X76772D01*
G01X74724Y495886D02*
X81890D01*
G01X92717Y497283D02*
X85384D01*
G01X85237D02*
X73228D01*
G01X74724Y497461D02*
X81890D01*
G01X77756Y497657D02*
X76772D01*
G01X77756Y498051D02*
X76772D01*
G01X85237Y498071D02*
X73228D01*
G01X85384D02*
X92717D01*
G01X77756Y498248D02*
X76772D01*
G01X74331Y499469D02*
X73228D01*
G01X75787Y500098D02*
X74803D01*
G01X75787Y500295D02*
X74803D01*
G01X92717Y500433D02*
X85384D01*
G01X85237D02*
X73228D01*
G01X75787Y500689D02*
X74803D01*
G01X74331Y500886D02*
X79921D01*
G01X85237Y501220D02*
X73228D01*
G01X85384D02*
X92717D01*
G01X74331Y502461D02*
X79921D01*
G01X75787Y502657D02*
X74803D01*
G01X75787Y503051D02*
X74803D01*
G01X75787Y503248D02*
X74803D01*
G01X92717Y503583D02*
X85384D01*
G01X85237D02*
X73228D01*
G01Y503878D02*
X74331D01*
G01X85237Y504370D02*
X73228D01*
G01X85384D02*
X92717D01*
G01X77756Y505098D02*
X76772D01*
G01X69213Y517067D02*
Y500728D01*
G01X74803Y503248D02*
Y500098D01*
G01X75170Y504370D02*
Y503583D01*
G01Y498071D02*
Y497283D01*
G01Y501220D02*
Y500433D01*
G01Y494921D02*
Y494134D01*
G01Y488622D02*
Y487835D01*
G01Y491772D02*
Y490984D01*
G01Y485472D02*
Y484685D01*
G01X75197Y504370D02*
Y503583D01*
G01Y498071D02*
Y497283D01*
G01Y501220D02*
Y500433D01*
G01Y494921D02*
Y494134D01*
G01Y488622D02*
Y487835D01*
G01Y491772D02*
Y490984D01*
G01Y485472D02*
Y484685D01*
G01X75573Y504370D02*
Y503583D01*
G01Y498071D02*
Y497283D01*
G01Y501220D02*
Y500433D01*
G01Y494921D02*
Y494134D01*
G01Y488622D02*
Y487835D01*
G01Y491772D02*
Y490984D01*
G01Y485472D02*
Y484685D01*
G01X75787Y503248D02*
Y500098D01*
G01Y497461D02*
Y495886D01*
G01Y492461D02*
Y490886D01*
G01Y487461D02*
Y485886D01*
G01X76772Y508248D02*
Y505098D01*
G01Y502461D02*
Y500886D01*
G01Y498248D02*
Y495098D01*
G01Y493248D02*
Y490098D01*
G01Y488248D02*
Y485098D01*
G01X77756Y508248D02*
Y505098D01*
G01Y498248D02*
Y495098D01*
G01Y493248D02*
Y490098D01*
G01Y488248D02*
Y485098D01*
G01X78740Y497461D02*
Y495886D01*
G01Y492461D02*
Y490886D01*
G01Y487461D02*
Y485886D01*
G01X78935Y484685D02*
Y485472D01*
G01Y487835D02*
Y488622D01*
G01Y490984D02*
Y491772D01*
G01Y494134D02*
Y494921D01*
G01Y497283D02*
Y498071D01*
G01Y500433D02*
Y501220D01*
G01Y503583D02*
Y504370D01*
G01X79921Y500886D02*
Y502461D01*
G01X80919Y484685D02*
Y485472D01*
G01Y487835D02*
Y488622D01*
G01Y490984D02*
Y491772D01*
G01Y494134D02*
Y494921D01*
G01Y497283D02*
Y498071D01*
G01Y500433D02*
Y501220D01*
G01Y503583D02*
Y504370D01*
G01X81890Y485886D02*
Y487461D01*
G01Y490886D02*
Y492461D01*
G01Y495886D02*
Y497461D01*
G01X82570Y504370D02*
Y503583D01*
G01Y498071D02*
Y497283D01*
G01Y501220D02*
Y500433D01*
G01Y494921D02*
Y494134D01*
G01Y488622D02*
Y487835D01*
G01Y491772D02*
Y490984D01*
G01Y485472D02*
Y484685D01*
G01X84298Y485472D02*
Y487835D01*
G01Y488622D02*
Y490984D01*
G01Y491772D02*
Y494134D01*
G01Y494921D02*
Y497283D01*
G01Y498071D02*
Y500433D01*
G01Y501220D02*
Y503583D01*
G01Y504370D02*
Y506732D01*
G01X85237Y504370D02*
Y503583D01*
G01Y498071D02*
Y497283D01*
G01Y501220D02*
Y500433D01*
G01Y494921D02*
Y494134D01*
G01Y488622D02*
Y487835D01*
G01Y491772D02*
Y490984D01*
G01Y485472D02*
Y484685D01*
G01X85384Y504370D02*
Y503583D01*
G01Y498071D02*
Y497283D01*
G01Y501220D02*
Y500433D01*
G01Y494921D02*
Y494134D01*
G01Y488622D02*
Y487835D01*
G01Y491772D02*
Y490984D01*
G01Y485472D02*
Y484685D01*
G01X86976Y504370D02*
Y503583D01*
G01Y498071D02*
Y497283D01*
G01Y501220D02*
Y500433D01*
G01Y494921D02*
Y494134D01*
G01Y488622D02*
Y487835D01*
G01Y491772D02*
Y490984D01*
G01Y485472D02*
Y484685D01*
G01X87918D02*
Y485472D01*
G01Y487835D02*
Y488622D01*
G01Y490984D02*
Y491772D01*
G01Y494134D02*
Y494921D01*
G01Y497283D02*
Y498071D01*
G01Y500433D02*
Y501220D01*
G01Y503583D02*
Y504370D01*
G01X90754Y484685D02*
Y485472D01*
G01Y487835D02*
Y488622D01*
G01Y490984D02*
Y491772D01*
G01Y494134D02*
Y494921D01*
G01Y497283D02*
Y498071D01*
G01Y500433D02*
Y501220D01*
G01Y503583D02*
Y504370D01*
G01X90943D02*
Y503583D01*
G01Y498071D02*
Y497283D01*
G01Y501220D02*
Y500433D01*
G01Y494921D02*
Y494134D01*
G01Y488622D02*
Y487835D01*
G01Y491772D02*
Y490984D01*
G01Y485472D02*
Y484685D01*
G01X92717Y504370D02*
Y503583D01*
G01Y498071D02*
Y497283D01*
G01Y501220D02*
Y500433D01*
G01Y494921D02*
Y494134D01*
G01Y488622D02*
Y487835D01*
G01Y491772D02*
Y490984D01*
G01Y485472D02*
Y484685D01*
G01X51428Y503780D02*
X51417Y503681D01*
X51389Y503609D01*
X51351Y503583D01*
G01X51428Y500630D02*
X51417Y500531D01*
X51389Y500459D01*
X51351Y500433D01*
G01X51428Y497480D02*
X51417Y497382D01*
X51389Y497310D01*
X51351Y497283D01*
G01X51428Y494331D02*
X51417Y494232D01*
X51389Y494160D01*
X51351Y494134D01*
G01X51428Y491181D02*
X51417Y491083D01*
X51389Y491011D01*
X51351Y490984D01*
G01X51428Y488031D02*
X51417Y487933D01*
X51389Y487861D01*
X51351Y487835D01*
G01X51428Y484882D02*
X51417Y484783D01*
X51389Y484711D01*
X51351Y484685D01*
G01X51802D02*
X51829Y484689D01*
X51855Y484700D01*
X51879Y484718D01*
X51900Y484743D01*
X51917Y484772D01*
X51930Y484806D01*
X51938Y484843D01*
X51941Y484882D01*
G01X51802Y487835D02*
X51829Y487838D01*
X51855Y487849D01*
X51879Y487867D01*
X51900Y487892D01*
X51917Y487922D01*
X51930Y487956D01*
X51938Y487993D01*
X51941Y488031D01*
G01X51802Y490984D02*
X51829Y490988D01*
X51855Y490999D01*
X51879Y491017D01*
X51900Y491042D01*
X51917Y491072D01*
X51930Y491106D01*
X51938Y491142D01*
X51941Y491181D01*
G01X51802Y494134D02*
X51829Y494137D01*
X51855Y494148D01*
X51879Y494167D01*
X51900Y494191D01*
X51917Y494221D01*
X51930Y494255D01*
X51938Y494292D01*
X51941Y494331D01*
G01X51802Y497283D02*
X51829Y497287D01*
X51855Y497298D01*
X51879Y497316D01*
X51900Y497341D01*
X51917Y497371D01*
X51930Y497405D01*
X51938Y497441D01*
X51941Y497480D01*
G01X51802Y500433D02*
X51829Y500437D01*
X51855Y500448D01*
X51879Y500466D01*
X51900Y500491D01*
X51917Y500520D01*
X51930Y500554D01*
X51938Y500591D01*
X51941Y500630D01*
G01X51802Y503583D02*
X51829Y503586D01*
X51855Y503597D01*
X51879Y503615D01*
X51900Y503640D01*
X51917Y503670D01*
X51930Y503704D01*
X51938Y503741D01*
X51941Y503780D01*
G01X52112Y496476D02*
X51839Y495886D01*
G01X52112Y491476D02*
X51839Y490886D01*
G01X52112Y486476D02*
X51839Y485886D01*
G01X52529Y495886D02*
X52956Y496476D01*
G01X52529Y490886D02*
X52956Y491476D01*
G01X52529Y485886D02*
X52956Y486476D01*
G01X74331Y492854D02*
G03X74724Y492461I393J0D01*
G01Y490886D02*
G03X74331Y490492I1J-394D01*
G01Y487854D02*
G03X74724Y487461I393J0D01*
G01Y485886D02*
G03X74331Y485492I1J-394D01*
G01Y497854D02*
G03X74724Y497461I393J0D01*
G01Y495886D02*
G03X74331Y495492I1J-394D01*
G01X50560Y502461D02*
X50987Y501870D01*
G01X46369Y486476D02*
X46506Y486279D01*
X46644Y486082D01*
X46784Y485886D01*
G01X46369Y491476D02*
X46506Y491279D01*
X46644Y491082D01*
X46784Y490886D01*
G01X46369Y496476D02*
X46506Y496279D01*
X46644Y496082D01*
X46784Y495886D01*
G01X44401Y501476D02*
X44538Y501279D01*
X44676Y501082D01*
X44815Y500886D01*
G01X49871Y502461D02*
X50143Y501870D01*
G01X46753Y487835D02*
X46627Y487862D01*
X46538Y487935D01*
X46506Y488031D01*
G01Y484882D02*
X46538Y484785D01*
X46626Y484713D01*
X46753Y484685D01*
G01X46506Y491181D02*
X46538Y491084D01*
X46626Y491012D01*
X46753Y490984D01*
G01X46506Y494331D02*
X46538Y494233D01*
X46626Y494161D01*
X46753Y494134D01*
G01X46506Y497480D02*
X46538Y497383D01*
X46626Y497311D01*
X46753Y497283D01*
G01X46506Y500630D02*
X46538Y500533D01*
X46626Y500461D01*
X46753Y500433D01*
G01X46506Y503780D02*
X46538Y503682D01*
X46626Y503610D01*
X46753Y503583D01*
G01X44401Y501476D02*
Y501870D01*
G01X46369Y486476D02*
Y486870D01*
G01Y491476D02*
Y491870D01*
G01Y496476D02*
Y496870D01*
G01X46506Y504173D02*
Y503780D01*
G01Y501024D02*
Y500630D01*
G01Y497874D02*
Y497480D01*
G01Y494724D02*
Y494331D01*
G01Y491575D02*
Y491181D01*
G01Y488425D02*
Y488031D01*
G01Y485276D02*
Y484882D01*
G01X49019Y501476D02*
Y501870D01*
G01X50143D02*
Y501476D01*
G01X50987Y501870D02*
Y501476D01*
G01Y486476D02*
Y486870D01*
G01Y491476D02*
Y491870D01*
G01Y496476D02*
Y496870D01*
G01X46753Y484685D02*
X52838D01*
G01X53118Y484882D02*
X46506D01*
G01Y485276D02*
X53118D01*
G01X46753Y485472D02*
X52838D01*
G01X46784Y485886D02*
X52529D01*
G01X46369Y486476D02*
X52956D01*
G01Y486870D02*
X46369D01*
G01X52529Y487461D02*
X46784D01*
G01X46753Y487835D02*
X52838D01*
G01X53118Y488031D02*
X46506D01*
G01Y488425D02*
X53118D01*
G01X46753Y488622D02*
X52838D01*
G01X46784Y490886D02*
X52529D01*
G01X46753Y490984D02*
X52838D01*
G01X53118Y491181D02*
X46506D01*
G01X46369Y491476D02*
X52956D01*
G01X46506Y491575D02*
X53118D01*
G01X46753Y491772D02*
X52838D01*
G01X52956Y491870D02*
X46369D01*
G01X52529Y492461D02*
X46784D01*
G01X46753Y494134D02*
X52838D01*
G01X53118Y494331D02*
X46506D01*
G01Y494724D02*
X53118D01*
G01X46753Y494921D02*
X52838D01*
G01X46784Y495886D02*
X52529D01*
G01X46369Y496476D02*
X52956D01*
G01Y496870D02*
X46369D01*
G01X46753Y497283D02*
X52838D01*
G01X52529Y497461D02*
X46784D01*
G01X53118Y497480D02*
X46506D01*
G01Y497874D02*
X53118D01*
G01X46753Y498071D02*
X52838D01*
G01X71181Y498366D02*
X44488D01*
G01X46753Y500433D02*
X52838D01*
G01X53118Y500630D02*
X46506D01*
G01X44488Y500728D02*
X71181D01*
G01X44815Y500886D02*
X50560D01*
G01X46506Y501024D02*
X53118D01*
G01X46753Y501220D02*
X52838D01*
G01X44401Y501476D02*
X50987D01*
G01Y501870D02*
X44401D01*
G01X50560Y502461D02*
X44815D01*
G01X46753Y503583D02*
X52838D01*
G01X53118Y503780D02*
X46506D01*
G01Y504173D02*
X53118D01*
G01X46753Y504370D02*
X52838D01*
G01X50987Y486870D02*
X50909Y487461D01*
G01X49019Y501870D02*
X48941Y502461D01*
G01X50987Y491870D02*
X50909Y492461D01*
G01X50987Y496870D02*
X50909Y497461D01*
G01X49019Y501476D02*
X48941Y500886D01*
G01X50987Y496476D02*
X50909Y495886D01*
G01X50987Y491476D02*
X50909Y490886D01*
G01X50987Y486476D02*
X50909Y485886D01*
G01X46753Y485472D02*
X46626Y485444D01*
X46537Y485372D01*
X46506Y485276D01*
G01X46753Y491772D02*
X46626Y491744D01*
X46537Y491671D01*
X46506Y491575D01*
G01X46753Y494921D02*
X46626Y494893D01*
X46537Y494820D01*
X46506Y494724D01*
G01X46753Y498071D02*
X46626Y498043D01*
X46537Y497970D01*
X46506Y497874D01*
G01X46753Y501220D02*
X46626Y501193D01*
X46537Y501120D01*
X46506Y501024D01*
G01X46753Y504370D02*
X46626Y504342D01*
X46537Y504269D01*
X46506Y504173D01*
G01Y488425D02*
X46539Y488524D01*
X46628Y488595D01*
X46753Y488622D01*
G01X50143Y501476D02*
X49871Y500886D01*
G01X44815Y502461D02*
X44676Y502265D01*
X44538Y502068D01*
X44401Y501870D01*
G01X46784Y497461D02*
X46644Y497265D01*
X46506Y497068D01*
X46369Y496870D01*
G01X46784Y492461D02*
X46644Y492265D01*
X46506Y492068D01*
X46369Y491870D01*
G01X46784Y487461D02*
X46644Y487265D01*
X46506Y487068D01*
X46369Y486870D01*
G01X50560Y500886D02*
X50987Y501476D01*
G01X51351Y526417D02*
X51389Y526391D01*
X51417Y526319D01*
X51428Y526220D01*
G01X51351Y529567D02*
X51389Y529541D01*
X51417Y529469D01*
X51428Y529370D01*
G01X51351Y532717D02*
X51389Y532690D01*
X51417Y532618D01*
X51428Y532520D01*
G01X51351Y535866D02*
X51389Y535840D01*
X51417Y535768D01*
X51428Y535669D01*
G01X51351Y539016D02*
X51389Y538989D01*
X51417Y538917D01*
X51428Y538819D01*
G01X51351Y542165D02*
X51389Y542139D01*
X51417Y542067D01*
X51428Y541969D01*
G01X51351Y545315D02*
X51389Y545289D01*
X51417Y545217D01*
X51428Y545118D01*
G01X51351Y548465D02*
X51389Y548438D01*
X51417Y548366D01*
X51428Y548268D01*
G01X51351Y551614D02*
X51389Y551588D01*
X51417Y551516D01*
X51428Y551417D01*
G01X51351Y554764D02*
X51389Y554737D01*
X51417Y554665D01*
X51428Y554567D01*
G01X52529Y547461D02*
X52956Y546870D01*
G01X52529Y552461D02*
X52956Y551870D01*
G01X52529Y557461D02*
X52956Y556870D01*
G01X52597Y542461D02*
X53021Y541870D01*
G01X51839Y542461D02*
X52112Y541870D01*
G01X51839Y547461D02*
X52112Y546870D01*
G01X51839Y552461D02*
X52112Y551870D01*
G01X51839Y557461D02*
X52112Y556870D01*
G01X51941Y526220D02*
X51938Y526259D01*
X51930Y526295D01*
X51917Y526329D01*
X51900Y526359D01*
X51879Y526384D01*
X51856Y526402D01*
X51830Y526413D01*
X51802Y526417D01*
G01X51941Y529370D02*
X51938Y529408D01*
X51930Y529445D01*
X51917Y529479D01*
X51900Y529509D01*
X51879Y529533D01*
X51856Y529552D01*
X51830Y529563D01*
X51802Y529567D01*
G01X51941Y532520D02*
X51938Y532558D01*
X51930Y532594D01*
X51917Y532628D01*
X51900Y532659D01*
X51879Y532683D01*
X51856Y532701D01*
X51830Y532713D01*
X51802Y532717D01*
G01X51941Y535669D02*
X51938Y535707D01*
X51930Y535744D01*
X51917Y535778D01*
X51900Y535808D01*
X51879Y535833D01*
X51856Y535851D01*
X51830Y535862D01*
X51802Y535866D01*
G01X51941Y538819D02*
X51938Y538857D01*
X51930Y538894D01*
X51917Y538928D01*
X51900Y538958D01*
X51879Y538982D01*
X51856Y539000D01*
X51830Y539012D01*
X51802Y539016D01*
G01X51941Y541969D02*
X51938Y542007D01*
X51930Y542043D01*
X51917Y542077D01*
X51900Y542107D01*
X51879Y542132D01*
X51856Y542150D01*
X51830Y542161D01*
X51802Y542165D01*
G01X51941Y545118D02*
X51938Y545156D01*
X51930Y545193D01*
X51917Y545227D01*
X51900Y545257D01*
X51879Y545281D01*
X51856Y545300D01*
X51830Y545311D01*
X51802Y545315D01*
G01X51941Y548268D02*
X51938Y548306D01*
X51930Y548343D01*
X51917Y548376D01*
X51900Y548407D01*
X51879Y548431D01*
X51856Y548449D01*
X51830Y548461D01*
X51802Y548465D01*
G01X51941Y551417D02*
X51938Y551456D01*
X51930Y551492D01*
X51917Y551526D01*
X51900Y551556D01*
X51879Y551581D01*
X51856Y551599D01*
X51830Y551610D01*
X51802Y551614D01*
G01X51941Y554567D02*
X51938Y554605D01*
X51930Y554642D01*
X51917Y554676D01*
X51900Y554706D01*
X51879Y554730D01*
X51856Y554748D01*
X51830Y554760D01*
X51802Y554764D01*
G01X51428Y554567D02*
Y554173D01*
G01Y551417D02*
Y551024D01*
G01Y545118D02*
Y544724D01*
G01Y548268D02*
Y547874D01*
G01Y541969D02*
Y541575D01*
G01Y538819D02*
Y538425D01*
G01Y535669D02*
Y535276D01*
G01Y532520D02*
Y532126D01*
G01Y529370D02*
Y528976D01*
G01Y526220D02*
Y525827D01*
G01X51872Y537537D02*
Y536553D01*
G01Y534387D02*
Y533403D01*
G01Y531238D02*
Y530254D01*
G01Y528088D02*
Y527104D01*
G01X51941Y528976D02*
Y529370D01*
G01Y525827D02*
Y526220D01*
G01Y532126D02*
Y532520D01*
G01Y538425D02*
Y538819D01*
G01Y535276D02*
Y535669D01*
G01Y541575D02*
Y541969D01*
G01Y544724D02*
Y545118D01*
G01Y547874D02*
Y548268D01*
G01Y551024D02*
Y551417D01*
G01Y554173D02*
Y554567D01*
G01X52112Y556870D02*
Y556476D01*
G01Y551870D02*
Y551476D01*
G01Y546870D02*
Y546476D01*
G01Y541870D02*
Y541476D01*
G01X52814Y537537D02*
Y536553D01*
G01Y534387D02*
Y533403D01*
G01Y531238D02*
Y530254D01*
G01Y528088D02*
Y527104D01*
G01X52956Y556870D02*
Y556476D01*
G01Y551870D02*
Y551476D01*
G01Y546870D02*
Y546476D01*
G01X53021Y541870D02*
Y541476D01*
G01X53118Y528976D02*
Y529370D01*
G01Y525827D02*
Y526220D01*
G01Y532126D02*
Y532520D01*
G01Y538425D02*
Y538819D01*
G01Y535276D02*
Y535669D01*
G01Y541575D02*
Y541969D01*
G01Y544724D02*
Y545118D01*
G01Y547874D02*
Y548268D01*
G01Y551024D02*
Y551417D01*
G01Y554173D02*
Y554567D01*
G01X76222Y525433D02*
X75237D01*
G01X82220Y525551D02*
X80337D01*
G01X92717Y525630D02*
X85384D01*
G01X85237D02*
X73228D01*
G01X85237Y526417D02*
X73228D01*
G01X85384D02*
X92717D01*
G01X76222Y526614D02*
X75237D01*
G01X76222Y526811D02*
X75237D01*
G01X74331Y527008D02*
X80356D01*
G01X74331Y528189D02*
X80356D01*
G01X76222Y528386D02*
X75237D01*
G01X76222Y528583D02*
X75237D01*
G01X92717Y528780D02*
X85384D01*
G01X85237D02*
X73228D01*
G01X85237Y529567D02*
X73228D01*
G01X85384D02*
X92717D01*
G01X76222Y529764D02*
X75237D01*
G01X76222Y529961D02*
X75237D01*
G01X74331Y530157D02*
X80356D01*
G01X74331Y531339D02*
X80356D01*
G01X76222Y531535D02*
X75237D01*
G01X76222Y531732D02*
X75237D01*
G01X92717Y531929D02*
X85384D01*
G01X85237D02*
X73228D01*
G01X85237Y532717D02*
X73228D01*
G01X85384D02*
X92717D01*
G01X82220Y532795D02*
X80337D01*
G01X76222Y532913D02*
X75237D01*
G01X76222Y533110D02*
X75237D01*
G01X74331Y533307D02*
X80356D01*
G01X74331Y534488D02*
X80356D01*
G01X76222Y534685D02*
X75237D01*
G01X76222Y534882D02*
X75237D01*
G01X82220Y535000D02*
X80337D01*
G01X92717Y535079D02*
X85384D01*
G01X85237D02*
X73228D01*
G01X85237Y535866D02*
X73228D01*
G01X85384D02*
X92717D01*
G01X76222Y536063D02*
X75237D01*
G01X76222Y536260D02*
X75237D01*
G01X74331Y536457D02*
X80356D01*
G01X74331Y537638D02*
X80356D01*
G01X76222Y537835D02*
X75237D01*
G01X76222Y538031D02*
X75237D01*
G01X92717Y538228D02*
X85384D01*
G01X85237D02*
X73228D01*
G01X78346Y538327D02*
X76222D01*
G01X73228Y538819D02*
X80763D01*
G01X74331Y538937D02*
X73228D01*
G01X85237Y539016D02*
X73228D01*
G01X85384D02*
X92717D01*
G01X77756Y540098D02*
X76772D01*
G01X77756Y540295D02*
X76772D01*
G01X77756Y540689D02*
X76772D01*
G01X74724Y540886D02*
X81890D01*
G01X92717Y541378D02*
X85384D01*
G01X85237D02*
X73228D01*
G01X85237Y542165D02*
X73228D01*
G01X85384D02*
X92717D01*
G01X74724Y542461D02*
X81890D01*
G01X77756Y542657D02*
X76772D01*
G01X77756Y543051D02*
X76772D01*
G01X77756Y543248D02*
X76772D01*
G01X92717Y544528D02*
X85384D01*
G01X85237D02*
X73228D01*
G01X77756Y545098D02*
X76772D01*
G01X77756Y545295D02*
X76772D01*
G01X85237Y545315D02*
X73228D01*
G01X85384D02*
X92717D01*
G01X77756Y545689D02*
X76772D01*
G01X74724Y545886D02*
X81890D01*
G01X51724Y528285D02*
X51753Y528281D01*
X51781Y528270D01*
X51806Y528252D01*
X51829Y528228D01*
X51847Y528198D01*
X51861Y528164D01*
X51869Y528127D01*
X51872Y528088D01*
G01X51724Y531435D02*
X51753Y531431D01*
X51781Y531420D01*
X51806Y531402D01*
X51829Y531377D01*
X51847Y531347D01*
X51861Y531313D01*
X51869Y531277D01*
X51872Y531238D01*
G01X51724Y534584D02*
X51753Y534581D01*
X51781Y534569D01*
X51806Y534552D01*
X51829Y534527D01*
X51847Y534497D01*
X51861Y534463D01*
X51869Y534426D01*
X51872Y534387D01*
G01X51724Y537734D02*
X51753Y537730D01*
X51781Y537719D01*
X51806Y537701D01*
X51829Y537676D01*
X51847Y537646D01*
X51861Y537613D01*
X51869Y537576D01*
X51872Y537537D01*
G01X69213Y541280D02*
Y556516D01*
G01X75170Y554764D02*
Y553976D01*
G01Y551614D02*
Y550827D01*
G01Y545315D02*
Y544528D01*
G01Y548465D02*
Y547677D01*
G01Y542165D02*
Y541378D01*
G01Y535866D02*
Y535079D01*
G01Y539016D02*
Y538228D01*
G01Y532717D02*
Y531929D01*
G01Y526417D02*
Y525630D01*
G01Y529567D02*
Y528780D01*
G01X75197Y554764D02*
Y553976D01*
G01Y551614D02*
Y550827D01*
G01Y545315D02*
Y544528D01*
G01Y548465D02*
Y547677D01*
G01Y542165D02*
Y541378D01*
G01Y535866D02*
Y535079D01*
G01Y539016D02*
Y538228D01*
G01Y532717D02*
Y531929D01*
G01Y526417D02*
Y525630D01*
G01Y529567D02*
Y528780D01*
G01X75237Y535079D02*
Y532717D01*
G01Y538228D02*
Y535866D01*
G01Y531929D02*
Y529567D01*
G01Y528780D02*
Y526417D01*
G01X75573Y554764D02*
Y553976D01*
G01Y551614D02*
Y550827D01*
G01Y545315D02*
Y544528D01*
G01Y548465D02*
Y547677D01*
G01Y542165D02*
Y541378D01*
G01Y535866D02*
Y535079D01*
G01Y539016D02*
Y538228D01*
G01Y532717D02*
Y531929D01*
G01Y526417D02*
Y525630D01*
G01Y529567D02*
Y528780D01*
G01X75787Y557461D02*
Y555886D01*
G01Y552461D02*
Y550886D01*
G01Y547461D02*
Y545886D01*
G01Y542461D02*
Y540886D01*
G01X76772Y558248D02*
Y555098D01*
G01Y553248D02*
Y550098D01*
G01Y548248D02*
Y545098D01*
G01Y543248D02*
Y540098D01*
G01X77206Y537638D02*
Y536457D01*
G01Y531339D02*
Y530157D01*
G01Y534488D02*
Y533307D01*
G01Y528189D02*
Y527008D01*
G01X77756Y558248D02*
Y555098D01*
G01Y553248D02*
Y550098D01*
G01Y548248D02*
Y545098D01*
G01Y543248D02*
Y540098D01*
G01X78740Y557461D02*
Y555886D01*
G01Y552461D02*
Y550886D01*
G01Y547461D02*
Y545886D01*
G01Y542461D02*
Y540886D01*
G01X78935Y525630D02*
Y526417D01*
G01Y528780D02*
Y529567D01*
G01Y531929D02*
Y532717D01*
G01Y535079D02*
Y535866D01*
G01Y538228D02*
Y539016D01*
G01Y541378D02*
Y542165D01*
G01Y544528D02*
Y545315D01*
G01Y547677D02*
Y548465D01*
G01Y550827D02*
Y551614D01*
G01Y553976D02*
Y554764D01*
G01X80337Y532795D02*
Y535000D01*
G01X80356Y527008D02*
Y528189D01*
G01Y530157D02*
Y531339D01*
G01Y533307D02*
Y534488D01*
G01Y536457D02*
Y537638D01*
G01X80763Y538819D02*
Y535000D01*
G01Y532795D02*
Y525551D01*
G01X80919Y525630D02*
Y526417D01*
G01Y528780D02*
Y529567D01*
G01Y531929D02*
Y532717D01*
G01Y535079D02*
Y535866D01*
G01Y538228D02*
Y539016D01*
G01Y541378D02*
Y542165D01*
G01Y544528D02*
Y545315D01*
G01Y547677D02*
Y548465D01*
G01Y550827D02*
Y551614D01*
G01Y553976D02*
Y554764D01*
G01X81890Y540886D02*
Y542461D01*
G01Y545886D02*
Y547461D01*
G01Y550886D02*
Y552461D01*
G01Y555886D02*
Y557461D01*
G01X82220Y535000D02*
Y532795D01*
G01X82570Y554764D02*
Y553976D01*
G01Y551614D02*
Y550827D01*
G01Y545315D02*
Y544528D01*
G01Y548465D02*
Y547677D01*
G01Y542165D02*
Y541378D01*
G01Y535866D02*
Y535079D01*
G01Y539016D02*
Y538228D01*
G01Y532717D02*
Y531929D01*
G01Y526417D02*
Y525630D01*
G01Y529567D02*
Y528780D01*
G01X84298Y526417D02*
Y528780D01*
G01Y529567D02*
Y531929D01*
G01Y532717D02*
Y535079D01*
G01Y535866D02*
Y538228D01*
G01Y539016D02*
Y541378D01*
G01Y542165D02*
Y544528D01*
G01Y545315D02*
Y547677D01*
G01Y548465D02*
Y550827D01*
G01Y551614D02*
Y553976D01*
G01Y554764D02*
Y557126D01*
G01X85237Y554764D02*
Y553976D01*
G01Y551614D02*
Y550827D01*
G01Y545315D02*
Y544528D01*
G01Y548465D02*
Y547677D01*
G01Y542165D02*
Y541378D01*
G01Y535866D02*
Y535079D01*
G01Y539016D02*
Y538228D01*
G01Y532717D02*
Y531929D01*
G01Y526417D02*
Y525630D01*
G01Y529567D02*
Y528780D01*
G01X85384Y554764D02*
Y553976D01*
G01Y551614D02*
Y550827D01*
G01Y545315D02*
Y544528D01*
G01Y548465D02*
Y547677D01*
G01Y542165D02*
Y541378D01*
G01Y535866D02*
Y535079D01*
G01Y539016D02*
Y538228D01*
G01Y532717D02*
Y531929D01*
G01Y526417D02*
Y525630D01*
G01Y529567D02*
Y528780D01*
G01X86976Y554764D02*
Y553976D01*
G01Y551614D02*
Y550827D01*
G01Y545315D02*
Y544528D01*
G01Y548465D02*
Y547677D01*
G01Y542165D02*
Y541378D01*
G01Y535866D02*
Y535079D01*
G01Y539016D02*
Y538228D01*
G01Y532717D02*
Y531929D01*
G01Y526417D02*
Y525630D01*
G01Y529567D02*
Y528780D01*
G01X87918Y525630D02*
Y526417D01*
G01Y528780D02*
Y529567D01*
G01Y531929D02*
Y532717D01*
G01Y535079D02*
Y535866D01*
G01Y538228D02*
Y539016D01*
G01Y541378D02*
Y542165D01*
G01Y544528D02*
Y545315D01*
G01Y547677D02*
Y548465D01*
G01Y550827D02*
Y551614D01*
G01Y553976D02*
Y554764D01*
G01X90754Y525630D02*
Y526417D01*
G01Y528780D02*
Y529567D01*
G01Y531929D02*
Y532717D01*
G01Y535079D02*
Y535866D01*
G01Y538228D02*
Y539016D01*
G01Y541378D02*
Y542165D01*
G01Y544528D02*
Y545315D01*
G01Y547677D02*
Y548465D01*
G01Y550827D02*
Y551614D01*
G01Y553976D02*
Y554764D01*
G01X90943D02*
Y553976D01*
G01Y551614D02*
Y550827D01*
G01Y545315D02*
Y544528D01*
G01Y548465D02*
Y547677D01*
G01Y542165D02*
Y541378D01*
G01Y535866D02*
Y535079D01*
G01Y539016D02*
Y538228D01*
G01Y532717D02*
Y531929D01*
G01Y526417D02*
Y525630D01*
G01Y529567D02*
Y528780D01*
G01X92717Y554764D02*
Y553976D01*
G01Y551614D02*
Y550827D01*
G01Y545315D02*
Y544528D01*
G01Y548465D02*
Y547677D01*
G01Y542165D02*
Y541378D01*
G01Y535866D02*
Y535079D01*
G01Y539016D02*
Y538228D01*
G01Y532717D02*
Y531929D01*
G01Y526417D02*
Y525630D01*
G01Y529567D02*
Y528780D01*
G01X51872Y536553D02*
X51869Y536515D01*
X51861Y536478D01*
X51847Y536444D01*
X51829Y536414D01*
X51807Y536389D01*
X51781Y536371D01*
X51754Y536360D01*
X51724Y536356D01*
G01X51872Y533403D02*
X51869Y533365D01*
X51861Y533328D01*
X51847Y533294D01*
X51829Y533264D01*
X51807Y533240D01*
X51781Y533222D01*
X51754Y533210D01*
X51724Y533206D01*
G01X51872Y530254D02*
X51869Y530215D01*
X51861Y530179D01*
X51847Y530145D01*
X51829Y530115D01*
X51807Y530090D01*
X51781Y530072D01*
X51754Y530061D01*
X51724Y530057D01*
G01X51872Y527104D02*
X51869Y527066D01*
X51861Y527029D01*
X51847Y526995D01*
X51829Y526965D01*
X51807Y526941D01*
X51781Y526922D01*
X51754Y526911D01*
X51724Y526907D01*
G01X51428Y551024D02*
X51417Y550925D01*
X51389Y550853D01*
X51351Y550827D01*
G01X51428Y547874D02*
X51417Y547776D01*
X51389Y547704D01*
X51351Y547677D01*
G01X51428Y538425D02*
X51417Y538327D01*
X51389Y538255D01*
X51351Y538228D01*
G01X51428Y535276D02*
X51417Y535177D01*
X51389Y535105D01*
X51351Y535079D01*
G01X51428Y532126D02*
X51417Y532028D01*
X51389Y531956D01*
X51351Y531929D01*
G01X51428Y528976D02*
X51417Y528878D01*
X51389Y528806D01*
X51351Y528780D01*
G01X51802Y525630D02*
X51829Y525633D01*
X51855Y525644D01*
X51879Y525663D01*
X51900Y525687D01*
X51917Y525717D01*
X51930Y525751D01*
X51938Y525788D01*
X51941Y525827D01*
G01X51802Y528780D02*
X51829Y528783D01*
X51855Y528794D01*
X51879Y528812D01*
X51900Y528837D01*
X51917Y528867D01*
X51930Y528901D01*
X51938Y528937D01*
X51941Y528976D01*
G01X51802Y531929D02*
X51829Y531933D01*
X51855Y531944D01*
X51879Y531962D01*
X51900Y531987D01*
X51917Y532017D01*
X51930Y532050D01*
X51938Y532087D01*
X51941Y532126D01*
G01X51802Y535079D02*
X51829Y535082D01*
X51855Y535093D01*
X51879Y535111D01*
X51900Y535136D01*
X51917Y535166D01*
X51930Y535200D01*
X51938Y535237D01*
X51941Y535276D01*
G01X51802Y538228D02*
X51829Y538232D01*
X51855Y538243D01*
X51879Y538261D01*
X51900Y538286D01*
X51917Y538316D01*
X51930Y538350D01*
X51938Y538386D01*
X51941Y538425D01*
G01X51802Y541378D02*
X51829Y541381D01*
X51855Y541393D01*
X51879Y541411D01*
X51900Y541435D01*
X51917Y541465D01*
X51930Y541499D01*
X51938Y541536D01*
X51941Y541575D01*
G01X51802Y544528D02*
X51829Y544531D01*
X51855Y544542D01*
X51879Y544560D01*
X51900Y544585D01*
X51917Y544615D01*
X51930Y544649D01*
X51938Y544685D01*
X51941Y544724D01*
G01X51802Y547677D02*
X51829Y547681D01*
X51855Y547692D01*
X51879Y547710D01*
X51900Y547735D01*
X51917Y547765D01*
X51930Y547798D01*
X51938Y547835D01*
X51941Y547874D01*
G01X51802Y550827D02*
X51829Y550830D01*
X51855Y550841D01*
X51879Y550859D01*
X51900Y550884D01*
X51917Y550914D01*
X51930Y550948D01*
X51938Y550985D01*
X51941Y551024D01*
G01X51802Y553976D02*
X51829Y553980D01*
X51855Y553991D01*
X51879Y554009D01*
X51900Y554034D01*
X51917Y554064D01*
X51930Y554098D01*
X51938Y554134D01*
X51941Y554173D01*
G01X74724Y547461D02*
X81890D01*
G01X77756Y547657D02*
X76772D01*
G01X92717Y547677D02*
X85384D01*
G01X85237D02*
X73228D01*
G01X77756Y548051D02*
X76772D01*
G01X77756Y548248D02*
X76772D01*
G01X85237Y548465D02*
X73228D01*
G01X85384D02*
X92717D01*
G01X77756Y550098D02*
X76772D01*
G01X77756Y550295D02*
X76772D01*
G01X77756Y550689D02*
X76772D01*
G01X92717Y550827D02*
X85384D01*
G01X85237D02*
X73228D01*
G01X74724Y550886D02*
X81890D01*
G01X85237Y551614D02*
X73228D01*
G01X85384D02*
X92717D01*
G01X74724Y552461D02*
X81890D01*
G01X77756Y552657D02*
X76772D01*
G01X77756Y553051D02*
X76772D01*
G01X77756Y553248D02*
X76772D01*
G01X92717Y553976D02*
X85384D01*
G01X85237D02*
X73228D01*
G01X85237Y554764D02*
X73228D01*
G01X85384D02*
X92717D01*
G01X77756Y555098D02*
X76772D01*
G01X77756Y555295D02*
X76772D01*
G01X77756Y555689D02*
X76772D01*
G01X74724Y555886D02*
X81890D01*
G01X52112Y556476D02*
X51839Y555886D01*
G01X52112Y551476D02*
X51839Y550886D01*
G01X52112Y546476D02*
X51839Y545886D01*
G01X52112Y541476D02*
X51839Y540886D01*
G01X52597D02*
X53021Y541476D01*
G01X52529Y555886D02*
X52956Y556476D01*
G01X52529Y550886D02*
X52956Y551476D01*
G01X52529Y545886D02*
X52956Y546476D01*
G01X51351Y553976D02*
X51389Y554003D01*
X51417Y554075D01*
X51428Y554173D01*
G01X51351Y544528D02*
X51389Y544554D01*
X51417Y544626D01*
X51428Y544724D01*
G01X51351Y541378D02*
X51389Y541404D01*
X51417Y541476D01*
X51428Y541575D01*
G01X51351Y525630D02*
X51389Y525656D01*
X51417Y525728D01*
X51428Y525827D01*
G01X74724Y555886D02*
G03X74331Y555492I1J-394D01*
G01Y552854D02*
G03X74724Y552461I393J0D01*
G01Y550886D02*
G03X74331Y550492I1J-394D01*
G01Y547854D02*
G03X74724Y547461I393J0D01*
G01Y545886D02*
G03X74331Y545492I1J-394D01*
G01Y542854D02*
G03X74724Y542461I393J0D01*
G01Y540886D02*
G03X74331Y540492I1J-394D01*
G01X51351Y507520D02*
X51389Y507493D01*
X51417Y507421D01*
X51428Y507323D01*
G01X51351Y510669D02*
X51389Y510643D01*
X51417Y510571D01*
X51428Y510472D01*
G01X51351Y513819D02*
X51389Y513793D01*
X51417Y513720D01*
X51428Y513622D01*
G01X51351Y516969D02*
X51389Y516942D01*
X51417Y516870D01*
X51428Y516772D01*
G01X51351Y520118D02*
X51389Y520092D01*
X51417Y520020D01*
X51428Y519921D01*
G01X51351Y523268D02*
X51389Y523241D01*
X51417Y523169D01*
X51428Y523071D01*
G01X52529Y507461D02*
X52956Y506870D01*
G01X52529Y512461D02*
X52956Y511870D01*
G01X52597Y517461D02*
X53021Y516870D01*
G01X51839Y507461D02*
X52112Y506870D01*
G01X51839Y512461D02*
X52112Y511870D01*
G01X51839Y517461D02*
X52112Y516870D01*
G01X51724Y521986D02*
X51753Y521982D01*
X51781Y521971D01*
X51806Y521953D01*
X51829Y521928D01*
X51847Y521898D01*
X51861Y521865D01*
X51869Y521828D01*
X51872Y521789D01*
G01X51724Y525135D02*
X51753Y525132D01*
X51781Y525120D01*
X51806Y525103D01*
X51829Y525078D01*
X51847Y525048D01*
X51861Y525014D01*
X51869Y524978D01*
X51872Y524939D01*
G01X51941Y507323D02*
X51938Y507361D01*
X51930Y507398D01*
X51917Y507431D01*
X51900Y507462D01*
X51879Y507486D01*
X51856Y507504D01*
X51830Y507516D01*
X51802Y507520D01*
G01X51941Y510472D02*
X51938Y510511D01*
X51930Y510547D01*
X51917Y510581D01*
X51900Y510611D01*
X51879Y510636D01*
X51856Y510654D01*
X51830Y510665D01*
X51802Y510669D01*
G01X51941Y513622D02*
X51938Y513660D01*
X51930Y513697D01*
X51917Y513731D01*
X51900Y513761D01*
X51879Y513785D01*
X51856Y513804D01*
X51830Y513815D01*
X51802Y513819D01*
G01X51941Y516772D02*
X51938Y516810D01*
X51930Y516846D01*
X51917Y516880D01*
X51900Y516911D01*
X51879Y516935D01*
X51856Y516953D01*
X51830Y516965D01*
X51802Y516969D01*
G01X51941Y519921D02*
X51938Y519959D01*
X51930Y519996D01*
X51917Y520030D01*
X51900Y520060D01*
X51879Y520085D01*
X51856Y520103D01*
X51830Y520114D01*
X51802Y520118D01*
G01X51941Y523071D02*
X51938Y523109D01*
X51930Y523146D01*
X51917Y523180D01*
X51900Y523210D01*
X51879Y523234D01*
X51856Y523252D01*
X51830Y523264D01*
X51802Y523268D01*
G01X51428Y523071D02*
Y522677D01*
G01Y516772D02*
Y516378D01*
G01Y519921D02*
Y519528D01*
G01Y513622D02*
Y513228D01*
G01Y507323D02*
Y506929D01*
G01Y510472D02*
Y510079D01*
G01X51872Y521789D02*
Y520805D01*
G01Y524939D02*
Y523954D01*
G01X51941Y506929D02*
Y507323D01*
G01Y510079D02*
Y510472D01*
G01Y513228D02*
Y513622D01*
G01Y516378D02*
Y516772D01*
G01Y519528D02*
Y519921D01*
G01Y522677D02*
Y523071D01*
G01X52112Y516870D02*
Y516476D01*
G01Y511870D02*
Y511476D01*
G01Y506870D02*
Y506476D01*
G01X52814Y521789D02*
Y520805D01*
G01Y524939D02*
Y523954D01*
G01X52956Y511870D02*
Y511476D01*
G01Y506870D02*
Y506476D01*
G01X53021Y516870D02*
Y516476D01*
G01X53118Y506929D02*
Y507323D01*
G01Y510079D02*
Y510472D01*
G01Y513228D02*
Y513622D01*
G01Y516378D02*
Y516772D01*
G01Y519528D02*
Y519921D01*
G01Y522677D02*
Y523071D01*
G01X77756Y505295D02*
X76772D01*
G01X77756Y505689D02*
X76772D01*
G01X74724Y505886D02*
X81890D01*
G01X92717Y506732D02*
X85384D01*
G01X85237D02*
X73228D01*
G01X74724Y507461D02*
X81890D01*
G01X85237Y507520D02*
X73228D01*
G01X85384D02*
X92717D01*
G01X77756Y507657D02*
X76772D01*
G01X77756Y508051D02*
X76772D01*
G01X77756Y508248D02*
X76772D01*
G01X92717Y509882D02*
X85384D01*
G01X85237D02*
X73228D01*
G01X77756Y510098D02*
X76772D01*
G01X77756Y510295D02*
X76772D01*
G01X85237Y510669D02*
X73228D01*
G01X85384D02*
X92717D01*
G01X77756Y510689D02*
X76772D01*
G01X74724Y510886D02*
X81890D01*
G01X74724Y512461D02*
X81890D01*
G01X77756Y512657D02*
X76772D01*
G01X92717Y513031D02*
X85384D01*
G01X85237D02*
X73228D01*
G01X77756Y513051D02*
X76772D01*
G01X77756Y513248D02*
X76772D01*
G01X85237Y513819D02*
X73228D01*
G01X85384D02*
X92717D01*
G01X77756Y515098D02*
X76772D01*
G01X77756Y515295D02*
X76772D01*
G01X77756Y515689D02*
X76772D01*
G01X74724Y515886D02*
X81890D01*
G01X92717Y516181D02*
X85384D01*
G01X85237D02*
X73228D01*
G01X85237Y516969D02*
X73228D01*
G01X85384D02*
X92717D01*
G01X74724Y517461D02*
X81890D01*
G01X77756Y517657D02*
X76772D01*
G01X77756Y518051D02*
X76772D01*
G01X77756Y518248D02*
X76772D01*
G01X92717Y519331D02*
X85384D01*
G01X85237D02*
X73228D01*
G01X74331Y519409D02*
X73228D01*
G01Y519528D02*
X80763D01*
G01X76222Y520020D02*
X78346D01*
G01X85237Y520118D02*
X73228D01*
G01X85384D02*
X92717D01*
G01X76222Y520315D02*
X75237D01*
G01X76222Y520512D02*
X75237D01*
G01X74331Y520709D02*
X80356D01*
G01X74331Y521890D02*
X80356D01*
G01X76222Y522087D02*
X75237D01*
G01X76222Y522283D02*
X75237D01*
G01X92717Y522480D02*
X85384D01*
G01X85237D02*
X73228D01*
G01X85237Y523268D02*
X73228D01*
G01X85384D02*
X92717D01*
G01X82220Y523346D02*
X80337D01*
G01X76222Y523465D02*
X75237D01*
G01X76222Y523661D02*
X75237D01*
G01X74331Y523858D02*
X80356D01*
G01X74331Y525039D02*
X80356D01*
G01X76222Y525236D02*
X75237D01*
G01X69213Y519429D02*
Y538917D01*
G01X74409Y519528D02*
Y538819D01*
G01X74724D02*
Y519528D01*
G01X75170Y523268D02*
Y522480D01*
G01Y516969D02*
Y516181D01*
G01Y520118D02*
Y519331D01*
G01Y513819D02*
Y513031D01*
G01Y507520D02*
Y506732D01*
G01Y510669D02*
Y509882D01*
G01X75197Y523268D02*
Y522480D01*
G01Y516969D02*
Y516181D01*
G01Y520118D02*
Y519331D01*
G01Y513819D02*
Y513031D01*
G01Y507520D02*
Y506732D01*
G01Y510669D02*
Y509882D01*
G01X75237Y525630D02*
Y523268D01*
G01Y522480D02*
Y520118D01*
G01X75512Y538819D02*
Y519528D01*
G01X75573Y523268D02*
Y522480D01*
G01Y516969D02*
Y516181D01*
G01Y520118D02*
Y519331D01*
G01Y513819D02*
Y513031D01*
G01Y507520D02*
Y506732D01*
G01Y510669D02*
Y509882D01*
G01X75787Y517461D02*
Y515886D01*
G01Y512461D02*
Y510886D01*
G01Y507461D02*
Y505886D01*
G01X76012Y519528D02*
Y538819D01*
G01X76222Y538327D02*
Y520020D01*
G01X76772Y518248D02*
Y515098D01*
G01Y513248D02*
Y510098D01*
G01X76929Y538819D02*
Y519528D01*
G01X77206Y525039D02*
Y523858D01*
G01Y521890D02*
Y520709D01*
G01X77756Y518248D02*
Y515098D01*
G01Y513248D02*
Y510098D01*
G01X78740Y517461D02*
Y515886D01*
G01Y512461D02*
Y510886D01*
G01Y507461D02*
Y505886D01*
G01X78935Y506732D02*
Y507520D01*
G01Y509882D02*
Y510669D01*
G01Y513031D02*
Y513819D01*
G01Y516181D02*
Y516969D01*
G01Y519331D02*
Y520118D01*
G01Y522480D02*
Y523268D01*
G01X80285Y538819D02*
Y519528D01*
G01X80337Y523346D02*
Y525551D01*
G01X80356Y523858D02*
Y525039D01*
G01Y520709D02*
Y521890D01*
G01X80763Y523346D02*
Y519528D01*
G01X80919Y506732D02*
Y507520D01*
G01Y509882D02*
Y510669D01*
G01Y513031D02*
Y513819D01*
G01Y516181D02*
Y516969D01*
G01Y519331D02*
Y520118D01*
G01Y522480D02*
Y523268D01*
G01X81890Y505886D02*
Y507461D01*
G01Y510886D02*
Y512461D01*
G01Y515886D02*
Y517461D01*
G01X82220Y525551D02*
Y523346D01*
G01X82570Y523268D02*
Y522480D01*
G01Y516969D02*
Y516181D01*
G01Y520118D02*
Y519331D01*
G01Y513819D02*
Y513031D01*
G01Y507520D02*
Y506732D01*
G01Y510669D02*
Y509882D01*
G01X84298Y507520D02*
Y509882D01*
G01Y510669D02*
Y513031D01*
G01Y513819D02*
Y516181D01*
G01Y516969D02*
Y519331D01*
G01Y520118D02*
Y522480D01*
G01Y523268D02*
Y525630D01*
G01X85237Y523268D02*
Y522480D01*
G01Y516969D02*
Y516181D01*
G01Y520118D02*
Y519331D01*
G01Y513819D02*
Y513031D01*
G01Y507520D02*
Y506732D01*
G01Y510669D02*
Y509882D01*
G01X85384Y523268D02*
Y522480D01*
G01Y516969D02*
Y516181D01*
G01Y520118D02*
Y519331D01*
G01Y513819D02*
Y513031D01*
G01Y507520D02*
Y506732D01*
G01Y510669D02*
Y509882D01*
G01X86976Y523268D02*
Y522480D01*
G01Y516969D02*
Y516181D01*
G01Y520118D02*
Y519331D01*
G01Y513819D02*
Y513031D01*
G01Y507520D02*
Y506732D01*
G01Y510669D02*
Y509882D01*
G01X87918Y506732D02*
Y507520D01*
G01Y509882D02*
Y510669D01*
G01Y513031D02*
Y513819D01*
G01Y516181D02*
Y516969D01*
G01Y519331D02*
Y520118D01*
G01Y522480D02*
Y523268D01*
G01X90754Y506732D02*
Y507520D01*
G01Y509882D02*
Y510669D01*
G01Y513031D02*
Y513819D01*
G01Y516181D02*
Y516969D01*
G01Y519331D02*
Y520118D01*
G01Y522480D02*
Y523268D01*
G01X90943D02*
Y522480D01*
G01Y516969D02*
Y516181D01*
G01Y520118D02*
Y519331D01*
G01Y513819D02*
Y513031D01*
G01Y507520D02*
Y506732D01*
G01Y510669D02*
Y509882D01*
G01X92717Y523268D02*
Y522480D01*
G01Y516969D02*
Y516181D01*
G01Y520118D02*
Y519331D01*
G01Y513819D02*
Y513031D01*
G01Y507520D02*
Y506732D01*
G01Y510669D02*
Y509882D01*
G01X51872Y523954D02*
X51869Y523916D01*
X51861Y523880D01*
X51847Y523846D01*
X51829Y523815D01*
X51807Y523791D01*
X51781Y523773D01*
X51754Y523761D01*
X51724Y523757D01*
G01X51872Y520805D02*
X51869Y520767D01*
X51861Y520730D01*
X51847Y520696D01*
X51829Y520666D01*
X51807Y520641D01*
X51781Y520623D01*
X51754Y520612D01*
X51724Y520608D01*
G01X51428Y522677D02*
X51417Y522579D01*
X51389Y522507D01*
X51351Y522480D01*
G01X51428Y519528D02*
X51417Y519429D01*
X51389Y519357D01*
X51351Y519331D01*
G01X51428Y516378D02*
X51417Y516280D01*
X51389Y516207D01*
X51351Y516181D01*
G01X51428Y513228D02*
X51417Y513130D01*
X51389Y513058D01*
X51351Y513031D01*
G01X51428Y510079D02*
X51417Y509980D01*
X51389Y509908D01*
X51351Y509882D01*
G01X51428Y506929D02*
X51417Y506831D01*
X51389Y506759D01*
X51351Y506732D01*
G01X51802D02*
X51829Y506736D01*
X51855Y506747D01*
X51879Y506765D01*
X51900Y506790D01*
X51917Y506820D01*
X51930Y506854D01*
X51938Y506890D01*
X51941Y506929D01*
G01X51802Y509882D02*
X51829Y509885D01*
X51855Y509896D01*
X51879Y509915D01*
X51900Y509939D01*
X51917Y509969D01*
X51930Y510003D01*
X51938Y510040D01*
X51941Y510079D01*
G01X51802Y513031D02*
X51829Y513035D01*
X51855Y513046D01*
X51879Y513064D01*
X51900Y513089D01*
X51917Y513119D01*
X51930Y513153D01*
X51938Y513189D01*
X51941Y513228D01*
G01X51802Y516181D02*
X51829Y516185D01*
X51855Y516196D01*
X51879Y516214D01*
X51900Y516239D01*
X51917Y516269D01*
X51930Y516302D01*
X51938Y516339D01*
X51941Y516378D01*
G01X51802Y519331D02*
X51829Y519334D01*
X51855Y519345D01*
X51879Y519363D01*
X51900Y519388D01*
X51917Y519418D01*
X51930Y519452D01*
X51938Y519489D01*
X51941Y519528D01*
G01X51802Y522480D02*
X51829Y522484D01*
X51855Y522495D01*
X51879Y522513D01*
X51900Y522538D01*
X51917Y522568D01*
X51930Y522602D01*
X51938Y522638D01*
X51941Y522677D01*
G01X52112Y516476D02*
X51839Y515886D01*
G01X52112Y511476D02*
X51839Y510886D01*
G01X52112Y506476D02*
X51839Y505886D01*
G01X52597Y515886D02*
X53021Y516476D01*
G01X52529Y510886D02*
X52956Y511476D01*
G01X52529Y505886D02*
X52956Y506476D01*
G01X74331Y517854D02*
G03X74724Y517461I393J0D01*
G01Y515886D02*
G03X74331Y515492I1J-394D01*
G01Y507854D02*
G03X74724Y507461I393J0D01*
G01Y505886D02*
G03X74331Y505492I1J-394D01*
G01Y512854D02*
G03X74724Y512461I393J0D01*
G01Y510886D02*
G03X74331Y510492I1J-394D01*
G01X50687Y528285D02*
X50694Y528281D01*
X50700Y528270D01*
X50706Y528252D01*
X50711Y528228D01*
X50715Y528198D01*
X50718Y528164D01*
X50720Y528127D01*
Y528088D01*
G01X50687Y531435D02*
X50694Y531431D01*
X50700Y531420D01*
X50706Y531402D01*
X50711Y531377D01*
X50715Y531347D01*
X50718Y531313D01*
X50720Y531277D01*
Y531238D01*
G01X50687Y534584D02*
X50694Y534581D01*
X50700Y534569D01*
X50706Y534552D01*
X50711Y534527D01*
X50715Y534497D01*
X50718Y534463D01*
X50720Y534426D01*
Y534387D01*
G01X50687Y537734D02*
X50694Y537730D01*
X50700Y537719D01*
X50706Y537701D01*
X50711Y537676D01*
X50715Y537646D01*
X50718Y537613D01*
X50720Y537576D01*
Y537537D01*
G01X44488Y538937D02*
X42520Y540906D01*
G01X46369Y546476D02*
X46506Y546279D01*
X46644Y546082D01*
X46784Y545886D01*
G01X46369Y551476D02*
X46506Y551279D01*
X46644Y551082D01*
X46784Y550886D01*
G01X46369Y556476D02*
X46506Y556279D01*
X46644Y556082D01*
X46784Y555886D01*
G01X46279Y541476D02*
X46413Y541279D01*
X46548Y541082D01*
X46684Y540886D01*
G01X46496Y527104D02*
X46530Y527005D01*
X46618Y526934D01*
X46744Y526907D01*
G01X46496Y530254D02*
X46530Y530155D01*
X46618Y530084D01*
X46744Y530057D01*
G01X46496Y533403D02*
X46530Y533304D01*
X46618Y533233D01*
X46744Y533206D01*
G01X46496Y536553D02*
X46530Y536454D01*
X46618Y536383D01*
X46744Y536356D01*
G01X46506Y525827D02*
X46538Y525730D01*
X46626Y525657D01*
X46753Y525630D01*
G01X46506Y528976D02*
X46538Y528879D01*
X46626Y528807D01*
X46753Y528780D01*
G01X46506Y532126D02*
X46538Y532029D01*
X46626Y531957D01*
X46753Y531929D01*
G01X46506Y535276D02*
X46538Y535178D01*
X46626Y535106D01*
X46753Y535079D01*
G01X46506Y538425D02*
X46538Y538328D01*
X46626Y538256D01*
X46753Y538228D01*
G01X46506Y541575D02*
X46538Y541478D01*
X46626Y541406D01*
X46753Y541378D01*
G01X46506Y544724D02*
X46538Y544627D01*
X46626Y544555D01*
X46753Y544528D01*
G01X46506Y547874D02*
X46538Y547777D01*
X46626Y547705D01*
X46753Y547677D01*
G01X46506Y551024D02*
X46538Y550926D01*
X46626Y550854D01*
X46753Y550827D01*
G01X46506Y554173D02*
X46538Y554076D01*
X46626Y554004D01*
X46753Y553976D01*
G01X43531Y539894D02*
Y545276D01*
G01X43701D02*
Y576280D01*
G01X46279Y541476D02*
Y541870D01*
G01X46369Y546476D02*
Y546870D01*
G01Y551476D02*
Y551870D01*
G01Y556476D02*
Y556870D01*
G01X46496Y527104D02*
Y528088D01*
G01Y533403D02*
Y534387D01*
G01Y530254D02*
Y531238D01*
G01Y536553D02*
Y537537D01*
G01X46506Y554567D02*
Y554173D01*
G01Y551417D02*
Y551024D01*
G01Y545118D02*
Y544724D01*
G01Y548268D02*
Y547874D01*
G01Y541969D02*
Y541575D01*
G01Y538819D02*
Y538425D01*
G01Y535669D02*
Y535276D01*
G01Y532520D02*
Y532126D01*
G01Y529370D02*
Y528976D01*
G01Y526220D02*
Y525827D01*
G01X48989Y538917D02*
Y540098D01*
G01X50720Y537537D02*
Y536553D01*
G01Y534387D02*
Y533403D01*
G01Y531238D02*
Y530254D01*
G01Y528088D02*
Y527104D01*
G01X50987Y541476D02*
Y541870D01*
G01Y546476D02*
Y546870D01*
G01Y551476D02*
Y551870D01*
G01Y556476D02*
Y556870D01*
G01X50720Y536553D02*
Y536515D01*
X50718Y536478D01*
X50715Y536444D01*
X50711Y536414D01*
X50706Y536389D01*
X50700Y536371D01*
X50694Y536360D01*
X50687Y536356D01*
G01X50720Y533403D02*
Y533365D01*
X50718Y533328D01*
X50715Y533294D01*
X50711Y533264D01*
X50706Y533240D01*
X50700Y533222D01*
X50694Y533210D01*
X50687Y533206D01*
G01X50720Y530254D02*
Y530215D01*
X50718Y530179D01*
X50715Y530145D01*
X50711Y530115D01*
X50706Y530090D01*
X50700Y530072D01*
X50694Y530061D01*
X50687Y530057D01*
G01X50720Y527104D02*
Y527066D01*
X50718Y527029D01*
X50715Y526995D01*
X50711Y526965D01*
X50706Y526941D01*
X50700Y526922D01*
X50694Y526911D01*
X50687Y526907D01*
G01X46753Y525630D02*
X52838D01*
G01X53118Y525827D02*
X46506D01*
G01Y526220D02*
X53118D01*
G01X46753Y526417D02*
X52838D01*
G01X52552Y526907D02*
X46744D01*
G01X46496Y527104D02*
X52814D01*
G01Y528088D02*
X46496D01*
G01X52552Y528285D02*
X46744D01*
G01X46753Y528780D02*
X52838D01*
G01X53118Y528976D02*
X46506D01*
G01Y529370D02*
X53118D01*
G01X46753Y529567D02*
X52838D01*
G01X52552Y530057D02*
X46744D01*
G01X46496Y530254D02*
X52814D01*
G01Y531238D02*
X46496D01*
G01X52552Y531435D02*
X46744D01*
G01X46753Y531929D02*
X52838D01*
G01X53118Y532126D02*
X46506D01*
G01Y532520D02*
X53118D01*
G01X46753Y532717D02*
X52838D01*
G01X52552Y533206D02*
X46744D01*
G01X46496Y533403D02*
X52814D01*
G01Y534387D02*
X46496D01*
G01X52552Y534584D02*
X46744D01*
G01X46753Y535079D02*
X52838D01*
G01X53118Y535276D02*
X46506D01*
G01Y535669D02*
X53118D01*
G01X46753Y535866D02*
X52838D01*
G01X52552Y536356D02*
X46744D01*
G01X46496Y536553D02*
X52814D01*
G01Y537537D02*
X46496D01*
G01X52552Y537734D02*
X46744D01*
G01X46753Y538228D02*
X52838D01*
G01X53118Y538425D02*
X46506D01*
G01Y538819D02*
X53118D01*
G01X71181Y538917D02*
X48989D01*
G01X62992Y538937D02*
X44488D01*
G01X46753Y539016D02*
X52838D01*
G01X42520Y540098D02*
X48989D01*
G01X52597Y540886D02*
X46684D01*
G01X44488Y541280D02*
X71181D01*
G01X46753Y541378D02*
X52838D01*
G01X46279Y541476D02*
X53021D01*
G01X53118Y541575D02*
X46506D01*
G01X53021Y541870D02*
X46279D01*
G01X46506Y541969D02*
X53118D01*
G01X46753Y542165D02*
X52838D01*
G01X52597Y542461D02*
X46684D01*
G01X46753Y544528D02*
X52838D01*
G01X53118Y544724D02*
X46506D01*
G01Y545118D02*
X53118D01*
G01X62992Y545276D02*
X43531D01*
G01X46753Y545315D02*
X52838D01*
G01X46784Y545886D02*
X52529D01*
G01X46369Y546476D02*
X52956D01*
G01X50987Y541870D02*
X50909Y542461D01*
G01X50987Y546870D02*
X50909Y547461D01*
G01X50987Y551870D02*
X50909Y552461D01*
G01X50987Y556870D02*
X50909Y557461D01*
G01X50987Y556476D02*
X50909Y555886D01*
G01X50987Y551476D02*
X50909Y550886D01*
G01X50987Y546476D02*
X50909Y545886D01*
G01X50987Y541476D02*
X50909Y540886D01*
G01X52956Y546870D02*
X46369D01*
G01X52529Y547461D02*
X46784D01*
G01X46753Y547677D02*
X52838D01*
G01X53118Y547874D02*
X46506D01*
G01Y548268D02*
X53118D01*
G01X46753Y548465D02*
X52838D01*
G01X46753Y550827D02*
X52838D01*
G01X46784Y550886D02*
X52529D01*
G01X53118Y551024D02*
X46506D01*
G01Y551417D02*
X53118D01*
G01X46369Y551476D02*
X52956D01*
G01X46753Y551614D02*
X52838D01*
G01X52956Y551870D02*
X46369D01*
G01X52529Y552461D02*
X46784D01*
G01X46753Y553976D02*
X52838D01*
G01X53118Y554173D02*
X46506D01*
G01Y554567D02*
X53118D01*
G01X46753Y554764D02*
X52838D01*
G01X46784Y555886D02*
X52529D01*
G01X46369Y556476D02*
X52956D01*
G01X71181Y556516D02*
X44488D01*
G01X46753Y526417D02*
X46626Y526389D01*
X46537Y526317D01*
X46506Y526220D01*
G01X46753Y529567D02*
X46626Y529539D01*
X46537Y529466D01*
X46506Y529370D01*
G01X46753Y532717D02*
X46626Y532689D01*
X46537Y532616D01*
X46506Y532520D01*
G01X46753Y535866D02*
X46626Y535838D01*
X46537Y535765D01*
X46506Y535669D01*
G01X46753Y539016D02*
X46626Y538988D01*
X46537Y538915D01*
X46506Y538819D01*
G01X46753Y542165D02*
X46626Y542137D01*
X46537Y542065D01*
X46506Y541969D01*
G01X46753Y545315D02*
X46626Y545287D01*
X46537Y545214D01*
X46506Y545118D01*
G01X46753Y548465D02*
X46626Y548437D01*
X46537Y548364D01*
X46506Y548268D01*
G01X46753Y551614D02*
X46626Y551586D01*
X46537Y551513D01*
X46506Y551417D01*
G01X46753Y554764D02*
X46626Y554736D01*
X46537Y554663D01*
X46506Y554567D01*
G01X46744Y528285D02*
X46617Y528258D01*
X46528Y528185D01*
X46496Y528088D01*
G01X46744Y531435D02*
X46617Y531407D01*
X46528Y531335D01*
X46496Y531238D01*
G01X46744Y534584D02*
X46617Y534557D01*
X46528Y534484D01*
X46496Y534387D01*
G01X46744Y537734D02*
X46617Y537707D01*
X46528Y537634D01*
X46496Y537537D01*
G01X46684Y542461D02*
X46548Y542264D01*
X46413Y542067D01*
X46279Y541870D01*
G01X46784Y557461D02*
X46644Y557265D01*
X46506Y557068D01*
X46369Y556870D01*
G01X46784Y552461D02*
X46644Y552265D01*
X46506Y552068D01*
X46369Y551870D01*
G01X46784Y547461D02*
X46644Y547265D01*
X46506Y547068D01*
X46369Y546870D01*
G01X50687Y521986D02*
X50694Y521982D01*
X50700Y521971D01*
X50706Y521953D01*
X50711Y521928D01*
X50715Y521898D01*
X50718Y521865D01*
X50720Y521828D01*
Y521789D01*
G01X50687Y525135D02*
X50694Y525132D01*
X50700Y525120D01*
X50706Y525103D01*
X50711Y525078D01*
X50715Y525048D01*
X50718Y525014D01*
X50720Y524978D01*
Y524939D01*
G01X46369Y506476D02*
X46506Y506279D01*
X46644Y506082D01*
X46784Y505886D01*
G01X46369Y511476D02*
X46506Y511279D01*
X46644Y511082D01*
X46784Y510886D01*
G01X46279Y516476D02*
X46413Y516279D01*
X46548Y516082D01*
X46684Y515886D01*
G01X46496Y520805D02*
X46530Y520706D01*
X46618Y520635D01*
X46744Y520608D01*
G01X46496Y523954D02*
X46530Y523856D01*
X46618Y523785D01*
X46744Y523757D01*
G01X46506Y506929D02*
X46538Y506832D01*
X46626Y506760D01*
X46753Y506732D01*
G01X46506Y510079D02*
X46538Y509981D01*
X46626Y509909D01*
X46753Y509882D01*
G01X46506Y513228D02*
X46538Y513131D01*
X46626Y513059D01*
X46753Y513031D01*
G01X46506Y516378D02*
X46538Y516281D01*
X46626Y516209D01*
X46753Y516181D01*
G01X46506Y519528D02*
X46538Y519430D01*
X46626Y519358D01*
X46753Y519331D01*
G01X46506Y522677D02*
X46538Y522580D01*
X46626Y522508D01*
X46753Y522480D01*
G01X43531Y512972D02*
Y518452D01*
G01X43701Y540098D02*
Y518248D01*
G01X46279Y516476D02*
Y516870D01*
G01X46369Y506476D02*
Y506870D01*
G01Y511476D02*
Y511870D01*
G01X46496Y520805D02*
Y521789D01*
G01Y523954D02*
Y524939D01*
G01X46506Y523071D02*
Y522677D01*
G01Y516772D02*
Y516378D01*
G01Y519921D02*
Y519528D01*
G01Y513622D02*
Y513228D01*
G01Y507323D02*
Y506929D01*
G01Y510472D02*
Y510079D01*
G01X48989Y518248D02*
Y519429D01*
G01X50720Y521789D02*
Y520805D01*
G01Y524939D02*
Y523954D01*
G01X50987Y506476D02*
Y506870D01*
G01Y511476D02*
Y511870D01*
G01Y516476D02*
Y516870D01*
G01X50720Y523954D02*
Y523916D01*
X50718Y523880D01*
X50715Y523846D01*
X50711Y523815D01*
X50706Y523791D01*
X50700Y523773D01*
X50694Y523761D01*
X50687Y523757D01*
G01X50720Y520805D02*
Y520767D01*
X50718Y520730D01*
X50715Y520696D01*
X50711Y520666D01*
X50706Y520641D01*
X50700Y520623D01*
X50694Y520612D01*
X50687Y520608D01*
G01X46784Y505886D02*
X52529D01*
G01X46369Y506476D02*
X52956D01*
G01X46753Y506732D02*
X52838D01*
G01X52956Y506870D02*
X46369D01*
G01X53118Y506929D02*
X46506D01*
G01Y507323D02*
X53118D01*
G01X52529Y507461D02*
X46784D01*
G01X46753Y507520D02*
X52838D01*
G01X46753Y509882D02*
X52838D01*
G01X53118Y510079D02*
X46506D01*
G01Y510472D02*
X53118D01*
G01X46753Y510669D02*
X52838D01*
G01X46784Y510886D02*
X52529D01*
G01X46369Y511476D02*
X52956D01*
G01Y511870D02*
X46369D01*
G01X52529Y512461D02*
X46784D01*
G01X43531Y512972D02*
X62992D01*
G01X46753Y513031D02*
X52838D01*
G01X53118Y513228D02*
X46506D01*
G01Y513622D02*
X53118D01*
G01X46753Y513819D02*
X52838D01*
G01X52597Y515886D02*
X46684D01*
G01X46753Y516181D02*
X52838D01*
G01X53118Y516378D02*
X46506D01*
G01X46279Y516476D02*
X53021D01*
G01X46506Y516772D02*
X53118D01*
G01X53021Y516870D02*
X46279D01*
G01X46753Y516969D02*
X52838D01*
G01X71181Y517067D02*
X44488D01*
G01X52597Y517461D02*
X46684D01*
G01X48989Y518248D02*
X42520D01*
G01X46753Y519331D02*
X52838D01*
G01X62992Y519409D02*
X44488D01*
G01X48989Y519429D02*
X71181D01*
G01X53118Y519528D02*
X46506D01*
G01Y519921D02*
X53118D01*
G01X46753Y520118D02*
X52838D01*
G01X52552Y520608D02*
X46744D01*
G01X46496Y520805D02*
X52814D01*
G01Y521789D02*
X46496D01*
G01X52552Y521986D02*
X46744D01*
G01X46753Y522480D02*
X52838D01*
G01X53118Y522677D02*
X46506D01*
G01Y523071D02*
X53118D01*
G01X46753Y523268D02*
X52838D01*
G01X52552Y523757D02*
X46744D01*
G01X46496Y523954D02*
X52814D01*
G01Y524939D02*
X46496D01*
G01X52552Y525135D02*
X46744D01*
G01X50987Y506870D02*
X50909Y507461D01*
G01X50987Y511870D02*
X50909Y512461D01*
G01X50987Y516870D02*
X50909Y517461D01*
G01X50987Y516476D02*
X50909Y515886D01*
G01X50987Y511476D02*
X50909Y510886D01*
G01X50987Y506476D02*
X50909Y505886D01*
G01X46753Y507520D02*
X46626Y507492D01*
X46537Y507419D01*
X46506Y507323D01*
G01X46753Y510669D02*
X46626Y510641D01*
X46537Y510569D01*
X46506Y510472D01*
G01X46753Y513819D02*
X46626Y513791D01*
X46537Y513718D01*
X46506Y513622D01*
G01X46753Y516969D02*
X46626Y516941D01*
X46537Y516868D01*
X46506Y516772D01*
G01X46753Y520118D02*
X46626Y520090D01*
X46537Y520017D01*
X46506Y519921D01*
G01X46753Y523268D02*
X46626Y523240D01*
X46537Y523167D01*
X46506Y523071D01*
G01X46744Y521986D02*
X46617Y521959D01*
X46528Y521886D01*
X46496Y521789D01*
G01X46744Y525135D02*
X46617Y525108D01*
X46528Y525035D01*
X46496Y524939D01*
G01X46684Y517461D02*
X46548Y517264D01*
X46413Y517067D01*
X46279Y516870D01*
G01X46784Y512461D02*
X46644Y512265D01*
X46506Y512068D01*
X46369Y511870D01*
G01X46784Y507461D02*
X46644Y507265D01*
X46506Y507068D01*
X46369Y506870D01*
G01X42520Y517441D02*
X44488Y519409D01*
G01X68110Y616043D02*
Y614075D01*
G01Y611516D02*
Y613484D01*
G01X69602Y612501D02*
Y612629D01*
G01X69685Y616339D02*
Y615748D01*
G01Y614567D02*
Y612992D01*
G01Y611811D02*
Y611220D01*
G01X69696Y611992D02*
Y612613D01*
G01X69789Y612740D02*
Y611992D01*
G01X70044Y596575D02*
Y595000D01*
G01X70079D02*
Y596575D01*
G01X70103Y595000D02*
Y596575D01*
G01X70669Y611220D02*
Y616339D01*
G01X70866D02*
Y611220D01*
G01X71260Y613484D02*
Y611516D01*
G01Y614075D02*
Y616043D01*
G01X71426Y596575D02*
Y595000D01*
G01X71796D02*
Y596575D01*
G01X73585Y587539D02*
Y586801D01*
G01X73873Y596575D02*
Y595000D01*
G01X74243D02*
Y596575D01*
G01X74409Y613484D02*
Y611516D01*
G01Y614075D02*
Y616043D01*
G01X74803Y616339D02*
Y611220D01*
G01X75000D02*
Y616339D01*
G01X75567Y596575D02*
Y595000D01*
G01X75591Y596575D02*
Y595000D01*
G01X75625D02*
Y596575D01*
G01X75984Y611220D02*
Y611811D01*
G01Y615748D02*
Y616339D01*
G01Y612992D02*
Y614567D01*
G01X77497Y587096D02*
Y587539D01*
G01X77559Y616043D02*
Y614075D01*
G01Y611516D02*
Y613484D01*
G01X81024Y601693D02*
Y588760D01*
G01X94488Y586791D02*
X70866D01*
G01X73585Y586801D02*
X76464D01*
G01X92113Y587539D02*
X91228D01*
G01X77497D02*
X73585D01*
G01X71666D02*
X70780D01*
G01X81024Y591516D02*
X64646D01*
G01X75000Y594213D02*
X70669D01*
G01X75625Y595000D02*
X70044D01*
G01Y596575D02*
X75625D01*
G01X70669Y597362D02*
X75000D01*
G01X81024Y601693D02*
X64646D01*
G01X69685Y611220D02*
X75984D01*
G01X71260Y611516D02*
X68110D01*
G01X74409D02*
X77559D01*
G01X69789Y611992D02*
X69696D01*
G01Y612740D02*
X69789D01*
G01X77559Y613484D02*
X74409D01*
G01X68110D02*
X71260D01*
G01X77559Y614075D02*
X74409D01*
G01X68110D02*
X71260D01*
G01Y616043D02*
X68110D01*
G01X74409D02*
X77559D01*
G01X75984Y616339D02*
X69685D01*
G01X69602Y612629D02*
X69696Y612740D01*
G01Y612613D02*
X69602Y612501D01*
G01X70669Y597362D02*
G03Y594213I0J-1574D01*
G01X69685Y614567D02*
G03Y615748I0J591D01*
G01Y611811D02*
G03Y612992I0J591D01*
G01X75922Y585817D02*
G03X76464Y586801I-1276J1344D01*
G01X76428Y585273D02*
G03X77498Y587096I-2810J2875D01*
G01X75000Y594213D02*
G03Y597362I0J1574D01*
G01X75984Y615748D02*
G03Y614567I0J-590D01*
G01Y612992D02*
G03Y611811I0J-590D01*
G01X40492Y588038D02*
X40547Y587652D01*
G01X66929Y587579D02*
X40551D01*
G01Y588760D02*
X94488D01*
G01X40519Y588729D02*
X40462Y588589D01*
X40457Y588349D01*
G01X40519Y588729D02*
X40463Y588594D01*
X40456Y588359D01*
X40493Y588030D01*
G01X51351Y557913D02*
X51389Y557887D01*
X51417Y557815D01*
X51428Y557717D01*
G01X51351Y561063D02*
X51389Y561037D01*
X51417Y560965D01*
X51428Y560866D01*
G01X51351Y564213D02*
X51389Y564186D01*
X51417Y564114D01*
X51428Y564016D01*
G01X51351Y567362D02*
X51389Y567336D01*
X51417Y567264D01*
X51428Y567165D01*
G01X51351Y570512D02*
X51389Y570485D01*
X51417Y570413D01*
X51428Y570315D01*
G01X71567Y569823D02*
X70957Y570335D01*
G01X71654D02*
X72264Y569823D01*
G01X68430Y571529D02*
X68779Y571187D01*
G01X72002Y573491D02*
X71654Y573832D01*
G01X52529Y562461D02*
X52956Y561870D01*
G01X52529Y567461D02*
X52956Y566870D01*
G01X52529Y572461D02*
X52956Y571870D01*
G01X68953Y571699D02*
X68779Y571955D01*
G01X71218Y573406D02*
X71480Y573320D01*
G01X68779Y571187D02*
X69128Y571017D01*
G01X80323Y582437D02*
X80040Y582615D01*
X79853Y582880D01*
X79786Y583182D01*
X79850Y583482D01*
X80036Y583749D01*
X80321Y583930D01*
X80672Y583996D01*
G01X81020Y583931D02*
X81303Y583753D01*
X81490Y583488D01*
X81557Y583186D01*
X81493Y582886D01*
X81307Y582619D01*
X81022Y582437D01*
X80672Y582372D01*
G01X85490Y582437D02*
X85207Y582615D01*
X85020Y582880D01*
X84953Y583182D01*
X85018Y583482D01*
X85203Y583749D01*
X85489Y583930D01*
X85839Y583996D01*
G01X86188Y583931D02*
X86470Y583753D01*
X86657Y583488D01*
X86724Y583186D01*
X86660Y582886D01*
X86475Y582619D01*
X86189Y582437D01*
X85839Y582372D01*
G01X75145Y582441D02*
X74865Y582622D01*
G01X69215Y571529D02*
X68953Y571699D01*
G01X80249Y584738D02*
X79888Y584974D01*
X79650Y585324D01*
X79565Y585728D01*
X79647Y586130D01*
X79883Y586482D01*
X80247Y586722D01*
X80672Y586807D01*
G01X81094Y586723D02*
X81455Y586487D01*
X81693Y586137D01*
X81779Y585733D01*
X81696Y585331D01*
X81460Y584979D01*
X81096Y584739D01*
X80672Y584654D01*
G01X85416Y584738D02*
X85056Y584974D01*
X84817Y585324D01*
X84732Y585728D01*
X84814Y586130D01*
X85051Y586482D01*
X85414Y586722D01*
X85839Y586807D01*
G01X86262Y586723D02*
X86622Y586487D01*
X86861Y586137D01*
X86946Y585733D01*
X86864Y585331D01*
X86627Y584979D01*
X86264Y584739D01*
X85839Y584654D01*
G01X79474Y584283D02*
X79022Y584723D01*
X78752Y585259D01*
X78682Y585829D01*
X78824Y586393D01*
X79170Y586918D01*
X79698Y587311D01*
X80340Y587515D01*
X81019Y587512D01*
X81659Y587304D01*
X82182Y586908D01*
X82524Y586384D01*
X82662Y585823D01*
X82590Y585256D01*
X82320Y584721D01*
G01X84641Y584283D02*
X84189Y584723D01*
X83919Y585259D01*
X83849Y585829D01*
X83991Y586393D01*
X84337Y586918D01*
X84865Y587311D01*
X85507Y587515D01*
X86187Y587512D01*
X86827Y587304D01*
X87350Y586908D01*
X87691Y586384D01*
X87829Y585823D01*
X87757Y585256D01*
X87487Y584721D01*
G01X81869Y584283D02*
X82192Y583863D01*
X82355Y583380D01*
X82333Y582875D01*
X82130Y582398D01*
X81763Y581995D01*
X81257Y581728D01*
X80666Y581634D01*
X80077Y581731D01*
X79574Y582000D01*
X79210Y582404D01*
X79009Y582881D01*
X78989Y583387D01*
X79154Y583868D01*
X79474Y584283D01*
G01X87037D02*
X87359Y583863D01*
X87522Y583380D01*
X87500Y582875D01*
X87297Y582398D01*
X86930Y581995D01*
X86424Y581728D01*
X85833Y581634D01*
X85244Y581731D01*
X84742Y582000D01*
X84377Y582404D01*
X84176Y582881D01*
X84157Y583387D01*
X84321Y583868D01*
X84641Y584283D01*
G01X74866Y582622D02*
X74683Y582886D01*
X74619Y583185D01*
X74683Y583482D01*
G01X71480Y573320D02*
X71654Y573064D01*
G01X79583Y577657D02*
X79328Y578051D01*
G01X68256Y571870D02*
X68430Y571529D01*
G01X72176Y573150D02*
X72002Y573491D01*
G01X51839Y562461D02*
X52112Y561870D01*
G01X51839Y567461D02*
X52112Y566870D01*
G01X51839Y572461D02*
X52112Y571870D01*
G01X71654Y573064D02*
X71741Y572808D01*
G01X68779Y571955D02*
X68692Y572296D01*
G01X72264Y572808D02*
X72176Y573150D01*
G01X51941Y557717D02*
X51938Y557755D01*
X51930Y557791D01*
X51917Y557825D01*
X51900Y557856D01*
X51879Y557880D01*
X51856Y557898D01*
X51830Y557909D01*
X51802Y557913D01*
G01X51941Y560866D02*
X51938Y560904D01*
X51930Y560941D01*
X51917Y560975D01*
X51900Y561005D01*
X51879Y561030D01*
X51856Y561048D01*
X51830Y561059D01*
X51802Y561063D01*
G01X51941Y564016D02*
X51938Y564054D01*
X51930Y564091D01*
X51917Y564124D01*
X51900Y564155D01*
X51879Y564179D01*
X51856Y564197D01*
X51830Y564209D01*
X51802Y564213D01*
G01X51941Y567165D02*
X51938Y567204D01*
X51930Y567240D01*
X51917Y567274D01*
X51900Y567304D01*
X51879Y567329D01*
X51856Y567347D01*
X51830Y567358D01*
X51802Y567362D01*
G01X51941Y570315D02*
X51938Y570353D01*
X51930Y570390D01*
X51917Y570424D01*
X51900Y570454D01*
X51879Y570478D01*
X51856Y570496D01*
X51830Y570508D01*
X51802Y570512D01*
G01X51428Y570315D02*
Y569921D01*
G01Y564016D02*
Y563622D01*
G01Y567165D02*
Y566772D01*
G01Y560866D02*
Y560472D01*
G01Y557717D02*
Y557323D01*
G01X51941D02*
Y557717D01*
G01Y560472D02*
Y560866D01*
G01Y563622D02*
Y564016D01*
G01Y566772D02*
Y567165D01*
G01Y569921D02*
Y570315D01*
G01X52112Y571870D02*
Y571476D01*
G01Y566870D02*
Y566476D01*
G01Y561870D02*
Y561476D01*
G01X52956Y571870D02*
Y571476D01*
G01Y566870D02*
Y566476D01*
G01Y561870D02*
Y561476D01*
G01X53118Y557323D02*
Y557717D01*
G01Y560472D02*
Y560866D01*
G01Y563622D02*
Y564016D01*
G01Y566772D02*
Y567165D01*
G01Y569921D02*
Y570315D01*
G01X75492Y582372D02*
X75144Y582441D01*
G01X71654Y573832D02*
X71306Y573917D01*
G01X68169Y572296D02*
X68256Y571870D01*
G01X64646Y575295D02*
Y601693D01*
G01X64961Y576476D02*
Y574705D01*
G01X66929Y588760D02*
Y580413D01*
G01X68169Y572979D02*
Y572296D01*
G01Y569311D02*
Y569823D01*
G01X68565Y582298D02*
Y581634D01*
G01X68692Y572296D02*
Y572979D01*
G01X69213Y558878D02*
Y575295D01*
G01X69302Y573661D02*
Y574173D01*
G01X69998Y572808D02*
Y572296D01*
G01X70521D02*
Y572808D01*
G01X70866Y586791D02*
Y583012D01*
G01Y578602D02*
Y581043D01*
G01X71306Y571785D02*
Y571273D01*
G01X71741Y572808D02*
Y572296D01*
G01X72264Y569823D02*
Y569311D01*
G01Y572382D02*
Y572808D01*
G01X72404Y581634D02*
Y582372D01*
G01X74783Y572638D02*
Y570669D01*
G01X75170Y570512D02*
Y569724D01*
G01Y564213D02*
Y563425D01*
G01Y567362D02*
Y566575D01*
G01Y561063D02*
Y560276D01*
G01Y557913D02*
Y557126D01*
G01X75197Y570512D02*
Y569724D01*
G01Y564213D02*
Y563425D01*
G01Y567362D02*
Y566575D01*
G01Y561063D02*
Y560276D01*
G01Y557913D02*
Y557126D01*
G01X75573Y570512D02*
Y569724D01*
G01Y564213D02*
Y563425D01*
G01Y567362D02*
Y566575D01*
G01Y561063D02*
Y560276D01*
G01Y557913D02*
Y557126D01*
G01X75787Y572461D02*
Y570886D01*
G01Y567461D02*
Y565886D01*
G01Y562461D02*
Y560886D01*
G01X76390Y583331D02*
Y583184D01*
G01X76772Y573248D02*
Y570098D01*
G01Y568248D02*
Y565098D01*
G01Y563248D02*
Y560098D01*
G01Y578110D02*
Y580413D01*
G01X77202Y583184D02*
Y583331D01*
G01X77756Y573248D02*
Y570098D01*
G01Y568248D02*
Y565098D01*
G01Y563248D02*
Y560098D01*
G01X78740Y572461D02*
Y570886D01*
G01Y567461D02*
Y565886D01*
G01Y562461D02*
Y560886D01*
G01X78935Y557126D02*
Y557913D01*
G01Y560276D02*
Y561063D01*
G01Y563425D02*
Y564213D01*
G01Y566575D02*
Y567362D01*
G01Y569724D02*
Y570512D01*
G01X79328Y578051D02*
Y578110D01*
G01X79967Y580413D02*
Y577657D01*
G01X80919Y557126D02*
Y557913D01*
G01Y560276D02*
Y561063D01*
G01Y563425D02*
Y564213D01*
G01Y566575D02*
Y567362D01*
G01Y569724D02*
Y570512D01*
G01X81890Y560886D02*
Y562461D01*
G01Y565886D02*
Y567461D01*
G01Y570886D02*
Y572461D01*
G01X82570Y570512D02*
Y569724D01*
G01Y564213D02*
Y563425D01*
G01Y567362D02*
Y566575D01*
G01Y561063D02*
Y560276D01*
G01Y557913D02*
Y557126D01*
G01X82854Y570669D02*
Y572638D01*
G01X84298Y557913D02*
Y560276D01*
G01Y561063D02*
Y563425D01*
G01Y564213D02*
Y566575D01*
G01Y567362D02*
Y569724D01*
G01Y570512D02*
Y573091D01*
G01X85237Y570512D02*
Y569724D01*
G01Y564213D02*
Y563425D01*
G01Y567362D02*
Y566575D01*
G01Y561063D02*
Y560276D01*
G01Y557913D02*
Y557126D01*
G01X85384Y570512D02*
Y569724D01*
G01Y564213D02*
Y563425D01*
G01Y567362D02*
Y566575D01*
G01Y561063D02*
Y560276D01*
G01Y557913D02*
Y557126D01*
G01X86976Y570512D02*
Y569724D01*
G01Y564213D02*
Y563425D01*
G01Y567362D02*
Y566575D01*
G01Y561063D02*
Y560276D01*
G01Y557913D02*
Y557126D01*
G01X87841Y580413D02*
Y577657D01*
G01X87918Y557126D02*
Y557913D01*
G01Y560276D02*
Y561063D01*
G01Y563425D02*
Y564213D01*
G01Y566575D02*
Y567362D01*
G01Y569724D02*
Y570512D01*
G01X89013Y582298D02*
Y581634D01*
G01X90754Y557126D02*
Y557913D01*
G01Y560276D02*
Y561063D01*
G01Y563425D02*
Y564213D01*
G01Y566575D02*
Y567362D01*
G01Y569724D02*
Y570512D01*
G01X90943D02*
Y569724D01*
G01Y564213D02*
Y563425D01*
G01Y567362D02*
Y566575D01*
G01Y561063D02*
Y560276D01*
G01Y557913D02*
Y557126D01*
G01X92717Y570512D02*
Y569724D01*
G01Y564213D02*
Y563425D01*
G01Y567362D02*
Y566575D01*
G01Y561063D02*
Y560276D01*
G01Y557913D02*
Y557126D01*
G01X92852Y581634D02*
Y582372D01*
G01X93696Y575079D02*
Y577657D01*
G01X94170Y575079D02*
Y580413D01*
G01X94488Y575079D02*
Y588760D01*
G01X51428Y566772D02*
X51417Y566673D01*
X51389Y566601D01*
X51351Y566575D01*
G01X51428Y563622D02*
X51417Y563524D01*
X51389Y563452D01*
X51351Y563425D01*
G01X92717Y557126D02*
X85384D01*
G01X85237D02*
X73228D01*
G01X74724Y557461D02*
X81890D01*
G01X77756Y557657D02*
X76772D01*
G01X85237Y557913D02*
X73228D01*
G01X85384D02*
X92717D01*
G01X77756Y558051D02*
X76772D01*
G01X77756Y558248D02*
X76772D01*
G01X77756Y560098D02*
X76772D01*
G01X92717Y560276D02*
X85384D01*
G01X85237D02*
X73228D01*
G01X77756Y560295D02*
X76772D01*
G01X77756Y560689D02*
X76772D01*
G01X74724Y560886D02*
X81890D01*
G01X85237Y561063D02*
X73228D01*
G01X85384D02*
X92717D01*
G01X74724Y562461D02*
X81890D01*
G01X77756Y562657D02*
X76772D01*
G01X77756Y563051D02*
X76772D01*
G01X77756Y563248D02*
X76772D01*
G01X92717Y563425D02*
X85384D01*
G01X85237D02*
X73228D01*
G01X85237Y564213D02*
X73228D01*
G01X85384D02*
X92717D01*
G01X77756Y565098D02*
X76772D01*
G01X77756Y565295D02*
X76772D01*
G01X77756Y565689D02*
X76772D01*
G01X74724Y565886D02*
X81890D01*
G01X92717Y566575D02*
X85384D01*
G01X85237D02*
X73228D01*
G01X85237Y567362D02*
X73228D01*
G01X85384D02*
X92717D01*
G01X74724Y567461D02*
X81890D01*
G01X77756Y567657D02*
X76772D01*
G01X77756Y568051D02*
X76772D01*
G01X77756Y568248D02*
X76772D01*
G01X72264Y569311D02*
X68169D01*
G01X92717Y569724D02*
X85384D01*
G01X85237D02*
X73228D01*
G01X68169Y569823D02*
X71567D01*
G01X77756Y570098D02*
X76772D01*
G01X77756Y570295D02*
X76772D01*
G01X70957Y570335D02*
X71654D01*
G01X85237Y570512D02*
X73228D01*
G01X85384D02*
X92717D01*
G01X74783Y570669D02*
X82854D01*
G01X77756Y570689D02*
X76772D01*
G01X74724Y570886D02*
X81890D01*
G01X69128Y571017D02*
X69563D01*
G01X69476Y571529D02*
X69215D01*
G01X74724Y572461D02*
X81890D01*
G01X82854Y572638D02*
X74783D01*
G01X77756Y572657D02*
X76772D01*
G01X77756Y573051D02*
X76772D01*
G01X78346Y573091D02*
X87331D01*
G01X77756Y573248D02*
X76772D01*
G01X71044Y573406D02*
X71218D01*
G01X71306Y573917D02*
X70957D01*
G01X74331Y574705D02*
X64961D01*
G01X74331Y575079D02*
X94488D01*
G01X64646Y575295D02*
X71181D01*
G01X74331Y576476D02*
X64961D01*
G01X93696Y577657D02*
X73228D01*
G01X79328Y578051D02*
X73228D01*
G01X79328Y578110D02*
X73228D01*
G01X70866Y578602D02*
X94488D01*
G01Y581043D02*
X70866D01*
G01X68565Y581634D02*
X72404D01*
G01X89013D02*
X92852D01*
G01Y582372D02*
X89899D01*
G01X72404D02*
X69451D01*
G01X70866Y583012D02*
X94488D01*
G01X77202Y583331D02*
X76390D01*
G01X77202Y583184D02*
X77115Y582707D01*
X76868Y582265D01*
X76480Y581913D01*
X75973Y581693D01*
X75395Y581637D01*
X74832Y581759D01*
X74356Y582041D01*
X74017Y582446D01*
X73837Y582903D01*
X73822Y583383D01*
X73979Y583854D01*
X74294Y584270D01*
G01X68256Y573406D02*
X68169Y572979D01*
G01X70434Y571870D02*
X70521Y572296D01*
G01X72176Y571955D02*
X72264Y572382D01*
G01X76323Y582879D02*
X76390Y583184D01*
G01X68692Y572979D02*
X68779Y573320D01*
G01X70086Y573150D02*
X69998Y572808D01*
G01Y572296D02*
X69911Y571955D01*
G01X70957Y573917D02*
X70608Y573832D01*
G01X69302Y574173D02*
X68953Y574088D01*
G01X51802Y557126D02*
X51829Y557130D01*
X51855Y557141D01*
X51879Y557159D01*
X51900Y557183D01*
X51917Y557213D01*
X51930Y557247D01*
X51938Y557284D01*
X51941Y557323D01*
G01X51802Y560276D02*
X51829Y560279D01*
X51855Y560290D01*
X51879Y560308D01*
X51900Y560333D01*
X51917Y560363D01*
X51930Y560397D01*
X51938Y560433D01*
X51941Y560472D01*
G01X51802Y563425D02*
X51829Y563429D01*
X51855Y563440D01*
X51879Y563458D01*
X51900Y563483D01*
X51917Y563513D01*
X51930Y563546D01*
X51938Y563583D01*
X51941Y563622D01*
G01X51802Y566575D02*
X51829Y566578D01*
X51855Y566589D01*
X51879Y566607D01*
X51900Y566632D01*
X51917Y566662D01*
X51930Y566696D01*
X51938Y566733D01*
X51941Y566772D01*
G01X51802Y569724D02*
X51829Y569728D01*
X51855Y569739D01*
X51879Y569757D01*
X51900Y569782D01*
X51917Y569812D01*
X51930Y569846D01*
X51938Y569882D01*
X51941Y569921D01*
G01X70521Y572808D02*
X70608Y573064D01*
G01X71741Y572296D02*
X71654Y572041D01*
G01X52112Y571476D02*
X51839Y570886D01*
G01X52112Y566476D02*
X51839Y565886D01*
G01X52112Y561476D02*
X51839Y560886D01*
G01X70260Y573491D02*
X70086Y573150D01*
G01X70260Y571529D02*
X70434Y571870D01*
G01X68518Y573832D02*
X68256Y573406D01*
G01X70608Y573064D02*
X70783Y573320D01*
G01X69911Y571955D02*
X69737Y571699D01*
G01X74865Y583746D02*
X74682Y583480D01*
X74619Y583183D01*
X74683Y582885D01*
G01X76133Y582612D02*
X76323Y582880D01*
G01X52529Y570886D02*
X52956Y571476D01*
G01X52529Y565886D02*
X52956Y566476D01*
G01X52529Y560886D02*
X52956Y561476D01*
G01X74294Y584270D02*
X73956Y583809D01*
X73811Y583291D01*
X73871Y582773D01*
X74122Y582289D01*
X74559Y581894D01*
X75132Y581671D01*
X75767Y581652D01*
X76351Y581838D01*
X76806Y582191D01*
X77098Y582663D01*
X77202Y583184D01*
G01X71915Y571614D02*
X72176Y571955D01*
G01X79474Y584283D02*
X79151Y583863D01*
X78989Y583380D01*
X79010Y582875D01*
X79213Y582398D01*
X79580Y581995D01*
X80086Y581728D01*
X80678Y581634D01*
X81267Y581731D01*
X81769Y582000D01*
X82133Y582404D01*
X82334Y582881D01*
X82354Y583387D01*
X82190Y583868D01*
X81869Y584283D01*
G01X84641D02*
X84319Y583863D01*
X84156Y583380D01*
X84178Y582875D01*
X84381Y582398D01*
X84748Y581995D01*
X85254Y581728D01*
X85845Y581634D01*
X86434Y581731D01*
X86936Y582000D01*
X87300Y582404D01*
X87502Y582881D01*
X87521Y583387D01*
X87357Y583868D01*
X87037Y584283D01*
G01X68779Y573320D02*
X69040Y573576D01*
G01X70608Y573832D02*
X70260Y573491D01*
G01X69911Y571187D02*
X70260Y571529D01*
G01X71654Y572041D02*
X71480Y571870D01*
G01X76428Y585273D02*
X74865Y583746D01*
G01X81869Y584283D02*
X82321Y584723D01*
X82591Y585259D01*
X82661Y585829D01*
X82520Y586393D01*
X82173Y586918D01*
X81646Y587311D01*
X81003Y587515D01*
X80324Y587512D01*
X79684Y587304D01*
X79161Y586908D01*
X78820Y586384D01*
X78681Y585823D01*
X78753Y585256D01*
X79024Y584721D01*
G01X87037Y584283D02*
X87488Y584723D01*
X87759Y585259D01*
X87829Y585829D01*
X87687Y586393D01*
X87341Y586918D01*
X86813Y587311D01*
X86170Y587515D01*
X85491Y587512D01*
X84851Y587304D01*
X84328Y586908D01*
X83987Y586384D01*
X83849Y585823D01*
X83920Y585256D01*
X84191Y584721D01*
G01X75922Y585817D02*
X74294Y584270D01*
G01X71567Y571358D02*
X71915Y571614D01*
G01X51351Y569724D02*
X51389Y569751D01*
X51417Y569823D01*
X51428Y569921D01*
G01X51351Y560276D02*
X51389Y560302D01*
X51417Y560374D01*
X51428Y560472D01*
G01X51351Y557126D02*
X51389Y557152D01*
X51417Y557224D01*
X51428Y557323D01*
G01X80249Y586723D02*
X79888Y586487D01*
X79650Y586137D01*
X79565Y585733D01*
X79647Y585331D01*
X79883Y584979D01*
X80247Y584739D01*
X80672Y584654D01*
G01X81094Y584738D02*
X81455Y584974D01*
X81693Y585324D01*
X81779Y585728D01*
X81696Y586130D01*
X81460Y586482D01*
X81096Y586722D01*
X80672Y586807D01*
G01X85416Y586723D02*
X85056Y586487D01*
X84817Y586137D01*
X84732Y585733D01*
X84814Y585331D01*
X85051Y584979D01*
X85414Y584739D01*
X85839Y584654D01*
G01X86262Y584738D02*
X86622Y584974D01*
X86861Y585324D01*
X86946Y585728D01*
X86864Y586130D01*
X86627Y586482D01*
X86264Y586722D01*
X85839Y586807D01*
G01X69737Y571699D02*
X69476Y571529D01*
G01X80323Y583931D02*
X80040Y583753D01*
X79853Y583488D01*
X79786Y583186D01*
X79850Y582886D01*
X80036Y582619D01*
X80321Y582437D01*
X80672Y582372D01*
G01X81020Y582437D02*
X81303Y582615D01*
X81490Y582880D01*
X81557Y583182D01*
X81493Y583482D01*
X81307Y583749D01*
X81022Y583930D01*
X80672Y583996D01*
G01X85490Y583931D02*
X85207Y583753D01*
X85020Y583488D01*
X84953Y583186D01*
X85018Y582886D01*
X85203Y582619D01*
X85489Y582437D01*
X85839Y582372D01*
G01X86188Y582437D02*
X86470Y582615D01*
X86657Y582880D01*
X86724Y583182D01*
X86660Y583482D01*
X86475Y583749D01*
X86189Y583930D01*
X85839Y583996D01*
G01X76133Y582613D02*
X75846Y582434D01*
X75492Y582372D01*
G01X68953Y574088D02*
X68518Y573832D01*
G01X69563Y571017D02*
X69911Y571187D01*
G01X71480Y571870D02*
X71306Y571785D01*
G01X69040Y573576D02*
X69302Y573661D01*
G01X70783Y573320D02*
X71044Y573406D01*
G01X71306Y571273D02*
X71567Y571358D01*
G01X68565Y582298D02*
G03X70780Y587539I-7141J6107D01*
G01X69451Y582372D02*
G03X71666Y587539I-6937J6032D01*
G01X74331Y557854D02*
G03X74724Y557461I393J0D01*
G01X74331Y567854D02*
G03X74724Y567461I393J0D01*
G01Y565886D02*
G03X74331Y565492I1J-394D01*
G01Y562854D02*
G03X74724Y562461I393J0D01*
G01Y560886D02*
G03X74331Y560492I1J-394D01*
G01Y572854D02*
G03X74724Y572461I393J0D01*
G01Y570886D02*
G03X74331Y570492I1J-394D01*
G01X86614Y583976D02*
G03I-4528J0D01*
G01X85591D02*
G03I-3505J0D01*
G01X85433D02*
G03I-3347J0D01*
G01X84252D02*
G03I-2166J0D01*
G01X89013Y582298D02*
G03X91228Y587539I-7141J6107D01*
G01X89899Y582372D02*
G03X92113Y587539I-6938J6031D01*
G01X42520Y577461D02*
X44488Y575492D01*
G01X46369Y561476D02*
X46506Y561279D01*
X46644Y561082D01*
X46784Y560886D01*
G01X46369Y566476D02*
X46506Y566279D01*
X46644Y566082D01*
X46784Y565886D01*
G01X46369Y571476D02*
X46506Y571279D01*
X46644Y571082D01*
X46784Y570886D01*
G01X46506Y557323D02*
X46538Y557226D01*
X46626Y557154D01*
X46753Y557126D01*
G01X46506Y560472D02*
X46538Y560375D01*
X46626Y560303D01*
X46753Y560276D01*
G01X46506Y563622D02*
X46538Y563525D01*
X46626Y563453D01*
X46753Y563425D01*
G01X46506Y566772D02*
X46538Y566674D01*
X46626Y566602D01*
X46753Y566575D01*
G01X46506Y569921D02*
X46538Y569824D01*
X46626Y569752D01*
X46753Y569724D01*
G01X40551Y587579D02*
Y580413D01*
G01X46369Y561476D02*
Y561870D01*
G01Y566476D02*
Y566870D01*
G01Y571476D02*
Y571870D01*
G01X46506Y570315D02*
Y569921D01*
G01Y564016D02*
Y563622D01*
G01Y567165D02*
Y566772D01*
G01Y560866D02*
Y560472D01*
G01Y557717D02*
Y557323D01*
G01X50987Y561476D02*
Y561870D01*
G01Y566476D02*
Y566870D01*
G01Y571476D02*
Y571870D01*
G01Y561870D02*
X50909Y562461D01*
G01X50987Y566870D02*
X50909Y567461D01*
G01X50987Y571870D02*
X50909Y572461D01*
G01X50987Y571476D02*
X50909Y570886D01*
G01X50987Y566476D02*
X50909Y565886D01*
G01X50987Y561476D02*
X50909Y560886D01*
G01X52956Y556870D02*
X46369D01*
G01X46753Y557126D02*
X52838D01*
G01X53118Y557323D02*
X46506D01*
G01X52529Y557461D02*
X46784D01*
G01X46506Y557717D02*
X53118D01*
G01X46753Y557913D02*
X52838D01*
G01X44488Y558878D02*
X71181D01*
G01X46753Y560276D02*
X52838D01*
G01X53118Y560472D02*
X46506D01*
G01Y560866D02*
X53118D01*
G01X46784Y560886D02*
X52529D01*
G01X46753Y561063D02*
X52838D01*
G01X46369Y561476D02*
X52956D01*
G01Y561870D02*
X46369D01*
G01X52529Y562461D02*
X46784D01*
G01X46753Y563425D02*
X52838D01*
G01X53118Y563622D02*
X46506D01*
G01Y564016D02*
X53118D01*
G01X46753Y564213D02*
X52838D01*
G01X46784Y565886D02*
X52529D01*
G01X46369Y566476D02*
X52956D01*
G01X46753Y566575D02*
X52838D01*
G01X53118Y566772D02*
X46506D01*
G01X52956Y566870D02*
X46369D01*
G01X46506Y567165D02*
X53118D01*
G01X46753Y567362D02*
X52838D01*
G01X52529Y567461D02*
X46784D01*
G01X46753Y569724D02*
X52838D01*
G01X53118Y569921D02*
X46506D01*
G01Y570315D02*
X53118D01*
G01X46753Y570512D02*
X52838D01*
G01X46784Y570886D02*
X52529D01*
G01X46369Y571476D02*
X52956D01*
G01Y571870D02*
X46369D01*
G01X52529Y572461D02*
X46784D01*
G01X62992Y575492D02*
X44488D01*
G01X73228Y575886D02*
X42520D01*
G01Y580413D02*
X39236D01*
G01X44488D02*
X94488D01*
G01X46753Y557913D02*
X46626Y557885D01*
X46537Y557813D01*
X46506Y557717D01*
G01X46753Y561063D02*
X46626Y561035D01*
X46537Y560962D01*
X46506Y560866D01*
G01X46753Y564213D02*
X46626Y564185D01*
X46537Y564112D01*
X46506Y564016D01*
G01X46753Y567362D02*
X46626Y567334D01*
X46537Y567261D01*
X46506Y567165D01*
G01X46753Y570512D02*
X46626Y570484D01*
X46537Y570411D01*
X46506Y570315D01*
G01X46784Y572461D02*
X46644Y572265D01*
X46506Y572068D01*
X46369Y571870D01*
G01X46784Y567461D02*
X46644Y567265D01*
X46506Y567068D01*
X46369Y566870D01*
G01X46784Y562461D02*
X46644Y562265D01*
X46506Y562068D01*
X46369Y561870D01*
G01X44488Y580413D02*
X42520Y578445D01*
G01X80132Y842598D02*
X80114Y842654D01*
X80062Y842820D01*
X79983Y843078D01*
X79887Y843406D01*
X79783Y843780D01*
G01X84041Y837165D02*
X84059Y837109D01*
X84111Y836944D01*
X84190Y836685D01*
X84285Y836358D01*
X84390Y835984D01*
G01X64961Y849154D02*
Y847382D01*
G01X66929Y835098D02*
Y843445D01*
G01X68670Y840507D02*
Y836500D01*
G01X70044Y828858D02*
Y827283D01*
G01X70079D02*
Y828858D01*
G01X70103Y827283D02*
Y828858D01*
G01X70110Y839025D02*
Y836500D01*
G01X70113Y840507D02*
Y839950D01*
G01X70866Y845217D02*
Y842815D01*
G01Y840846D02*
Y837067D01*
G01X71426Y828858D02*
Y827283D01*
G01X71541Y836500D02*
Y839025D01*
G01X71796Y827283D02*
Y828858D01*
G01X73000Y839025D02*
Y836500D01*
G01X73228Y845748D02*
Y983622D01*
G01X73873Y828858D02*
Y827283D01*
G01X74243D02*
Y828858D01*
G01X74331Y983169D02*
Y846201D01*
G01X74430Y836500D02*
Y839025D01*
G01X75567Y828858D02*
Y827283D01*
G01X75591Y828858D02*
Y827283D01*
G01X75625D02*
Y828858D01*
G01X75823Y839429D02*
Y836500D01*
G01X76772Y843445D02*
Y845748D01*
G01X78346Y983169D02*
Y846201D01*
G01X79328Y845748D02*
Y845807D01*
G01X79967Y846201D02*
Y843445D01*
G01X81622Y836500D02*
Y842254D01*
G01X83082D02*
Y836500D01*
G01X87331Y846201D02*
Y983169D01*
G01X87841Y846201D02*
Y843445D01*
G01X93696Y846201D02*
Y848976D01*
G01X94170Y843445D02*
Y848976D01*
G01X94488Y835098D02*
Y848976D01*
G01X88428Y840507D02*
X89697Y838647D01*
G01X90044Y840507D02*
X90650Y839521D01*
G01X91426Y838656D02*
X92747Y836500D01*
G01X90453Y837778D02*
X91198Y836500D01*
G01X79783Y835984D02*
X79886Y836353D01*
X79982Y836683D01*
X80063Y836945D01*
X80115Y837111D01*
X80132Y837165D01*
G01X84041Y842598D02*
X84059Y842654D01*
X84111Y842819D01*
X84190Y843078D01*
X84285Y843405D01*
X84390Y843780D01*
G01X90453Y837778D02*
X89662Y836500D01*
G01X79328Y845807D02*
X79583Y846201D01*
G01X89697Y838647D02*
X88254Y836500D01*
G01X91339Y840507D02*
X90650Y839521D01*
G01X92721Y840507D02*
X91426Y838656D01*
G01X75000Y826496D02*
X70669D01*
G01X75625Y827283D02*
X70044D01*
G01Y828858D02*
X75625D01*
G01X70669Y829646D02*
X75000D01*
G01X81024Y832343D02*
X64646D01*
G01X79783Y835984D02*
X84390D01*
G01X89662Y836500D02*
X88254D01*
G01X92747D02*
X91198D01*
G01X83082D02*
X81622D01*
G01X75823D02*
X74430D01*
G01X73000D02*
X71541D01*
G01X70110D02*
X68670D01*
G01X94488Y837067D02*
X70866D01*
G01X84041Y837165D02*
X80132D01*
G01X88097Y837656D02*
X86594D01*
G01X88228Y838099D02*
X85228D01*
G01X86655Y838925D02*
X85229D01*
G01X90044Y840507D02*
X88428D01*
G01X92721D02*
X91339D01*
G01X70113D02*
X68670D01*
G01X94488Y840846D02*
X70866D01*
G01X83082Y842254D02*
X81622D01*
G01X80132Y842598D02*
X84041D01*
G01X94488Y842815D02*
X70866D01*
G01X84390Y843780D02*
X79783D01*
G01X94488Y845217D02*
X70866D01*
G01X79328Y845748D02*
X73228D01*
G01X79328Y845807D02*
X73228D01*
G01X93696Y846201D02*
X73228D01*
G01X74331Y847382D02*
X64961D01*
G01X72893Y839956D02*
G03X70113Y839950I-1387J-1207D01*
G01X75529Y840100D02*
G03X72893Y839956I-1248J-1351D01*
G01X70669Y829646D02*
G03Y826496I0J-1575D01*
G01X74430Y839025D02*
G03X73000I-715J0D01*
G01X71541D02*
G03X70110I-716J0D01*
G01X79502Y837609D02*
G03Y839294I-2236J843D01*
G01X75000Y826496D02*
G03Y829646I0J1575D01*
G01X75823Y839429D02*
G03X75529Y840100I-913J0D01*
G01X80324Y840154D02*
G03X77277Y840153I-1523J-2362D01*
G01X77278Y836709D02*
G03X80324Y836710I1522J2362D01*
G01X80845Y837276D02*
G03X80844Y839588I-2163J1155D01*
G01X76756D02*
G03X76757Y837274I2163J-1156D01*
G01X78030Y839294D02*
G03Y837609I2236J-843D01*
G01X77277Y840153D02*
G03X76756Y839588I830J-1288D01*
G01X80844D02*
G03X80323Y840154I-1352J-722D01*
G01X80324Y836711D02*
G03X80845Y837276I-830J1288D01*
G01X76757Y837274D02*
G03X77278Y836709I1351J723D01*
G01X79502Y839294D02*
G03X78029I-736J-278D01*
G01Y837609D02*
G03X79502I737J277D01*
G01X84390Y835984D02*
G03Y843780I-2303J3898D01*
G01X79783D02*
G03Y835984I2303J-3898D01*
G01X85591Y839882D02*
G03I-3505J0D01*
G01X80132Y842598D02*
G03Y837165I1954J-2716D01*
G01X84041D02*
G03Y842598I-1954J2717D01*
G01X84252Y839882D02*
G03I-2166J0D01*
G01X83847Y839333D02*
G03X83673Y838673I4018J-1412D01*
G01D02*
G03Y838176I3525J-248D01*
G01X88228Y838099D02*
G03X87889Y839542I-3015J53D01*
G01X83673Y838178D02*
G03X83935Y837315I2971J431D01*
G01X86655Y840515D02*
G03X85012Y840472I-757J-2475D01*
G01X83934Y837318D02*
G03X85672Y836300I1807J1093D01*
G01X85012Y840472D02*
G03X83847Y839333I729J-1911D01*
G01X87889Y839542D02*
G03X86655Y840516I-1735J-930D01*
G01X87254Y836587D02*
G03X88098Y837656I-703J1423D01*
G01X85229Y838099D02*
G03X86003Y837291I792J-16D01*
G01D02*
G03X86594Y837656I9J646D01*
G01X85669Y836300D02*
G03X87254Y836587I262J3073D01*
G01X86654Y838925D02*
G03X85229I-713J82D01*
G01X40551Y843445D02*
Y836280D01*
G01X42520Y985925D02*
Y843445D01*
G01X43701Y847579D02*
Y918484D01*
G01X40519Y835130D02*
X40462Y835269D01*
X40457Y835509D01*
G01X40493Y835830D02*
X40457Y835506D01*
X40463Y835265D01*
X40519Y835130D01*
G01X40493Y835828D02*
X40547Y836206D01*
G01X42520Y845413D02*
X44488Y843445D01*
G01Y848366D02*
X42520Y846398D01*
G01X94488Y835098D02*
X40551D01*
G01Y836280D02*
X66929D01*
G01X42520Y843445D02*
X39236D01*
G01X44488D02*
X94488D01*
G01X64646Y848563D02*
Y822165D01*
G01X81024Y835098D02*
Y822165D01*
G01X64646D02*
X81024D01*
G01X51941Y852992D02*
X51938Y853030D01*
X51930Y853067D01*
X51917Y853101D01*
X51900Y853131D01*
X51879Y853156D01*
X51856Y853174D01*
X51830Y853185D01*
X51802Y853189D01*
G01X51941Y856142D02*
X51938Y856180D01*
X51930Y856217D01*
X51917Y856250D01*
X51900Y856281D01*
X51879Y856305D01*
X51856Y856323D01*
X51830Y856335D01*
X51802Y856339D01*
G01X51941Y859291D02*
X51938Y859330D01*
X51930Y859366D01*
X51917Y859400D01*
X51900Y859430D01*
X51879Y859455D01*
X51856Y859473D01*
X51830Y859484D01*
X51802Y859488D01*
G01X51941Y862441D02*
X51938Y862479D01*
X51930Y862516D01*
X51917Y862550D01*
X51900Y862580D01*
X51879Y862604D01*
X51856Y862622D01*
X51830Y862634D01*
X51802Y862638D01*
G01X51428Y865591D02*
Y865197D01*
G01Y862441D02*
Y862047D01*
G01Y859291D02*
Y858898D01*
G01Y856142D02*
Y855748D01*
G01Y852992D02*
Y852598D01*
G01X51941D02*
Y852992D01*
G01Y855748D02*
Y856142D01*
G01Y858898D02*
Y859291D01*
G01Y865197D02*
Y865591D01*
G01Y862047D02*
Y862441D01*
G01X52112Y862382D02*
Y861988D01*
G01Y857382D02*
Y856988D01*
G01Y852382D02*
Y851988D01*
G01X52956Y862382D02*
Y861988D01*
G01Y857382D02*
Y856988D01*
G01Y852382D02*
Y851988D01*
G01X53118Y852598D02*
Y852992D01*
G01Y855748D02*
Y856142D01*
G01Y858898D02*
Y859291D01*
G01Y865197D02*
Y865591D01*
G01Y862047D02*
Y862441D01*
G01X52529Y852972D02*
X52956Y852382D01*
G01X52529Y857972D02*
X52956Y857382D01*
G01X51839Y852972D02*
X52112Y852382D01*
G01X51839Y857972D02*
X52112Y857382D01*
G01X51839Y862972D02*
X52112Y862382D01*
G01X62992Y848366D02*
Y981004D01*
G01X69213Y866083D02*
Y848563D01*
G01X71181Y980807D02*
Y848563D01*
G01X75170Y862638D02*
Y861850D01*
G01Y865787D02*
Y865000D01*
G01Y859488D02*
Y858701D01*
G01Y853189D02*
Y852402D01*
G01Y856339D02*
Y855551D01*
G01X75197Y862638D02*
Y861850D01*
G01Y865787D02*
Y865000D01*
G01Y859488D02*
Y858701D01*
G01Y853189D02*
Y852402D01*
G01Y856339D02*
Y855551D01*
G01X75573Y862638D02*
Y861850D01*
G01Y865787D02*
Y865000D01*
G01Y859488D02*
Y858701D01*
G01Y853189D02*
Y852402D01*
G01Y856339D02*
Y855551D01*
G01X75787Y862972D02*
Y861398D01*
G01Y857972D02*
Y856398D01*
G01Y852972D02*
Y851398D01*
G01X76772Y863760D02*
Y860610D01*
G01Y858760D02*
Y855610D01*
G01Y853760D02*
Y850610D01*
G01X77756Y863760D02*
Y860610D01*
G01Y858760D02*
Y855610D01*
G01Y853760D02*
Y850610D01*
G01X78740Y862972D02*
Y861398D01*
G01Y857972D02*
Y856398D01*
G01Y852972D02*
Y851398D01*
G01X78801Y980591D02*
Y848976D01*
G01X78935Y852402D02*
Y853189D01*
G01Y855551D02*
Y856339D01*
G01Y858701D02*
Y859488D01*
G01Y861850D02*
Y862638D01*
G01Y865000D02*
Y865787D01*
G01X80919Y852402D02*
Y853189D01*
G01Y855551D02*
Y856339D01*
G01Y858701D02*
Y859488D01*
G01Y861850D02*
Y862638D01*
G01Y865000D02*
Y865787D01*
G01X81890Y851398D02*
Y852972D01*
G01Y856398D02*
Y857972D01*
G01Y861398D02*
Y862972D01*
G01X82570Y862638D02*
Y861850D01*
G01Y865787D02*
Y865000D01*
G01Y859488D02*
Y858701D01*
G01Y853189D02*
Y852402D01*
G01Y856339D02*
Y855551D01*
G01X84298Y850728D02*
Y852402D01*
G01Y853189D02*
Y855551D01*
G01Y856339D02*
Y858701D01*
G01Y859488D02*
Y861850D01*
G01Y862638D02*
Y865000D01*
G01X85237Y862638D02*
Y861850D01*
G01Y865787D02*
Y865000D01*
G01Y859488D02*
Y858701D01*
G01Y853189D02*
Y852402D01*
G01Y856339D02*
Y855551D01*
G01X85384Y862638D02*
Y861850D01*
G01Y865787D02*
Y865000D01*
G01Y859488D02*
Y858701D01*
G01Y853189D02*
Y852402D01*
G01Y856339D02*
Y855551D01*
G01X86976Y862638D02*
Y861850D01*
G01Y865787D02*
Y865000D01*
G01Y859488D02*
Y858701D01*
G01Y853189D02*
Y852402D01*
G01Y856339D02*
Y855551D01*
G01X87918Y852402D02*
Y853189D01*
G01Y855551D02*
Y856339D01*
G01Y858701D02*
Y859488D01*
G01Y861850D02*
Y862638D01*
G01Y865000D02*
Y865787D01*
G01X90754Y852402D02*
Y853189D01*
G01Y855551D02*
Y856339D01*
G01Y858701D02*
Y859488D01*
G01Y861850D02*
Y862638D01*
G01Y865000D02*
Y865787D01*
G01X90943Y862638D02*
Y861850D01*
G01Y865787D02*
Y865000D01*
G01Y859488D02*
Y858701D01*
G01Y853189D02*
Y852402D01*
G01Y856339D02*
Y855551D01*
G01X92717Y862638D02*
Y861850D01*
G01Y865787D02*
Y865000D01*
G01Y859488D02*
Y858701D01*
G01Y853189D02*
Y852402D01*
G01Y856339D02*
Y855551D01*
G01X51428Y865197D02*
X51417Y865098D01*
X51389Y865026D01*
X51351Y865000D01*
G01X51428Y862047D02*
X51417Y861949D01*
X51389Y861877D01*
X51351Y861850D01*
G01X51428Y858898D02*
X51417Y858799D01*
X51389Y858727D01*
X51351Y858701D01*
G01X51428Y855748D02*
X51417Y855650D01*
X51389Y855578D01*
X51351Y855551D01*
G01X51428Y852598D02*
X51417Y852500D01*
X51389Y852428D01*
X51351Y852402D01*
G01Y853189D02*
X51389Y853163D01*
X51417Y853091D01*
X51428Y852992D01*
G01X51351Y856339D02*
X51389Y856312D01*
X51417Y856240D01*
X51428Y856142D01*
G01X51351Y859488D02*
X51389Y859462D01*
X51417Y859390D01*
X51428Y859291D01*
G01X52529Y862972D02*
X52956Y862382D01*
G01X52112Y861988D02*
X51839Y861398D01*
G01X52112Y856988D02*
X51839Y856398D01*
G01X52112Y851988D02*
X51839Y851398D01*
G01X51351Y862638D02*
X51389Y862611D01*
X51417Y862539D01*
X51428Y862441D01*
G01X52529Y861398D02*
X52956Y861988D01*
G01X52529Y856398D02*
X52956Y856988D01*
G01X52529Y851398D02*
X52956Y851988D01*
G01X64646Y848563D02*
X71181D01*
G01X94488Y848976D02*
X74331D01*
G01Y849154D02*
X64961D01*
G01X77756Y850610D02*
X76772D01*
G01X87331Y850728D02*
X78346D01*
G01X77756Y850807D02*
X76772D01*
G01X77756Y851201D02*
X76772D01*
G01X74724Y851398D02*
X81890D01*
G01X92717Y852402D02*
X85384D01*
G01X85237D02*
X73228D01*
G01X74724Y852972D02*
X81890D01*
G01X51802Y852402D02*
X51829Y852405D01*
X51855Y852416D01*
X51879Y852434D01*
X51900Y852459D01*
X51917Y852489D01*
X51930Y852523D01*
X51938Y852559D01*
X51941Y852598D01*
G01X51802Y855551D02*
X51829Y855555D01*
X51855Y855566D01*
X51879Y855584D01*
X51900Y855609D01*
X51917Y855639D01*
X51930Y855672D01*
X51938Y855709D01*
X51941Y855748D01*
G01X51802Y858701D02*
X51829Y858704D01*
X51855Y858715D01*
X51879Y858733D01*
X51900Y858758D01*
X51917Y858788D01*
X51930Y858822D01*
X51938Y858859D01*
X51941Y858898D01*
G01X51802Y861850D02*
X51829Y861854D01*
X51855Y861865D01*
X51879Y861883D01*
X51900Y861908D01*
X51917Y861938D01*
X51930Y861972D01*
X51938Y862008D01*
X51941Y862047D01*
G01X51802Y865000D02*
X51829Y865004D01*
X51855Y865015D01*
X51879Y865033D01*
X51900Y865057D01*
X51917Y865087D01*
X51930Y865121D01*
X51938Y865158D01*
X51941Y865197D01*
G01X77756Y853169D02*
X76772D01*
G01X85237Y853189D02*
X73228D01*
G01X85384D02*
X92717D01*
G01X77756Y853563D02*
X76772D01*
G01X77756Y853760D02*
X76772D01*
G01X92717Y855551D02*
X85384D01*
G01X85237D02*
X73228D01*
G01X77756Y855610D02*
X76772D01*
G01X77756Y855807D02*
X76772D01*
G01X77756Y856201D02*
X76772D01*
G01X85237Y856339D02*
X73228D01*
G01X85384D02*
X92717D01*
G01X81890Y856398D02*
X74724D01*
G01X81890Y857972D02*
X74724D01*
G01X77756Y858169D02*
X76772D01*
G01X77756Y858563D02*
X76772D01*
G01X92717Y858701D02*
X85384D01*
G01X85237D02*
X73228D01*
G01X77756Y858760D02*
X76772D01*
G01X85237Y859488D02*
X73228D01*
G01X85384D02*
X92717D01*
G01X77756Y860610D02*
X76772D01*
G01X77756Y860807D02*
X76772D01*
G01X77756Y861201D02*
X76772D01*
G01X74724Y861398D02*
X81890D01*
G01X92717Y861850D02*
X85384D01*
G01X85237D02*
X73228D01*
G01X85237Y862638D02*
X73228D01*
G01X85384D02*
X92717D01*
G01X74724Y862972D02*
X81890D01*
G01X77756Y863169D02*
X76772D01*
G01X77756Y863563D02*
X76772D01*
G01X77756Y863760D02*
X76772D01*
G01X73228Y864980D02*
X74331D01*
G01X92717Y865000D02*
X85384D01*
G01X85237D02*
X73228D01*
G01X74331Y858366D02*
G03X74724Y857972I394J0D01*
G01Y856398D02*
G03X74331Y856004I1J-394D01*
G01Y863366D02*
G03X74724Y862972I394J0D01*
G01Y861398D02*
G03X74331Y861004I1J-394D01*
G01Y853366D02*
G03X74724Y852972I394J0D01*
G01Y851398D02*
G03X74331Y851004I1J-394D01*
G01X43642Y847972D02*
Y981398D01*
G01X44488Y981004D02*
Y848366D01*
G01X46369Y851988D02*
Y852382D01*
G01Y856988D02*
Y857382D01*
G01Y861988D02*
Y862382D01*
G01X46506Y865591D02*
Y865197D01*
G01Y862441D02*
Y862047D01*
G01Y859291D02*
Y858898D01*
G01Y856142D02*
Y855748D01*
G01Y852992D02*
Y852598D01*
G01X50987Y857382D02*
Y856988D01*
G01Y851988D02*
Y852382D01*
G01Y861988D02*
Y862382D01*
G01X46369Y851988D02*
X46506Y851791D01*
X46644Y851594D01*
X46784Y851398D01*
G01X46369Y856988D02*
X46506Y856791D01*
X46644Y856594D01*
X46784Y856398D01*
G01X46369Y861988D02*
X46506Y861791D01*
X46644Y861594D01*
X46784Y861398D01*
G01X46506Y852598D02*
X46538Y852501D01*
X46626Y852429D01*
X46753Y852402D01*
G01X46506Y855748D02*
X46538Y855651D01*
X46626Y855579D01*
X46753Y855551D01*
G01X46506Y858898D02*
X46538Y858800D01*
X46626Y858728D01*
X46753Y858701D01*
G01X46506Y862047D02*
X46538Y861950D01*
X46626Y861878D01*
X46753Y861850D01*
G01X50987Y852382D02*
X50909Y852972D01*
G01Y857972D02*
X50987Y857382D01*
G01Y862382D02*
X50909Y862972D01*
G01X50987Y861988D02*
X50909Y861398D01*
G01Y856398D02*
X50987Y856988D01*
G01Y851988D02*
X50909Y851398D01*
G01X46784Y862972D02*
X46644Y862776D01*
X46506Y862580D01*
X46369Y862382D01*
G01X46784Y857972D02*
X46644Y857776D01*
X46506Y857580D01*
X46369Y857382D01*
G01X46784Y852972D02*
X46644Y852776D01*
X46506Y852580D01*
X46369Y852382D01*
G01X46753Y865000D02*
X46627Y865027D01*
X46538Y865100D01*
X46506Y865197D01*
G01X42520Y847972D02*
X73228D01*
G01X44488Y848366D02*
X62992D01*
G01X46784Y851398D02*
X52529D01*
G01X46369Y851988D02*
X52956D01*
G01Y852382D02*
X46369D01*
G01X46753Y852402D02*
X52838D01*
G01X53118Y852598D02*
X46506D01*
G01X52529Y852972D02*
X46784D01*
G01X46506Y852992D02*
X53118D01*
G01X46753Y853189D02*
X52838D01*
G01X46753Y855551D02*
X52838D01*
G01X53118Y855748D02*
X46506D01*
G01Y856142D02*
X53118D01*
G01X46753Y856339D02*
X52838D01*
G01X46784Y856398D02*
X52529D01*
G01X46369Y856988D02*
X52956D01*
G01Y857382D02*
X46369D01*
G01X52529Y857972D02*
X46784D01*
G01X46753Y858701D02*
X52838D01*
G01X53118Y858898D02*
X46506D01*
G01Y859291D02*
X53118D01*
G01X46753Y859488D02*
X52838D01*
G01X46784Y861398D02*
X52529D01*
G01X46753Y861850D02*
X52838D01*
G01X46369Y861988D02*
X52956D01*
G01X53118Y862047D02*
X46506D01*
G01X52956Y862382D02*
X46369D01*
G01X46506Y862441D02*
X53118D01*
G01X46753Y862638D02*
X52838D01*
G01X52529Y862972D02*
X46784D01*
G01X46753Y865000D02*
X52838D01*
G01X53118Y865197D02*
X46506D01*
G01X46753Y853189D02*
X46626Y853161D01*
X46537Y853088D01*
X46506Y852992D01*
G01X46753Y856339D02*
X46626Y856311D01*
X46537Y856238D01*
X46506Y856142D01*
G01X46753Y859488D02*
X46626Y859460D01*
X46537Y859387D01*
X46506Y859291D01*
G01X46753Y862638D02*
X46626Y862610D01*
X46537Y862537D01*
X46506Y862441D01*
G01X51941Y887638D02*
X51938Y887676D01*
X51930Y887713D01*
X51917Y887746D01*
X51900Y887777D01*
X51879Y887801D01*
X51856Y887819D01*
X51830Y887831D01*
X51802Y887835D01*
G01X51941Y890787D02*
X51938Y890826D01*
X51930Y890862D01*
X51917Y890896D01*
X51900Y890926D01*
X51879Y890951D01*
X51856Y890969D01*
X51830Y890980D01*
X51802Y890984D01*
G01X51941Y893937D02*
X51938Y893975D01*
X51930Y894012D01*
X51917Y894046D01*
X51900Y894076D01*
X51879Y894100D01*
X51856Y894119D01*
X51830Y894130D01*
X51802Y894134D01*
G01X51941Y897087D02*
X51938Y897125D01*
X51930Y897161D01*
X51917Y897195D01*
X51900Y897226D01*
X51879Y897250D01*
X51856Y897268D01*
X51830Y897280D01*
X51802Y897283D01*
G01X51941Y900236D02*
X51938Y900274D01*
X51930Y900311D01*
X51917Y900345D01*
X51900Y900375D01*
X51879Y900400D01*
X51856Y900418D01*
X51830Y900429D01*
X51802Y900433D01*
G01X51941Y903386D02*
X51938Y903424D01*
X51930Y903461D01*
X51917Y903494D01*
X51900Y903525D01*
X51879Y903549D01*
X51856Y903567D01*
X51830Y903579D01*
X51802Y903583D01*
G01X51941Y906535D02*
X51938Y906574D01*
X51930Y906610D01*
X51917Y906644D01*
X51900Y906674D01*
X51879Y906699D01*
X51856Y906717D01*
X51830Y906728D01*
X51802Y906732D01*
G01X51941Y909685D02*
X51938Y909723D01*
X51930Y909760D01*
X51917Y909794D01*
X51900Y909824D01*
X51879Y909848D01*
X51856Y909867D01*
X51830Y909878D01*
X51802Y909882D01*
G01X51941Y912835D02*
X51938Y912873D01*
X51930Y912909D01*
X51917Y912943D01*
X51900Y912974D01*
X51879Y912998D01*
X51856Y913016D01*
X51830Y913028D01*
X51802Y913031D01*
G01X51941Y915984D02*
X51938Y916022D01*
X51930Y916059D01*
X51917Y916093D01*
X51900Y916123D01*
X51879Y916148D01*
X51856Y916166D01*
X51830Y916177D01*
X51802Y916181D01*
G01X51941Y919134D02*
X51938Y919172D01*
X51930Y919209D01*
X51917Y919243D01*
X51900Y919273D01*
X51879Y919297D01*
X51856Y919315D01*
X51830Y919327D01*
X51802Y919331D01*
G01X51428Y919134D02*
Y918740D01*
G01Y915984D02*
Y915591D01*
G01Y909685D02*
Y909291D01*
G01Y912835D02*
Y912441D01*
G01Y906535D02*
Y906142D01*
G01Y900236D02*
Y899843D01*
G01Y903386D02*
Y902992D01*
G01Y897087D02*
Y896693D01*
G01Y890787D02*
Y890394D01*
G01Y893937D02*
Y893543D01*
G01Y887638D02*
Y887244D01*
G01X51941D02*
Y887638D01*
G01Y890394D02*
Y890787D01*
G01Y893543D02*
Y893937D01*
G01Y896693D02*
Y897087D01*
G01Y899843D02*
Y900236D01*
G01Y902992D02*
Y903386D01*
G01Y906142D02*
Y906535D01*
G01Y909291D02*
Y909685D01*
G01Y912441D02*
Y912835D01*
G01Y915591D02*
Y915984D01*
G01Y918740D02*
Y919134D01*
G01X52112Y917382D02*
Y916988D01*
G01Y912382D02*
Y911988D01*
G01Y902382D02*
Y901988D01*
G01Y897382D02*
Y896988D01*
G01Y892382D02*
Y891988D01*
G01Y887382D02*
Y886988D01*
G01X52956Y917382D02*
Y916988D01*
G01Y912382D02*
Y911988D01*
G01Y902382D02*
Y901988D01*
G01Y897382D02*
Y896988D01*
G01Y892382D02*
Y891988D01*
G01Y887382D02*
Y886988D01*
G01X53118Y887244D02*
Y887638D01*
G01Y890394D02*
Y890787D01*
G01Y893543D02*
Y893937D01*
G01Y896693D02*
Y897087D01*
G01Y899843D02*
Y900236D01*
G01Y902992D02*
Y903386D01*
G01Y906142D02*
Y906535D01*
G01Y909291D02*
Y909685D01*
G01Y912441D02*
Y912835D01*
G01Y915591D02*
Y915984D01*
G01Y918740D02*
Y919134D01*
G01X51839Y887972D02*
X52112Y887382D01*
G01X51839Y892972D02*
X52112Y892382D01*
G01X51839Y897972D02*
X52112Y897382D01*
G01X51839Y902972D02*
X52112Y902382D01*
G01X51839Y912972D02*
X52112Y912382D01*
G01X69213Y922579D02*
Y906240D01*
G01Y903878D02*
Y887343D01*
G01X74803Y908760D02*
Y905610D01*
G01X75170Y919331D02*
Y918543D01*
G01Y916181D02*
Y915394D01*
G01Y909882D02*
Y909094D01*
G01Y913031D02*
Y912244D01*
G01Y906732D02*
Y905945D01*
G01Y900433D02*
Y899646D01*
G01Y903583D02*
Y902795D01*
G01Y897283D02*
Y896496D01*
G01Y890984D02*
Y890197D01*
G01Y894134D02*
Y893346D01*
G01Y887835D02*
Y887047D01*
G01X75197Y919331D02*
Y918543D01*
G01Y916181D02*
Y915394D01*
G01Y909882D02*
Y909094D01*
G01Y913031D02*
Y912244D01*
G01Y906732D02*
Y905945D01*
G01Y900433D02*
Y899646D01*
G01Y903583D02*
Y902795D01*
G01Y897283D02*
Y896496D01*
G01Y890984D02*
Y890197D01*
G01Y894134D02*
Y893346D01*
G01Y887835D02*
Y887047D01*
G01X75573Y919331D02*
Y918543D01*
G01Y916181D02*
Y915394D01*
G01Y909882D02*
Y909094D01*
G01Y913031D02*
Y912244D01*
G01Y906732D02*
Y905945D01*
G01Y900433D02*
Y899646D01*
G01Y903583D02*
Y902795D01*
G01Y897283D02*
Y896496D01*
G01Y890984D02*
Y890197D01*
G01Y894134D02*
Y893346D01*
G01Y887835D02*
Y887047D01*
G01X75787Y917972D02*
Y916398D01*
G01Y912972D02*
Y911398D01*
G01Y908760D02*
Y905610D01*
G01Y902972D02*
Y901398D01*
G01Y897972D02*
Y896398D01*
G01Y892972D02*
Y891398D01*
G01Y887972D02*
Y886398D01*
G01X76772Y923760D02*
Y920610D01*
G01Y918760D02*
Y915610D01*
G01Y913760D02*
Y910610D01*
G01Y907972D02*
Y906398D01*
G01Y903760D02*
Y900610D01*
G01Y898760D02*
Y895610D01*
G01Y893760D02*
Y890610D01*
G01Y888760D02*
Y885610D01*
G01X77756Y923760D02*
Y920610D01*
G01Y918760D02*
Y915610D01*
G01Y913760D02*
Y910610D01*
G01Y903760D02*
Y900610D01*
G01Y898760D02*
Y895610D01*
G01Y893760D02*
Y890610D01*
G01Y888760D02*
Y885610D01*
G01X78740Y917972D02*
Y916398D01*
G01Y912972D02*
Y911398D01*
G01Y902972D02*
Y901398D01*
G01Y897972D02*
Y896398D01*
G01Y892972D02*
Y891398D01*
G01Y887972D02*
Y886398D01*
G01X78935Y887047D02*
Y887835D01*
G01Y890197D02*
Y890984D01*
G01Y893346D02*
Y894134D01*
G01Y896496D02*
Y897283D01*
G01Y899646D02*
Y900433D01*
G01Y902795D02*
Y903583D01*
G01Y905945D02*
Y906732D01*
G01Y909094D02*
Y909882D01*
G01Y912244D02*
Y913031D01*
G01Y915394D02*
Y916181D01*
G01Y918543D02*
Y919331D01*
G01X79921Y906398D02*
Y907972D01*
G01X80919Y887047D02*
Y887835D01*
G01Y890197D02*
Y890984D01*
G01Y893346D02*
Y894134D01*
G01Y896496D02*
Y897283D01*
G01Y899646D02*
Y900433D01*
G01Y902795D02*
Y903583D01*
G01Y905945D02*
Y906732D01*
G01Y909094D02*
Y909882D01*
G01Y912244D02*
Y913031D01*
G01Y915394D02*
Y916181D01*
G01Y918543D02*
Y919331D01*
G01X81890Y886398D02*
Y887972D01*
G01Y891398D02*
Y892972D01*
G01Y896398D02*
Y897972D01*
G01Y901398D02*
Y902972D01*
G01Y911398D02*
Y912972D01*
G01Y916398D02*
Y917972D01*
G01X82570Y919331D02*
Y918543D01*
G01Y916181D02*
Y915394D01*
G01Y909882D02*
Y909094D01*
G01Y913031D02*
Y912244D01*
G01Y906732D02*
Y905945D01*
G01Y900433D02*
Y899646D01*
G01Y903583D02*
Y902795D01*
G01Y897283D02*
Y896496D01*
G01Y890984D02*
Y890197D01*
G01Y894134D02*
Y893346D01*
G01Y887835D02*
Y887047D01*
G01X84298Y887835D02*
Y890197D01*
G01Y890984D02*
Y893346D01*
G01Y894134D02*
Y896496D01*
G01Y897283D02*
Y899646D01*
G01Y900433D02*
Y902795D01*
G01Y903583D02*
Y905945D01*
G01Y906732D02*
Y909094D01*
G01Y909882D02*
Y912244D01*
G01Y913031D02*
Y915394D01*
G01Y916181D02*
Y918543D01*
G01Y919331D02*
Y921693D01*
G01X85237Y919331D02*
Y918543D01*
G01Y916181D02*
Y915394D01*
G01Y909882D02*
Y909094D01*
G01Y913031D02*
Y912244D01*
G01Y906732D02*
Y905945D01*
G01Y900433D02*
Y899646D01*
G01Y903583D02*
Y902795D01*
G01Y897283D02*
Y896496D01*
G01Y890984D02*
Y890197D01*
G01Y894134D02*
Y893346D01*
G01Y887835D02*
Y887047D01*
G01X85384Y919331D02*
Y918543D01*
G01Y916181D02*
Y915394D01*
G01Y909882D02*
Y909094D01*
G01Y913031D02*
Y912244D01*
G01Y906732D02*
Y905945D01*
G01Y900433D02*
Y899646D01*
G01Y903583D02*
Y902795D01*
G01Y897283D02*
Y896496D01*
G01Y890984D02*
Y890197D01*
G01Y894134D02*
Y893346D01*
G01Y887835D02*
Y887047D01*
G01X86976Y919331D02*
Y918543D01*
G01Y916181D02*
Y915394D01*
G01Y909882D02*
Y909094D01*
G01Y913031D02*
Y912244D01*
G01Y906732D02*
Y905945D01*
G01Y900433D02*
Y899646D01*
G01Y903583D02*
Y902795D01*
G01Y897283D02*
Y896496D01*
G01Y890984D02*
Y890197D01*
G01Y894134D02*
Y893346D01*
G01Y887835D02*
Y887047D01*
G01X87918D02*
Y887835D01*
G01Y890197D02*
Y890984D01*
G01Y893346D02*
Y894134D01*
G01Y896496D02*
Y897283D01*
G01Y899646D02*
Y900433D01*
G01Y902795D02*
Y903583D01*
G01Y905945D02*
Y906732D01*
G01Y909094D02*
Y909882D01*
G01Y912244D02*
Y913031D01*
G01Y915394D02*
Y916181D01*
G01Y918543D02*
Y919331D01*
G01X90754Y887047D02*
Y887835D01*
G01Y890197D02*
Y890984D01*
G01Y893346D02*
Y894134D01*
G01Y896496D02*
Y897283D01*
G01Y899646D02*
Y900433D01*
G01Y902795D02*
Y903583D01*
G01Y905945D02*
Y906732D01*
G01Y909094D02*
Y909882D01*
G01Y912244D02*
Y913031D01*
G01Y915394D02*
Y916181D01*
G01Y918543D02*
Y919331D01*
G01X90943D02*
Y918543D01*
G01Y916181D02*
Y915394D01*
G01Y909882D02*
Y909094D01*
G01Y913031D02*
Y912244D01*
G01Y906732D02*
Y905945D01*
G01Y900433D02*
Y899646D01*
G01Y903583D02*
Y902795D01*
G01Y897283D02*
Y896496D01*
G01Y890984D02*
Y890197D01*
G01Y894134D02*
Y893346D01*
G01Y887835D02*
Y887047D01*
G01X92717Y919331D02*
Y918543D01*
G01Y916181D02*
Y915394D01*
G01Y909882D02*
Y909094D01*
G01Y913031D02*
Y912244D01*
G01Y906732D02*
Y905945D01*
G01Y900433D02*
Y899646D01*
G01Y903583D02*
Y902795D01*
G01Y897283D02*
Y896496D01*
G01Y890984D02*
Y890197D01*
G01Y894134D02*
Y893346D01*
G01Y887835D02*
Y887047D01*
G01X51428Y918740D02*
X51417Y918642D01*
X51389Y918570D01*
X51351Y918543D01*
G01X51428Y915591D02*
X51417Y915492D01*
X51389Y915420D01*
X51351Y915394D01*
G01X51428Y912441D02*
X51417Y912343D01*
X51389Y912270D01*
X51351Y912244D01*
G01X51428Y909291D02*
X51417Y909193D01*
X51389Y909121D01*
X51351Y909094D01*
G01X51428Y906142D02*
X51417Y906043D01*
X51389Y905971D01*
X51351Y905945D01*
G01X51428Y902992D02*
X51417Y902894D01*
X51389Y902822D01*
X51351Y902795D01*
G01X51428Y899843D02*
X51417Y899744D01*
X51389Y899672D01*
X51351Y899646D01*
G01X51428Y896693D02*
X51417Y896594D01*
X51389Y896522D01*
X51351Y896496D01*
G01X51428Y893543D02*
X51417Y893445D01*
X51389Y893373D01*
X51351Y893346D01*
G01X51428Y890394D02*
X51417Y890295D01*
X51389Y890223D01*
X51351Y890197D01*
G01X51428Y887244D02*
X51417Y887146D01*
X51389Y887074D01*
X51351Y887047D01*
G01X52112Y916988D02*
X51839Y916398D01*
G01X52112Y911988D02*
X51839Y911398D01*
G01X52112Y901988D02*
X51839Y901398D01*
G01X52112Y896988D02*
X51839Y896398D01*
G01X52529Y887972D02*
X52956Y887382D01*
G01X52529Y892972D02*
X52956Y892382D01*
G01X52529Y897972D02*
X52956Y897382D01*
G01X52529Y902972D02*
X52956Y902382D01*
G01X52529Y912972D02*
X52956Y912382D01*
G01X52529Y917972D02*
X52956Y917382D01*
G01X51839Y917972D02*
X52112Y917382D01*
G01Y891988D02*
X51839Y891398D01*
G01X52112Y886988D02*
X51839Y886398D01*
G01X52529Y916398D02*
X52956Y916988D01*
G01X52529Y911398D02*
X52956Y911988D01*
G01X52529Y901398D02*
X52956Y901988D01*
G01X52529Y896398D02*
X52956Y896988D01*
G01X52529Y891398D02*
X52956Y891988D01*
G01X52529Y886398D02*
X52956Y886988D01*
G01X51351Y887835D02*
X51389Y887808D01*
X51417Y887736D01*
X51428Y887638D01*
G01X51351Y890984D02*
X51389Y890958D01*
X51417Y890886D01*
X51428Y890787D01*
G01X51351Y894134D02*
X51389Y894107D01*
X51417Y894035D01*
X51428Y893937D01*
G01X51351Y897283D02*
X51389Y897257D01*
X51417Y897185D01*
X51428Y897087D01*
G01X51351Y900433D02*
X51389Y900407D01*
X51417Y900335D01*
X51428Y900236D01*
G01X51351Y903583D02*
X51389Y903556D01*
X51417Y903484D01*
X51428Y903386D01*
G01X51351Y906732D02*
X51389Y906706D01*
X51417Y906634D01*
X51428Y906535D01*
G01X51351Y909882D02*
X51389Y909856D01*
X51417Y909783D01*
X51428Y909685D01*
G01X51351Y913031D02*
X51389Y913005D01*
X51417Y912933D01*
X51428Y912835D01*
G01X51351Y916181D02*
X51389Y916155D01*
X51417Y916083D01*
X51428Y915984D01*
G01X51351Y919331D02*
X51389Y919304D01*
X51417Y919232D01*
X51428Y919134D01*
G01X77756Y885610D02*
X76772D01*
G01X77756Y885807D02*
X76772D01*
G01X77756Y886201D02*
X76772D01*
G01X74724Y886398D02*
X81890D01*
G01X92717Y887047D02*
X85384D01*
G01X85237D02*
X73228D01*
G01X85237Y887835D02*
X73228D01*
G01X85384D02*
X92717D01*
G01X74724Y887972D02*
X81890D01*
G01X77756Y888169D02*
X76772D01*
G01X77756Y888563D02*
X76772D01*
G01X77756Y888760D02*
X76772D01*
G01X92717Y890197D02*
X85384D01*
G01X85237D02*
X73228D01*
G01X77756Y890610D02*
X76772D01*
G01X77756Y890807D02*
X76772D01*
G01X85237Y890984D02*
X73228D01*
G01X85384D02*
X92717D01*
G01X77756Y891201D02*
X76772D01*
G01X74724Y891398D02*
X81890D01*
G01X74724Y892972D02*
X81890D01*
G01X77756Y893169D02*
X76772D01*
G01X92717Y893346D02*
X85384D01*
G01X85237D02*
X73228D01*
G01X77756Y893563D02*
X76772D01*
G01X77756Y893760D02*
X76772D01*
G01X85237Y894134D02*
X73228D01*
G01X85384D02*
X92717D01*
G01X77756Y895610D02*
X76772D01*
G01X77756Y895807D02*
X76772D01*
G01X77756Y896201D02*
X76772D01*
G01X74724Y896398D02*
X81890D01*
G01X92717Y896496D02*
X85384D01*
G01X85237D02*
X73228D01*
G01X85237Y897283D02*
X73228D01*
G01X85384D02*
X92717D01*
G01X74724Y897972D02*
X81890D01*
G01X77756Y898169D02*
X76772D01*
G01X77756Y898563D02*
X76772D01*
G01X77756Y898760D02*
X76772D01*
G01X92717Y899646D02*
X85384D01*
G01X85237D02*
X73228D01*
G01X85237Y900433D02*
X73228D01*
G01X85384D02*
X92717D01*
G01X77756Y900610D02*
X76772D01*
G01X77756Y900807D02*
X76772D01*
G01X77756Y901201D02*
X76772D01*
G01X74724Y901398D02*
X81890D01*
G01X92717Y902795D02*
X85384D01*
G01X85237D02*
X73228D01*
G01X74724Y902972D02*
X81890D01*
G01X77756Y903169D02*
X76772D01*
G01X77756Y903563D02*
X76772D01*
G01X85237Y903583D02*
X73228D01*
G01X85384D02*
X92717D01*
G01X77756Y903760D02*
X76772D01*
G01X74331Y904980D02*
X73228D01*
G01X75787Y905610D02*
X74803D01*
G01X75787Y905807D02*
X74803D01*
G01X92717Y905945D02*
X85384D01*
G01X85237D02*
X73228D01*
G01X75787Y906201D02*
X74803D01*
G01X74331Y906398D02*
X79921D01*
G01X85237Y906732D02*
X73228D01*
G01X85384D02*
X92717D01*
G01X74331Y907972D02*
X79921D01*
G01X75787Y908169D02*
X74803D01*
G01X75787Y908563D02*
X74803D01*
G01X75787Y908760D02*
X74803D01*
G01X92717Y909094D02*
X85384D01*
G01X85237D02*
X73228D01*
G01Y909390D02*
X74331D01*
G01X85237Y909882D02*
X73228D01*
G01X85384D02*
X92717D01*
G01X77756Y910610D02*
X76772D01*
G01X77756Y910807D02*
X76772D01*
G01X77756Y911201D02*
X76772D01*
G01X74724Y911398D02*
X81890D01*
G01X92717Y912244D02*
X85384D01*
G01X85237D02*
X73228D01*
G01X74724Y912972D02*
X81890D01*
G01X85237Y913031D02*
X73228D01*
G01X85384D02*
X92717D01*
G01X77756Y913169D02*
X76772D01*
G01X77756Y913563D02*
X76772D01*
G01X77756Y913760D02*
X76772D01*
G01X92717Y915394D02*
X85384D01*
G01X85237D02*
X73228D01*
G01X77756Y915610D02*
X76772D01*
G01X77756Y915807D02*
X76772D01*
G01X85237Y916181D02*
X73228D01*
G01X85384D02*
X92717D01*
G01X77756Y916201D02*
X76772D01*
G01X74724Y916398D02*
X81890D01*
G01X74724Y917972D02*
X81890D01*
G01X77756Y918169D02*
X76772D01*
G01X92717Y918543D02*
X85384D01*
G01X85237D02*
X73228D01*
G01X77756Y918563D02*
X76772D01*
G01X77756Y918760D02*
X76772D01*
G01X85237Y919331D02*
X73228D01*
G01X85384D02*
X92717D01*
G01X77756Y920610D02*
X76772D01*
G01X51802Y887047D02*
X51829Y887051D01*
X51855Y887062D01*
X51879Y887080D01*
X51900Y887105D01*
X51917Y887135D01*
X51930Y887169D01*
X51938Y887205D01*
X51941Y887244D01*
G01X51802Y890197D02*
X51829Y890200D01*
X51855Y890211D01*
X51879Y890230D01*
X51900Y890254D01*
X51917Y890284D01*
X51930Y890318D01*
X51938Y890355D01*
X51941Y890394D01*
G01X51802Y893346D02*
X51829Y893350D01*
X51855Y893361D01*
X51879Y893379D01*
X51900Y893404D01*
X51917Y893434D01*
X51930Y893468D01*
X51938Y893504D01*
X51941Y893543D01*
G01X51802Y896496D02*
X51829Y896500D01*
X51855Y896511D01*
X51879Y896529D01*
X51900Y896554D01*
X51917Y896583D01*
X51930Y896617D01*
X51938Y896654D01*
X51941Y896693D01*
G01X51802Y899646D02*
X51829Y899649D01*
X51855Y899660D01*
X51879Y899678D01*
X51900Y899703D01*
X51917Y899733D01*
X51930Y899767D01*
X51938Y899804D01*
X51941Y899843D01*
G01X51802Y902795D02*
X51829Y902799D01*
X51855Y902810D01*
X51879Y902828D01*
X51900Y902853D01*
X51917Y902883D01*
X51930Y902917D01*
X51938Y902953D01*
X51941Y902992D01*
G01X51802Y905945D02*
X51829Y905948D01*
X51855Y905959D01*
X51879Y905978D01*
X51900Y906002D01*
X51917Y906032D01*
X51930Y906066D01*
X51938Y906103D01*
X51941Y906142D01*
G01X51802Y909094D02*
X51829Y909098D01*
X51855Y909109D01*
X51879Y909127D01*
X51900Y909152D01*
X51917Y909182D01*
X51930Y909216D01*
X51938Y909252D01*
X51941Y909291D01*
G01X51802Y912244D02*
X51829Y912248D01*
X51855Y912259D01*
X51879Y912277D01*
X51900Y912302D01*
X51917Y912331D01*
X51930Y912365D01*
X51938Y912402D01*
X51941Y912441D01*
G01X51802Y915394D02*
X51829Y915397D01*
X51855Y915408D01*
X51879Y915426D01*
X51900Y915451D01*
X51917Y915481D01*
X51930Y915515D01*
X51938Y915552D01*
X51941Y915591D01*
G01X51802Y918543D02*
X51829Y918547D01*
X51855Y918558D01*
X51879Y918576D01*
X51900Y918601D01*
X51917Y918631D01*
X51930Y918665D01*
X51938Y918701D01*
X51941Y918740D01*
G01X74331Y898366D02*
G03X74724Y897972I394J0D01*
G01Y896398D02*
G03X74331Y896004I1J-394D01*
G01Y888366D02*
G03X74724Y887972I394J0D01*
G01Y886398D02*
G03X74331Y886004I1J-394D01*
G01Y893366D02*
G03X74724Y892972I394J0D01*
G01Y891398D02*
G03X74331Y891004I1J-394D01*
G01Y903366D02*
G03X74724Y902972I394J0D01*
G01Y901398D02*
G03X74331Y901004I1J-394D01*
G01Y913366D02*
G03X74724Y912972I394J0D01*
G01Y911398D02*
G03X74331Y911004I1J-394D01*
G01Y918366D02*
G03X74724Y917972I394J0D01*
G01Y916398D02*
G03X74331Y916004I1J-394D01*
G01X51941Y865591D02*
X51938Y865629D01*
X51930Y865665D01*
X51917Y865699D01*
X51900Y865730D01*
X51879Y865754D01*
X51856Y865772D01*
X51830Y865783D01*
X51802Y865787D01*
G01X51941Y868740D02*
X51938Y868778D01*
X51930Y868815D01*
X51917Y868849D01*
X51900Y868879D01*
X51879Y868904D01*
X51856Y868922D01*
X51830Y868933D01*
X51802Y868937D01*
G01X51941Y871890D02*
X51938Y871928D01*
X51930Y871965D01*
X51917Y871998D01*
X51900Y872029D01*
X51879Y872053D01*
X51856Y872071D01*
X51830Y872083D01*
X51802Y872087D01*
G01X51941Y875039D02*
X51938Y875078D01*
X51930Y875114D01*
X51917Y875148D01*
X51900Y875178D01*
X51879Y875203D01*
X51856Y875221D01*
X51830Y875232D01*
X51802Y875236D01*
G01X51941Y878189D02*
X51938Y878227D01*
X51930Y878264D01*
X51917Y878298D01*
X51900Y878328D01*
X51879Y878352D01*
X51856Y878370D01*
X51830Y878382D01*
X51802Y878386D01*
G01X51941Y881339D02*
X51938Y881377D01*
X51930Y881413D01*
X51917Y881447D01*
X51900Y881478D01*
X51879Y881502D01*
X51856Y881520D01*
X51830Y881531D01*
X51802Y881535D01*
G01X51941Y884488D02*
X51938Y884526D01*
X51930Y884563D01*
X51917Y884597D01*
X51900Y884627D01*
X51879Y884652D01*
X51856Y884670D01*
X51830Y884681D01*
X51802Y884685D01*
G01X51428Y884488D02*
Y884094D01*
G01Y881339D02*
Y880945D01*
G01Y878189D02*
Y877795D01*
G01Y875039D02*
Y874646D01*
G01Y871890D02*
Y871496D01*
G01Y868740D02*
Y868346D01*
G01X51941D02*
Y868740D01*
G01Y874646D02*
Y875039D01*
G01Y871496D02*
Y871890D01*
G01Y877795D02*
Y878189D01*
G01Y884094D02*
Y884488D01*
G01Y880945D02*
Y881339D01*
G01X52112Y882382D02*
Y881988D01*
G01Y877382D02*
Y876988D01*
G01Y872382D02*
Y871988D01*
G01X52956Y882382D02*
Y881988D01*
G01Y877382D02*
Y876988D01*
G01Y872382D02*
Y871988D01*
G01X53118Y868346D02*
Y868740D01*
G01Y874646D02*
Y875039D01*
G01Y871496D02*
Y871890D01*
G01Y877795D02*
Y878189D01*
G01Y884094D02*
Y884488D01*
G01Y880945D02*
Y881339D01*
G01X51839Y872972D02*
X52112Y872382D01*
G01X51839Y877972D02*
X52112Y877382D01*
G01X51839Y882972D02*
X52112Y882382D01*
G01X69213Y884980D02*
Y868445D01*
G01X74803Y868760D02*
Y865610D01*
G01X75170Y881535D02*
Y880748D01*
G01Y884685D02*
Y883898D01*
G01Y878386D02*
Y877598D01*
G01Y872087D02*
Y871299D01*
G01Y875236D02*
Y874449D01*
G01Y868937D02*
Y868150D01*
G01X75197Y881535D02*
Y880748D01*
G01Y884685D02*
Y883898D01*
G01Y878386D02*
Y877598D01*
G01Y872087D02*
Y871299D01*
G01Y875236D02*
Y874449D01*
G01Y868937D02*
Y868150D01*
G01X75573Y881535D02*
Y880748D01*
G01Y884685D02*
Y883898D01*
G01Y878386D02*
Y877598D01*
G01Y872087D02*
Y871299D01*
G01Y875236D02*
Y874449D01*
G01Y868937D02*
Y868150D01*
G01X75787Y882972D02*
Y881398D01*
G01Y877972D02*
Y876398D01*
G01Y872972D02*
Y871398D01*
G01Y868760D02*
Y865610D01*
G01X76772Y883760D02*
Y880610D01*
G01Y878760D02*
Y875610D01*
G01Y873760D02*
Y870610D01*
G01Y867972D02*
Y866398D01*
G01X77756Y883760D02*
Y880610D01*
G01Y878760D02*
Y875610D01*
G01Y873760D02*
Y870610D01*
G01X78740Y882972D02*
Y881398D01*
G01Y877972D02*
Y876398D01*
G01Y872972D02*
Y871398D01*
G01X78935Y868150D02*
Y868937D01*
G01Y871299D02*
Y872087D01*
G01Y874449D02*
Y875236D01*
G01Y877598D02*
Y878386D01*
G01Y880748D02*
Y881535D01*
G01Y883898D02*
Y884685D01*
G01X79921Y866398D02*
Y867972D01*
G01X80919Y868150D02*
Y868937D01*
G01Y871299D02*
Y872087D01*
G01Y874449D02*
Y875236D01*
G01Y877598D02*
Y878386D01*
G01Y880748D02*
Y881535D01*
G01Y883898D02*
Y884685D01*
G01X81890Y871398D02*
Y872972D01*
G01Y876398D02*
Y877972D01*
G01Y881398D02*
Y882972D01*
G01X82570Y881535D02*
Y880748D01*
G01Y884685D02*
Y883898D01*
G01Y878386D02*
Y877598D01*
G01Y872087D02*
Y871299D01*
G01Y875236D02*
Y874449D01*
G01Y868937D02*
Y868150D01*
G01X84298Y865787D02*
Y868150D01*
G01Y868937D02*
Y871299D01*
G01Y872087D02*
Y874449D01*
G01Y875236D02*
Y877598D01*
G01Y878386D02*
Y880748D01*
G01Y881535D02*
Y883898D01*
G01Y884685D02*
Y887047D01*
G01X85237Y881535D02*
Y880748D01*
G01Y884685D02*
Y883898D01*
G01Y878386D02*
Y877598D01*
G01Y872087D02*
Y871299D01*
G01Y875236D02*
Y874449D01*
G01Y868937D02*
Y868150D01*
G01X85384Y881535D02*
Y880748D01*
G01Y884685D02*
Y883898D01*
G01Y878386D02*
Y877598D01*
G01Y872087D02*
Y871299D01*
G01Y875236D02*
Y874449D01*
G01Y868937D02*
Y868150D01*
G01X86976Y881535D02*
Y880748D01*
G01Y884685D02*
Y883898D01*
G01Y878386D02*
Y877598D01*
G01Y872087D02*
Y871299D01*
G01Y875236D02*
Y874449D01*
G01Y868937D02*
Y868150D01*
G01X87918D02*
Y868937D01*
G01Y871299D02*
Y872087D01*
G01Y874449D02*
Y875236D01*
G01Y877598D02*
Y878386D01*
G01Y880748D02*
Y881535D01*
G01Y883898D02*
Y884685D01*
G01X90754Y868150D02*
Y868937D01*
G01Y871299D02*
Y872087D01*
G01Y874449D02*
Y875236D01*
G01Y877598D02*
Y878386D01*
G01Y880748D02*
Y881535D01*
G01Y883898D02*
Y884685D01*
G01X90943Y881535D02*
Y880748D01*
G01Y884685D02*
Y883898D01*
G01Y878386D02*
Y877598D01*
G01Y872087D02*
Y871299D01*
G01Y875236D02*
Y874449D01*
G01Y868937D02*
Y868150D01*
G01X92717Y881535D02*
Y880748D01*
G01Y884685D02*
Y883898D01*
G01Y878386D02*
Y877598D01*
G01Y872087D02*
Y871299D01*
G01Y875236D02*
Y874449D01*
G01Y868937D02*
Y868150D01*
G01X51428Y884094D02*
X51417Y883996D01*
X51389Y883924D01*
X51351Y883898D01*
G01X51428Y880945D02*
X51417Y880846D01*
X51389Y880774D01*
X51351Y880748D01*
G01X51428Y877795D02*
X51417Y877697D01*
X51389Y877625D01*
X51351Y877598D01*
G01X51428Y874646D02*
X51417Y874547D01*
X51389Y874475D01*
X51351Y874449D01*
G01X51428Y871496D02*
X51417Y871398D01*
X51389Y871326D01*
X51351Y871299D01*
G01X51428Y868346D02*
X51417Y868248D01*
X51389Y868176D01*
X51351Y868150D01*
G01X52529Y872972D02*
X52956Y872382D01*
G01X52529Y877972D02*
X52956Y877382D01*
G01X52529Y882972D02*
X52956Y882382D01*
G01X52112Y881988D02*
X51839Y881398D01*
G01X52112Y876988D02*
X51839Y876398D01*
G01X52112Y871988D02*
X51839Y871398D01*
G01X52529Y881398D02*
X52956Y881988D01*
G01X52529Y876398D02*
X52956Y876988D01*
G01X52529Y871398D02*
X52956Y871988D01*
G01X51351Y865787D02*
X51389Y865761D01*
X51417Y865689D01*
X51428Y865591D01*
G01X51351Y868937D02*
X51389Y868911D01*
X51417Y868839D01*
X51428Y868740D01*
G01X51351Y872087D02*
X51389Y872060D01*
X51417Y871988D01*
X51428Y871890D01*
G01X51351Y875236D02*
X51389Y875210D01*
X51417Y875138D01*
X51428Y875039D01*
G01X51351Y878386D02*
X51389Y878359D01*
X51417Y878287D01*
X51428Y878189D01*
G01X51351Y881535D02*
X51389Y881509D01*
X51417Y881437D01*
X51428Y881339D01*
G01X51351Y884685D02*
X51389Y884659D01*
X51417Y884587D01*
X51428Y884488D01*
G01X75787Y865610D02*
X74803D01*
G01X85237Y865787D02*
X73228D01*
G01X85384D02*
X92717D01*
G01X75787Y865807D02*
X74803D01*
G01X75787Y866201D02*
X74803D01*
G01X74331Y866398D02*
X79921D01*
G01X74331Y867972D02*
X79921D01*
G01X92717Y868150D02*
X85384D01*
G01X85237D02*
X73228D01*
G01X75787Y868169D02*
X74803D01*
G01X75787Y868563D02*
X74803D01*
G01X75787Y868760D02*
X74803D01*
G01X85237Y868937D02*
X73228D01*
G01X85384D02*
X92717D01*
G01X73228Y869390D02*
X74331D01*
G01X77756Y870610D02*
X76772D01*
G01X77756Y870807D02*
X76772D01*
G01X77756Y871201D02*
X76772D01*
G01X92717Y871299D02*
X85384D01*
G01X85237D02*
X73228D01*
G01X74724Y871398D02*
X81890D01*
G01X85237Y872087D02*
X73228D01*
G01X85384D02*
X92717D01*
G01X74724Y872972D02*
X81890D01*
G01X77756Y873169D02*
X76772D01*
G01X77756Y873563D02*
X76772D01*
G01X77756Y873760D02*
X76772D01*
G01X92717Y874449D02*
X85384D01*
G01X85237D02*
X73228D01*
G01X85237Y875236D02*
X73228D01*
G01X85384D02*
X92717D01*
G01X77756Y875610D02*
X76772D01*
G01X77756Y875807D02*
X76772D01*
G01X77756Y876201D02*
X76772D01*
G01X74724Y876398D02*
X81890D01*
G01X92717Y877598D02*
X85384D01*
G01X85237D02*
X73228D01*
G01X74724Y877972D02*
X81890D01*
G01X77756Y878169D02*
X76772D01*
G01X85237Y878386D02*
X73228D01*
G01X85384D02*
X92717D01*
G01X77756Y878563D02*
X76772D01*
G01X77756Y878760D02*
X76772D01*
G01X77756Y880610D02*
X76772D01*
G01X92717Y880748D02*
X85384D01*
G01X85237D02*
X73228D01*
G01X77756Y880807D02*
X76772D01*
G01X77756Y881201D02*
X76772D01*
G01X74724Y881398D02*
X81890D01*
G01X85237Y881535D02*
X73228D01*
G01X85384D02*
X92717D01*
G01X74724Y882972D02*
X81890D01*
G01X77756Y883169D02*
X76772D01*
G01X77756Y883563D02*
X76772D01*
G01X77756Y883760D02*
X76772D01*
G01X92717Y883898D02*
X85384D01*
G01X85237D02*
X73228D01*
G01X85237Y884685D02*
X73228D01*
G01X85384D02*
X92717D01*
G01X51802Y868150D02*
X51829Y868153D01*
X51855Y868164D01*
X51879Y868182D01*
X51900Y868207D01*
X51917Y868237D01*
X51930Y868271D01*
X51938Y868307D01*
X51941Y868346D01*
G01X51802Y871299D02*
X51829Y871303D01*
X51855Y871314D01*
X51879Y871332D01*
X51900Y871357D01*
X51917Y871387D01*
X51930Y871420D01*
X51938Y871457D01*
X51941Y871496D01*
G01X51802Y874449D02*
X51829Y874452D01*
X51855Y874463D01*
X51879Y874481D01*
X51900Y874506D01*
X51917Y874536D01*
X51930Y874570D01*
X51938Y874607D01*
X51941Y874646D01*
G01X51802Y877598D02*
X51829Y877602D01*
X51855Y877613D01*
X51879Y877631D01*
X51900Y877656D01*
X51917Y877686D01*
X51930Y877720D01*
X51938Y877756D01*
X51941Y877795D01*
G01X51802Y880748D02*
X51829Y880752D01*
X51855Y880763D01*
X51879Y880781D01*
X51900Y880806D01*
X51917Y880835D01*
X51930Y880869D01*
X51938Y880906D01*
X51941Y880945D01*
G01X51802Y883898D02*
X51829Y883901D01*
X51855Y883912D01*
X51879Y883930D01*
X51900Y883955D01*
X51917Y883985D01*
X51930Y884019D01*
X51938Y884056D01*
X51941Y884094D01*
G01X74331Y883366D02*
G03X74724Y882972I394J0D01*
G01Y881398D02*
G03X74331Y881004I1J-394D01*
G01Y878366D02*
G03X74724Y877972I394J0D01*
G01Y876398D02*
G03X74331Y876004I1J-394D01*
G01Y873366D02*
G03X74724Y872972I394J0D01*
G01Y871398D02*
G03X74331Y871004I1J-394D01*
G01X43531Y918484D02*
Y923964D01*
G01X44401Y906988D02*
Y907382D01*
G01X46369Y886988D02*
Y887382D01*
G01Y891988D02*
Y892382D01*
G01Y896988D02*
Y897382D01*
G01Y901988D02*
Y902382D01*
G01Y911988D02*
Y912382D01*
G01Y916988D02*
Y917382D01*
G01X46506Y919134D02*
Y918740D01*
G01Y915984D02*
Y915591D01*
G01Y909685D02*
Y909291D01*
G01Y912835D02*
Y912441D01*
G01Y906535D02*
Y906142D01*
G01Y900236D02*
Y899843D01*
G01Y903386D02*
Y902992D01*
G01Y897087D02*
Y896693D01*
G01Y890787D02*
Y890394D01*
G01Y893937D02*
Y893543D01*
G01Y887638D02*
Y887244D01*
G01X49019Y906988D02*
Y907382D01*
G01X50143D02*
Y906988D01*
G01X50987Y907382D02*
Y906988D01*
G01Y886988D02*
Y887382D01*
G01Y891988D02*
Y892382D01*
G01Y896988D02*
Y897382D01*
G01Y901988D02*
Y902382D01*
G01Y911988D02*
Y912382D01*
G01Y916988D02*
Y917382D01*
G01X49871Y907972D02*
X50143Y907382D01*
G01X46506Y887244D02*
X46538Y887147D01*
X46626Y887075D01*
X46753Y887047D01*
G01X46506Y890394D02*
X46538Y890296D01*
X46626Y890224D01*
X46753Y890197D01*
G01X46506Y896693D02*
X46538Y896596D01*
X46626Y896524D01*
X46753Y896496D01*
G01X46506Y899843D02*
X46538Y899745D01*
X46626Y899673D01*
X46753Y899646D01*
G01X46506Y902992D02*
X46538Y902895D01*
X46626Y902823D01*
X46753Y902795D01*
G01X46506Y906142D02*
X46538Y906044D01*
X46626Y905972D01*
X46753Y905945D01*
G01X46506Y909291D02*
X46538Y909194D01*
X46626Y909122D01*
X46753Y909094D01*
G01X46506Y912441D02*
X46538Y912344D01*
X46626Y912272D01*
X46753Y912244D01*
G01X46506Y915591D02*
X46538Y915493D01*
X46626Y915421D01*
X46753Y915394D01*
G01X46506Y918740D02*
X46538Y918643D01*
X46626Y918571D01*
X46753Y918543D01*
G01X50987Y887382D02*
X50909Y887972D01*
G01X50987Y892382D02*
X50909Y892972D01*
G01X49019Y907382D02*
X48941Y907972D01*
G01X50987Y897382D02*
X50909Y897972D01*
G01X50987Y902382D02*
X50909Y902972D01*
G01X50987Y912382D02*
X50909Y912972D01*
G01X50987Y917382D02*
X50909Y917972D01*
G01X49019Y906988D02*
X48941Y906398D01*
G01X50987Y916988D02*
X50909Y916398D01*
G01X50987Y911988D02*
X50909Y911398D01*
G01X50987Y901988D02*
X50909Y901398D01*
G01X50987Y896988D02*
X50909Y896398D01*
G01X50987Y891988D02*
X50909Y891398D01*
G01X50987Y886988D02*
X50909Y886398D01*
G01X46506Y893937D02*
X46539Y894036D01*
X46628Y894107D01*
X46753Y894134D01*
G01X50143Y906988D02*
X49871Y906398D01*
G01X50560Y907972D02*
X50987Y907382D01*
G01X46369Y886988D02*
X46506Y886791D01*
X46644Y886594D01*
X46784Y886398D01*
G01X46369Y891988D02*
X46506Y891791D01*
X46644Y891594D01*
X46784Y891398D01*
G01X46369Y896988D02*
X46506Y896791D01*
X46644Y896594D01*
X46784Y896398D01*
G01X46369Y901988D02*
X46506Y901791D01*
X46644Y901594D01*
X46784Y901398D01*
G01X44401Y906988D02*
X44538Y906791D01*
X44676Y906594D01*
X44815Y906398D01*
G01X46369Y911988D02*
X46506Y911791D01*
X46644Y911594D01*
X46784Y911398D01*
G01X46369Y916988D02*
X46506Y916791D01*
X46644Y916594D01*
X46784Y916398D01*
G01Y917972D02*
X46644Y917776D01*
X46506Y917580D01*
X46369Y917382D01*
G01X46784Y912972D02*
X46644Y912776D01*
X46506Y912580D01*
X46369Y912382D01*
G01X44815Y907972D02*
X44676Y907776D01*
X44538Y907580D01*
X44401Y907382D01*
G01X46784Y902972D02*
X46644Y902776D01*
X46506Y902580D01*
X46369Y902382D01*
G01X46784Y897972D02*
X46644Y897776D01*
X46506Y897580D01*
X46369Y897382D01*
G01X46784Y892972D02*
X46644Y892776D01*
X46506Y892580D01*
X46369Y892382D01*
G01X46784Y887972D02*
X46644Y887776D01*
X46506Y887580D01*
X46369Y887382D01*
G01X50560Y906398D02*
X50987Y906988D01*
G01X46753Y893346D02*
X46627Y893374D01*
X46538Y893446D01*
X46506Y893543D01*
G01X46784Y886398D02*
X52529D01*
G01X46369Y886988D02*
X52956D01*
G01X46753Y887047D02*
X52838D01*
G01X53118Y887244D02*
X46506D01*
G01X44488Y887343D02*
X71181D01*
G01X52956Y887382D02*
X46369D01*
G01X46506Y887638D02*
X53118D01*
G01X46753Y887835D02*
X52838D01*
G01X52529Y887972D02*
X46784D01*
G01X46753Y890197D02*
X52838D01*
G01X53118Y890394D02*
X46506D01*
G01Y890787D02*
X53118D01*
G01X46753Y890984D02*
X52838D01*
G01X46784Y891398D02*
X52529D01*
G01X46369Y891988D02*
X52956D01*
G01Y892382D02*
X46369D01*
G01X52529Y892972D02*
X46784D01*
G01X46753Y893346D02*
X52838D01*
G01X53118Y893543D02*
X46506D01*
G01Y893937D02*
X53118D01*
G01X46753Y894134D02*
X52838D01*
G01X46784Y896398D02*
X52529D01*
G01X46753Y896496D02*
X52838D01*
G01X53118Y896693D02*
X46506D01*
G01X46369Y896988D02*
X52956D01*
G01X46506Y897087D02*
X53118D01*
G01X46753Y897283D02*
X52838D01*
G01X52956Y897382D02*
X46369D01*
G01X52529Y897972D02*
X46784D01*
G01X46753Y899646D02*
X52838D01*
G01X53118Y899843D02*
X46506D01*
G01Y900236D02*
X53118D01*
G01X46753Y900433D02*
X52838D01*
G01X46784Y901398D02*
X52529D01*
G01X46369Y901988D02*
X52956D01*
G01Y902382D02*
X46369D01*
G01X46753Y902795D02*
X52838D01*
G01X52529Y902972D02*
X46784D01*
G01X53118Y902992D02*
X46506D01*
G01Y903386D02*
X53118D01*
G01X46753Y903583D02*
X52838D01*
G01X71181Y903878D02*
X44488D01*
G01X46753Y905945D02*
X52838D01*
G01X53118Y906142D02*
X46506D01*
G01X44488Y906240D02*
X71181D01*
G01X44815Y906398D02*
X50560D01*
G01X46506Y906535D02*
X53118D01*
G01X46753Y906732D02*
X52838D01*
G01X44401Y906988D02*
X50987D01*
G01Y907382D02*
X44401D01*
G01X50560Y907972D02*
X44815D01*
G01X46753Y909094D02*
X52838D01*
G01X53118Y909291D02*
X46506D01*
G01Y909685D02*
X53118D01*
G01X46753Y909882D02*
X52838D01*
G01X46784Y911398D02*
X52529D01*
G01X46369Y911988D02*
X52956D01*
G01X46753Y912244D02*
X52838D01*
G01X52956Y912382D02*
X46369D01*
G01X53118Y912441D02*
X46506D01*
G01Y912835D02*
X53118D01*
G01X52529Y912972D02*
X46784D01*
G01X46753Y913031D02*
X52838D01*
G01X46753Y915394D02*
X52838D01*
G01X53118Y915591D02*
X46506D01*
G01Y915984D02*
X53118D01*
G01X46753Y916181D02*
X52838D01*
G01X46784Y916398D02*
X52529D01*
G01X46369Y916988D02*
X52956D01*
G01Y917382D02*
X46369D01*
G01X52529Y917972D02*
X46784D01*
G01X43531Y918484D02*
X62992D01*
G01X46753Y918543D02*
X52838D01*
G01X53118Y918740D02*
X46506D01*
G01Y919134D02*
X53118D01*
G01X46753Y919331D02*
X52838D01*
G01X46753Y887835D02*
X46626Y887807D01*
X46537Y887734D01*
X46506Y887638D01*
G01X46753Y890984D02*
X46626Y890956D01*
X46537Y890883D01*
X46506Y890787D01*
G01X46753Y897283D02*
X46626Y897256D01*
X46537Y897183D01*
X46506Y897087D01*
G01X46753Y900433D02*
X46626Y900405D01*
X46537Y900332D01*
X46506Y900236D01*
G01X46753Y903583D02*
X46626Y903555D01*
X46537Y903482D01*
X46506Y903386D01*
G01X46753Y906732D02*
X46626Y906704D01*
X46537Y906631D01*
X46506Y906535D01*
G01X46753Y909882D02*
X46626Y909854D01*
X46537Y909781D01*
X46506Y909685D01*
G01X46753Y913031D02*
X46626Y913004D01*
X46537Y912931D01*
X46506Y912835D01*
G01X46753Y916181D02*
X46626Y916153D01*
X46537Y916080D01*
X46506Y915984D01*
G01X46753Y919331D02*
X46626Y919303D01*
X46537Y919230D01*
X46506Y919134D01*
G01X44401Y866988D02*
Y867382D01*
G01X46369Y871988D02*
Y872382D01*
G01Y876988D02*
Y877382D01*
G01Y881988D02*
Y882382D01*
G01X46506Y884488D02*
Y884094D01*
G01Y881339D02*
Y880945D01*
G01Y878189D02*
Y877795D01*
G01Y875039D02*
Y874646D01*
G01Y871890D02*
Y871496D01*
G01Y868740D02*
Y868346D01*
G01X49019Y866988D02*
Y867382D01*
G01X50143D02*
Y866988D01*
G01X50987Y867382D02*
Y866988D01*
G01Y871988D02*
Y872382D01*
G01Y876988D02*
Y877382D01*
G01Y881988D02*
Y882382D01*
G01X44401Y866988D02*
X44538Y866791D01*
X44676Y866594D01*
X44815Y866398D01*
G01X46369Y871988D02*
X46506Y871791D01*
X46644Y871594D01*
X46784Y871398D01*
G01X46369Y876988D02*
X46506Y876791D01*
X46644Y876594D01*
X46784Y876398D01*
G01X49871Y867972D02*
X50143Y867382D01*
G01X46506Y868346D02*
X46538Y868249D01*
X46626Y868177D01*
X46753Y868150D01*
G01X46506Y871496D02*
X46538Y871399D01*
X46626Y871327D01*
X46753Y871299D01*
G01X46506Y874646D02*
X46538Y874548D01*
X46626Y874476D01*
X46753Y874449D01*
G01X46506Y877795D02*
X46538Y877698D01*
X46626Y877626D01*
X46753Y877598D01*
G01X46506Y880945D02*
X46538Y880848D01*
X46626Y880776D01*
X46753Y880748D01*
G01X46506Y884094D02*
X46538Y883997D01*
X46626Y883925D01*
X46753Y883898D01*
G01X49019Y867382D02*
X48941Y867972D01*
G01X50987Y872382D02*
X50909Y872972D01*
G01X50987Y877382D02*
X50909Y877972D01*
G01X50987Y882382D02*
X50909Y882972D01*
G01X50987Y881988D02*
X50909Y881398D01*
G01X49019Y866988D02*
X48941Y866398D01*
G01X50987Y876988D02*
X50909Y876398D01*
G01X50987Y871988D02*
X50909Y871398D01*
G01X46506Y865591D02*
X46539Y865689D01*
X46628Y865760D01*
X46753Y865787D01*
G01X50560Y867972D02*
X50987Y867382D01*
G01X46369Y881988D02*
X46506Y881791D01*
X46644Y881594D01*
X46784Y881398D01*
G01X50143Y866988D02*
X49871Y866398D01*
G01X46784Y882972D02*
X46644Y882776D01*
X46506Y882580D01*
X46369Y882382D01*
G01X46784Y877972D02*
X46644Y877776D01*
X46506Y877580D01*
X46369Y877382D01*
G01X46784Y872972D02*
X46644Y872776D01*
X46506Y872580D01*
X46369Y872382D01*
G01X44815Y867972D02*
X44676Y867776D01*
X44538Y867580D01*
X44401Y867382D01*
G01X50560Y866398D02*
X50987Y866988D01*
G01X46506Y865591D02*
X53118D01*
G01X46753Y865787D02*
X52838D01*
G01X71181Y866083D02*
X44488D01*
G01X44815Y866398D02*
X50560D01*
G01X44401Y866988D02*
X50987D01*
G01Y867382D02*
X44401D01*
G01X50560Y867972D02*
X44815D01*
G01X46753Y868150D02*
X52838D01*
G01X53118Y868346D02*
X46506D01*
G01X44488Y868445D02*
X71181D01*
G01X46506Y868740D02*
X53118D01*
G01X46753Y868937D02*
X52838D01*
G01X46753Y871299D02*
X52838D01*
G01X46784Y871398D02*
X52529D01*
G01X53118Y871496D02*
X46506D01*
G01Y871890D02*
X53118D01*
G01X46369Y871988D02*
X52956D01*
G01X46753Y872087D02*
X52838D01*
G01X52956Y872382D02*
X46369D01*
G01X52529Y872972D02*
X46784D01*
G01X46753Y874449D02*
X52838D01*
G01X53118Y874646D02*
X46506D01*
G01Y875039D02*
X53118D01*
G01X46753Y875236D02*
X52838D01*
G01X46784Y876398D02*
X52529D01*
G01X46369Y876988D02*
X52956D01*
G01Y877382D02*
X46369D01*
G01X46753Y877598D02*
X52838D01*
G01X53118Y877795D02*
X46506D01*
G01X52529Y877972D02*
X46784D01*
G01X46506Y878189D02*
X53118D01*
G01X46753Y878386D02*
X52838D01*
G01X46753Y880748D02*
X52838D01*
G01X53118Y880945D02*
X46506D01*
G01Y881339D02*
X53118D01*
G01X46784Y881398D02*
X52529D01*
G01X46753Y881535D02*
X52838D01*
G01X46369Y881988D02*
X52956D01*
G01Y882382D02*
X46369D01*
G01X52529Y882972D02*
X46784D01*
G01X46753Y883898D02*
X52838D01*
G01X53118Y884094D02*
X46506D01*
G01Y884488D02*
X53118D01*
G01X46753Y884685D02*
X52838D01*
G01X71181Y884980D02*
X44488D01*
G01X46753Y868937D02*
X46626Y868909D01*
X46537Y868836D01*
X46506Y868740D01*
G01X46753Y872087D02*
X46626Y872059D01*
X46537Y871986D01*
X46506Y871890D01*
G01X46753Y875236D02*
X46626Y875208D01*
X46537Y875135D01*
X46506Y875039D01*
G01X46753Y878386D02*
X46626Y878358D01*
X46537Y878285D01*
X46506Y878189D01*
G01X46753Y881535D02*
X46626Y881507D01*
X46537Y881435D01*
X46506Y881339D01*
G01X46753Y884685D02*
X46626Y884657D01*
X46537Y884584D01*
X46506Y884488D01*
G01X51941Y947480D02*
X51938Y947519D01*
X51930Y947555D01*
X51917Y947589D01*
X51900Y947619D01*
X51879Y947644D01*
X51856Y947662D01*
X51830Y947673D01*
X51802Y947677D01*
G01X51941Y950630D02*
X51938Y950668D01*
X51930Y950705D01*
X51917Y950739D01*
X51900Y950769D01*
X51879Y950793D01*
X51856Y950811D01*
X51830Y950823D01*
X51802Y950827D01*
G01X51941Y953780D02*
X51938Y953818D01*
X51930Y953854D01*
X51917Y953888D01*
X51900Y953919D01*
X51879Y953943D01*
X51856Y953961D01*
X51830Y953972D01*
X51802Y953976D01*
G01X51941Y956929D02*
X51938Y956967D01*
X51930Y957004D01*
X51917Y957038D01*
X51900Y957068D01*
X51879Y957093D01*
X51856Y957111D01*
X51830Y957122D01*
X51802Y957126D01*
G01X51941Y960079D02*
X51938Y960117D01*
X51930Y960154D01*
X51917Y960187D01*
X51900Y960218D01*
X51879Y960242D01*
X51856Y960260D01*
X51830Y960272D01*
X51802Y960276D01*
G01X51941Y963228D02*
X51938Y963267D01*
X51930Y963303D01*
X51917Y963337D01*
X51900Y963367D01*
X51879Y963392D01*
X51856Y963410D01*
X51830Y963421D01*
X51802Y963425D01*
G01X51941Y966378D02*
X51938Y966416D01*
X51930Y966453D01*
X51917Y966487D01*
X51900Y966517D01*
X51879Y966541D01*
X51856Y966559D01*
X51830Y966571D01*
X51802Y966575D01*
G01X51941Y969528D02*
X51938Y969566D01*
X51930Y969602D01*
X51917Y969636D01*
X51900Y969667D01*
X51879Y969691D01*
X51856Y969709D01*
X51830Y969720D01*
X51802Y969724D01*
G01X51941Y972677D02*
X51938Y972715D01*
X51930Y972752D01*
X51917Y972786D01*
X51900Y972816D01*
X51879Y972841D01*
X51856Y972859D01*
X51830Y972870D01*
X51802Y972874D01*
G01X51941Y975827D02*
X51938Y975865D01*
X51930Y975902D01*
X51917Y975935D01*
X51900Y975966D01*
X51879Y975990D01*
X51856Y976008D01*
X51830Y976020D01*
X51802Y976024D01*
G01X51428Y975827D02*
Y975433D01*
G01Y972677D02*
Y972283D01*
G01Y969528D02*
Y969134D01*
G01Y966378D02*
Y965984D01*
G01Y963228D02*
Y962835D01*
G01Y960079D02*
Y959685D01*
G01Y956929D02*
Y956535D01*
G01Y953780D02*
Y953386D01*
G01Y950630D02*
Y950236D01*
G01Y947480D02*
Y947087D01*
G01X51941Y950236D02*
Y950630D01*
G01Y947087D02*
Y947480D01*
G01Y953386D02*
Y953780D01*
G01Y959685D02*
Y960079D01*
G01Y956535D02*
Y956929D01*
G01Y962835D02*
Y963228D01*
G01Y969134D02*
Y969528D01*
G01Y965984D02*
Y966378D01*
G01Y972283D02*
Y972677D01*
G01Y975433D02*
Y975827D01*
G01X52112Y977382D02*
Y976988D01*
G01Y972382D02*
Y971988D01*
G01Y967382D02*
Y966988D01*
G01Y962382D02*
Y961988D01*
G01Y957382D02*
Y956988D01*
G01Y952382D02*
Y951988D01*
G01Y947382D02*
Y946988D01*
G01X52956Y977382D02*
Y976988D01*
G01Y972382D02*
Y971988D01*
G01Y967382D02*
Y966988D01*
G01Y962382D02*
Y961988D01*
G01Y957382D02*
Y956988D01*
G01Y952382D02*
Y951988D01*
G01X53021Y947382D02*
Y946988D01*
G01X53118Y950236D02*
Y950630D01*
G01Y947087D02*
Y947480D01*
G01Y953386D02*
Y953780D01*
G01Y959685D02*
Y960079D01*
G01Y956535D02*
Y956929D01*
G01Y962835D02*
Y963228D01*
G01Y969134D02*
Y969528D01*
G01Y965984D02*
Y966378D01*
G01Y972283D02*
Y972677D01*
G01Y975433D02*
Y975827D01*
G01X51428Y972283D02*
X51417Y972185D01*
X51389Y972113D01*
X51351Y972087D01*
G01X51428Y969134D02*
X51417Y969035D01*
X51389Y968963D01*
X51351Y968937D01*
G01X51428Y956535D02*
X51417Y956437D01*
X51389Y956365D01*
X51351Y956339D01*
G01X51428Y953386D02*
X51417Y953287D01*
X51389Y953215D01*
X51351Y953189D01*
G01X64646Y980807D02*
Y1007205D01*
G01X64961Y981988D02*
Y980217D01*
G01X68169Y978491D02*
Y977808D01*
G01Y974823D02*
Y975335D01*
G01X68692Y977808D02*
Y978491D01*
G01X69213Y946791D02*
Y962028D01*
G01Y964390D02*
Y980807D01*
G01X69302Y979173D02*
Y979685D01*
G01X69998Y978320D02*
Y977808D01*
G01X70521D02*
Y978320D01*
G01X70866Y984114D02*
Y986555D01*
G01X71306Y977296D02*
Y976785D01*
G01X71741Y978320D02*
Y977808D01*
G01X72264Y975335D02*
Y974823D01*
G01Y977894D02*
Y978320D01*
G01X74783Y978150D02*
Y976181D01*
G01X75170Y976024D02*
Y975236D01*
G01Y972874D02*
Y972087D01*
G01Y966575D02*
Y965787D01*
G01Y969724D02*
Y968937D01*
G01Y963425D02*
Y962638D01*
G01Y957126D02*
Y956339D01*
G01Y960276D02*
Y959488D01*
G01Y953976D02*
Y953189D01*
G01Y947677D02*
Y946890D01*
G01Y950827D02*
Y950039D01*
G01X75197Y976024D02*
Y975236D01*
G01Y972874D02*
Y972087D01*
G01Y966575D02*
Y965787D01*
G01Y969724D02*
Y968937D01*
G01Y963425D02*
Y962638D01*
G01Y957126D02*
Y956339D01*
G01Y960276D02*
Y959488D01*
G01Y953976D02*
Y953189D01*
G01Y947677D02*
Y946890D01*
G01Y950827D02*
Y950039D01*
G01X75573Y976024D02*
Y975236D01*
G01Y972874D02*
Y972087D01*
G01Y966575D02*
Y965787D01*
G01Y969724D02*
Y968937D01*
G01Y963425D02*
Y962638D01*
G01Y957126D02*
Y956339D01*
G01Y960276D02*
Y959488D01*
G01Y953976D02*
Y953189D01*
G01Y947677D02*
Y946890D01*
G01Y950827D02*
Y950039D01*
G01X75787Y977972D02*
Y976398D01*
G01Y972972D02*
Y971398D01*
G01Y967972D02*
Y966398D01*
G01Y962972D02*
Y961398D01*
G01Y957972D02*
Y956398D01*
G01Y952972D02*
Y951398D01*
G01Y947972D02*
Y946398D01*
G01X76772Y978760D02*
Y975610D01*
G01Y973760D02*
Y970610D01*
G01Y968760D02*
Y965610D01*
G01Y963760D02*
Y960610D01*
G01Y958760D02*
Y955610D01*
G01Y953760D02*
Y950610D01*
G01Y948760D02*
Y945610D01*
G01Y983622D02*
Y985925D01*
G01X77756Y978760D02*
Y975610D01*
G01Y973760D02*
Y970610D01*
G01Y968760D02*
Y965610D01*
G01Y963760D02*
Y960610D01*
G01Y958760D02*
Y955610D01*
G01Y953760D02*
Y950610D01*
G01Y948760D02*
Y945610D01*
G01X78740Y977972D02*
Y976398D01*
G01Y972972D02*
Y971398D01*
G01Y967972D02*
Y966398D01*
G01Y962972D02*
Y961398D01*
G01Y957972D02*
Y956398D01*
G01Y952972D02*
Y951398D01*
G01Y947972D02*
Y946398D01*
G01X78935Y946890D02*
Y947677D01*
G01Y950039D02*
Y950827D01*
G01Y953189D02*
Y953976D01*
G01Y956339D02*
Y957126D01*
G01Y959488D02*
Y960276D01*
G01Y962638D02*
Y963425D01*
G01Y965787D02*
Y966575D01*
G01Y968937D02*
Y969724D01*
G01Y972087D02*
Y972874D01*
G01Y975236D02*
Y976024D01*
G01X79328Y983563D02*
Y983622D01*
G01X79967Y985925D02*
Y983169D01*
G01X80919Y946890D02*
Y947677D01*
G01Y950039D02*
Y950827D01*
G01Y953189D02*
Y953976D01*
G01Y956339D02*
Y957126D01*
G01Y959488D02*
Y960276D01*
G01Y962638D02*
Y963425D01*
G01Y965787D02*
Y966575D01*
G01Y968937D02*
Y969724D01*
G01Y972087D02*
Y972874D01*
G01Y975236D02*
Y976024D01*
G01X81890Y946398D02*
Y947972D01*
G01Y951398D02*
Y952972D01*
G01Y956398D02*
Y957972D01*
G01Y961398D02*
Y962972D01*
G01Y966398D02*
Y967972D01*
G01Y971398D02*
Y972972D01*
G01Y976398D02*
Y977972D01*
G01X82570Y976024D02*
Y975236D01*
G01Y972874D02*
Y972087D01*
G01Y966575D02*
Y965787D01*
G01Y969724D02*
Y968937D01*
G01Y963425D02*
Y962638D01*
G01Y957126D02*
Y956339D01*
G01Y960276D02*
Y959488D01*
G01Y953976D02*
Y953189D01*
G01Y947677D02*
Y946890D01*
G01Y950827D02*
Y950039D01*
G01X82854Y976181D02*
Y978150D01*
G01X84298Y947677D02*
Y950039D01*
G01Y950827D02*
Y953189D01*
G01Y953976D02*
Y956339D01*
G01Y957126D02*
Y959488D01*
G01Y960276D02*
Y962638D01*
G01Y963425D02*
Y965787D01*
G01Y966575D02*
Y968937D01*
G01Y969724D02*
Y972087D01*
G01Y976024D02*
Y978602D01*
G01Y972874D02*
Y975236D01*
G01X85237Y976024D02*
Y975236D01*
G01Y972874D02*
Y972087D01*
G01Y966575D02*
Y965787D01*
G01Y969724D02*
Y968937D01*
G01Y963425D02*
Y962638D01*
G01Y957126D02*
Y956339D01*
G01Y960276D02*
Y959488D01*
G01Y953976D02*
Y953189D01*
G01Y947677D02*
Y946890D01*
G01Y950827D02*
Y950039D01*
G01X85384Y976024D02*
Y975236D01*
G01Y972874D02*
Y972087D01*
G01Y966575D02*
Y965787D01*
G01Y969724D02*
Y968937D01*
G01Y963425D02*
Y962638D01*
G01Y957126D02*
Y956339D01*
G01Y960276D02*
Y959488D01*
G01Y953976D02*
Y953189D01*
G01Y947677D02*
Y946890D01*
G01Y950827D02*
Y950039D01*
G01X86976Y976024D02*
Y975236D01*
G01Y972874D02*
Y972087D01*
G01Y966575D02*
Y965787D01*
G01Y969724D02*
Y968937D01*
G01Y963425D02*
Y962638D01*
G01Y957126D02*
Y956339D01*
G01Y960276D02*
Y959488D01*
G01Y953976D02*
Y953189D01*
G01Y947677D02*
Y946890D01*
G01Y950827D02*
Y950039D01*
G01X87841Y985925D02*
Y983169D01*
G01X87918Y946890D02*
Y947677D01*
G01Y950039D02*
Y950827D01*
G01Y953189D02*
Y953976D01*
G01Y956339D02*
Y957126D01*
G01Y959488D02*
Y960276D01*
G01Y962638D02*
Y963425D01*
G01Y965787D02*
Y966575D01*
G01Y968937D02*
Y969724D01*
G01Y972087D02*
Y972874D01*
G01Y975236D02*
Y976024D01*
G01X90754Y946890D02*
Y947677D01*
G01Y950039D02*
Y950827D01*
G01Y953189D02*
Y953976D01*
G01Y956339D02*
Y957126D01*
G01Y959488D02*
Y960276D01*
G01Y962638D02*
Y963425D01*
G01Y965787D02*
Y966575D01*
G01Y968937D02*
Y969724D01*
G01Y972087D02*
Y972874D01*
G01Y975236D02*
Y976024D01*
G01X90943D02*
Y975236D01*
G01Y972874D02*
Y972087D01*
G01Y966575D02*
Y965787D01*
G01Y969724D02*
Y968937D01*
G01Y963425D02*
Y962638D01*
G01Y957126D02*
Y956339D01*
G01Y960276D02*
Y959488D01*
G01Y953976D02*
Y953189D01*
G01Y947677D02*
Y946890D01*
G01Y950827D02*
Y950039D01*
G01X92717Y976024D02*
Y975236D01*
G01Y972874D02*
Y972087D01*
G01Y966575D02*
Y965787D01*
G01Y969724D02*
Y968937D01*
G01Y963425D02*
Y962638D01*
G01Y957126D02*
Y956339D01*
G01Y960276D02*
Y959488D01*
G01Y953976D02*
Y953189D01*
G01Y947677D02*
Y946890D01*
G01Y950827D02*
Y950039D01*
G01X93696Y980591D02*
Y983169D01*
G01X94170Y980591D02*
Y985925D01*
G01X94488Y980591D02*
Y994272D01*
G01X68256Y978917D02*
X68169Y978491D01*
G01X70434Y977382D02*
X70521Y977808D01*
G01X72176Y977467D02*
X72264Y977894D01*
G01X68692Y978491D02*
X68779Y978832D01*
G01X70086Y978661D02*
X69998Y978320D01*
G01Y977808D02*
X69911Y977467D01*
G01X70521Y978320D02*
X70608Y978576D01*
G01X71741Y977808D02*
X71654Y977552D01*
G01X52112Y976988D02*
X51839Y976398D01*
G01X52112Y971988D02*
X51839Y971398D01*
G01X52112Y966988D02*
X51839Y966398D01*
G01X52112Y961988D02*
X51839Y961398D01*
G01X52112Y956988D02*
X51839Y956398D01*
G01X52112Y951988D02*
X51839Y951398D01*
G01X52112Y946988D02*
X51839Y946398D01*
G01X70260Y979002D02*
X70086Y978661D01*
G01X70260Y977041D02*
X70434Y977382D01*
G01X52529Y952972D02*
X52956Y952382D01*
G01X52529Y957972D02*
X52956Y957382D01*
G01X52529Y962972D02*
X52956Y962382D01*
G01X52529Y967972D02*
X52956Y967382D01*
G01X52529Y972972D02*
X52956Y972382D01*
G01X52529Y977972D02*
X52956Y977382D01*
G01X52597Y947972D02*
X53021Y947382D01*
G01X68953Y977211D02*
X68779Y977467D01*
G01X68256Y977382D02*
X68430Y977041D01*
G01X72176Y978661D02*
X72002Y979002D01*
G01X51839Y947972D02*
X52112Y947382D01*
G01X51839Y952972D02*
X52112Y952382D01*
G01X51839Y957972D02*
X52112Y957382D01*
G01X51839Y962972D02*
X52112Y962382D01*
G01X51839Y967972D02*
X52112Y967382D01*
G01X51839Y972972D02*
X52112Y972382D01*
G01X51839Y977972D02*
X52112Y977382D01*
G01X71654Y978576D02*
X71741Y978320D01*
G01X68779Y977467D02*
X68692Y977808D01*
G01X72264Y978320D02*
X72176Y978661D01*
G01X68169Y977808D02*
X68256Y977382D01*
G01X68518Y979344D02*
X68256Y978917D01*
G01X70608Y978576D02*
X70783Y978832D01*
G01X69911Y977467D02*
X69737Y977211D01*
G01X52597Y946398D02*
X53021Y946988D01*
G01X52529Y976398D02*
X52956Y976988D01*
G01X52529Y971398D02*
X52956Y971988D01*
G01X52529Y966398D02*
X52956Y966988D01*
G01X52529Y961398D02*
X52956Y961988D01*
G01X52529Y956398D02*
X52956Y956988D01*
G01X52529Y951398D02*
X52956Y951988D01*
G01X71915Y977126D02*
X72176Y977467D01*
G01X68779Y978832D02*
X69040Y979088D01*
G01X51351Y947677D02*
X51389Y947651D01*
X51417Y947579D01*
X51428Y947480D01*
G01X51351Y950827D02*
X51389Y950800D01*
X51417Y950728D01*
X51428Y950630D01*
G01X71567Y975335D02*
X70957Y975846D01*
G01X71654D02*
X72264Y975335D01*
G01X68430Y977041D02*
X68779Y976699D01*
G01X72002Y979002D02*
X71654Y979344D01*
G01X71480Y978832D02*
X71654Y978576D01*
G01X79583Y983169D02*
X79328Y983563D01*
G01X70608Y979344D02*
X70260Y979002D01*
G01X69911Y976699D02*
X70260Y977041D01*
G01X71654Y977552D02*
X71480Y977382D01*
G01X71567Y976870D02*
X71915Y977126D01*
G01X51351Y975236D02*
X51389Y975263D01*
X51417Y975335D01*
X51428Y975433D01*
G01X51351Y965787D02*
X51389Y965814D01*
X51417Y965886D01*
X51428Y965984D01*
G01X51351Y962638D02*
X51389Y962664D01*
X51417Y962736D01*
X51428Y962835D01*
G01X51351Y959488D02*
X51389Y959515D01*
X51417Y959587D01*
X51428Y959685D01*
G01X51351Y950039D02*
X51389Y950066D01*
X51417Y950138D01*
X51428Y950236D01*
G01X51351Y946890D02*
X51389Y946916D01*
X51417Y946988D01*
X51428Y947087D01*
G01X69737Y977211D02*
X69476Y977041D01*
G01X69215D02*
X68953Y977211D01*
G01X51351Y953976D02*
X51389Y953950D01*
X51417Y953878D01*
X51428Y953780D01*
G01X51351Y957126D02*
X51389Y957100D01*
X51417Y957028D01*
X51428Y956929D01*
G01X51351Y960276D02*
X51389Y960249D01*
X51417Y960177D01*
X51428Y960079D01*
G01X51351Y963425D02*
X51389Y963399D01*
X51417Y963327D01*
X51428Y963228D01*
G01X51351Y966575D02*
X51389Y966548D01*
X51417Y966476D01*
X51428Y966378D01*
G01X51351Y969724D02*
X51389Y969698D01*
X51417Y969626D01*
X51428Y969528D01*
G01X51351Y972874D02*
X51389Y972848D01*
X51417Y972776D01*
X51428Y972677D01*
G01X51351Y976024D02*
X51389Y975997D01*
X51417Y975925D01*
X51428Y975827D01*
G01X68953Y979600D02*
X68518Y979344D01*
G01X69563Y976529D02*
X69911Y976699D01*
G01X71480Y977382D02*
X71306Y977296D01*
G01X71218Y978917D02*
X71480Y978832D01*
G01X68779Y976699D02*
X69128Y976529D01*
G01X69040Y979088D02*
X69302Y979173D01*
G01X70783Y978832D02*
X71044Y978917D01*
G01X71306Y976785D02*
X71567Y976870D01*
G01X71654Y979344D02*
X71306Y979429D01*
G01X77756Y945610D02*
X76772D01*
G01X77756Y945807D02*
X76772D01*
G01X77756Y946201D02*
X76772D01*
G01X74724Y946398D02*
X81890D01*
G01X92717Y946890D02*
X85384D01*
G01X85237D02*
X73228D01*
G01X85237Y947677D02*
X73228D01*
G01X85384D02*
X92717D01*
G01X74724Y947972D02*
X81890D01*
G01X77756Y948169D02*
X76772D01*
G01X77756Y948563D02*
X76772D01*
G01X77756Y948760D02*
X76772D01*
G01X92717Y950039D02*
X85384D01*
G01X85237D02*
X73228D01*
G01X77756Y950610D02*
X76772D01*
G01X77756Y950807D02*
X76772D01*
G01X85237Y950827D02*
X73228D01*
G01X85384D02*
X92717D01*
G01X77756Y951201D02*
X76772D01*
G01X74724Y951398D02*
X81890D01*
G01X74724Y952972D02*
X81890D01*
G01X77756Y953169D02*
X76772D01*
G01X92717Y953189D02*
X85384D01*
G01X85237D02*
X73228D01*
G01X77756Y953563D02*
X76772D01*
G01X77756Y953760D02*
X76772D01*
G01X85237Y953976D02*
X73228D01*
G01X85384D02*
X92717D01*
G01X77756Y955610D02*
X76772D01*
G01X77756Y955807D02*
X76772D01*
G01X77756Y956201D02*
X76772D01*
G01X92717Y956339D02*
X85384D01*
G01X85237D02*
X73228D01*
G01X74724Y956398D02*
X81890D01*
G01X85237Y957126D02*
X73228D01*
G01X85384D02*
X92717D01*
G01X74724Y957972D02*
X81890D01*
G01X77756Y958169D02*
X76772D01*
G01X77756Y958563D02*
X76772D01*
G01X77756Y958760D02*
X76772D01*
G01X92717Y959488D02*
X85384D01*
G01X85237D02*
X73228D01*
G01X85237Y960276D02*
X73228D01*
G01X85384D02*
X92717D01*
G01X77756Y960610D02*
X76772D01*
G01X77756Y960807D02*
X76772D01*
G01X77756Y961201D02*
X76772D01*
G01X74724Y961398D02*
X81890D01*
G01X92717Y962638D02*
X85384D01*
G01X85237D02*
X73228D01*
G01X74724Y962972D02*
X81890D01*
G01X77756Y963169D02*
X76772D01*
G01X85237Y963425D02*
X73228D01*
G01X85384D02*
X92717D01*
G01X77756Y963563D02*
X76772D01*
G01X77756Y963760D02*
X76772D01*
G01X77756Y965610D02*
X76772D01*
G01X92717Y965787D02*
X85384D01*
G01X85237D02*
X73228D01*
G01X77756Y965807D02*
X76772D01*
G01X77756Y966201D02*
X76772D01*
G01X74724Y966398D02*
X81890D01*
G01X85237Y966575D02*
X73228D01*
G01X85384D02*
X92717D01*
G01X74724Y967972D02*
X81890D01*
G01X77756Y968169D02*
X76772D01*
G01X77756Y968563D02*
X76772D01*
G01X77756Y968760D02*
X76772D01*
G01X92717Y968937D02*
X85384D01*
G01X85237D02*
X73228D01*
G01X85237Y969724D02*
X73228D01*
G01X85384D02*
X92717D01*
G01X77756Y970610D02*
X76772D01*
G01X77756Y970807D02*
X76772D01*
G01X77756Y971201D02*
X76772D01*
G01X74724Y971398D02*
X81890D01*
G01X92717Y972087D02*
X85384D01*
G01X85237D02*
X73228D01*
G01X85237Y972874D02*
X73228D01*
G01X85384D02*
X92717D01*
G01X74724Y972972D02*
X81890D01*
G01X77756Y973169D02*
X76772D01*
G01X77756Y973563D02*
X76772D01*
G01X77756Y973760D02*
X76772D01*
G01X72264Y974823D02*
X68169D01*
G01X92717Y975236D02*
X85384D01*
G01X85237D02*
X73228D01*
G01X68169Y975335D02*
X71567D01*
G01X77756Y975610D02*
X76772D01*
G01X77756Y975807D02*
X76772D01*
G01X70957Y975846D02*
X71654D01*
G01X85237Y976024D02*
X73228D01*
G01X85384D02*
X92717D01*
G01X74783Y976181D02*
X82854D01*
G01X77756Y976201D02*
X76772D01*
G01X74724Y976398D02*
X81890D01*
G01X69128Y976529D02*
X69563D01*
G01X69476Y977041D02*
X69215D01*
G01X74724Y977972D02*
X81890D01*
G01X82854Y978150D02*
X74783D01*
G01X77756Y978169D02*
X76772D01*
G01X77756Y978563D02*
X76772D01*
G01X78346Y978602D02*
X87331D01*
G01X77756Y978760D02*
X76772D01*
G01X71044Y978917D02*
X71218D01*
G01X71306Y979429D02*
X70957D01*
G01X74331Y980217D02*
X64961D01*
G01X74331Y980591D02*
X94488D01*
G01X64646Y980807D02*
X71181D01*
G01X74331Y981988D02*
X64961D01*
G01X93696Y983169D02*
X73228D01*
G01X79328Y983563D02*
X73228D01*
G01X79328Y983622D02*
X73228D01*
G01X70866Y984114D02*
X94488D01*
G01X51802Y946890D02*
X51829Y946893D01*
X51855Y946904D01*
X51879Y946922D01*
X51900Y946947D01*
X51917Y946977D01*
X51930Y947011D01*
X51938Y947048D01*
X51941Y947087D01*
G01X51802Y950039D02*
X51829Y950043D01*
X51855Y950054D01*
X51879Y950072D01*
X51900Y950097D01*
X51917Y950127D01*
X51930Y950161D01*
X51938Y950197D01*
X51941Y950236D01*
G01X51802Y953189D02*
X51829Y953193D01*
X51855Y953204D01*
X51879Y953222D01*
X51900Y953246D01*
X51917Y953276D01*
X51930Y953310D01*
X51938Y953347D01*
X51941Y953386D01*
G01X51802Y956339D02*
X51829Y956342D01*
X51855Y956353D01*
X51879Y956371D01*
X51900Y956396D01*
X51917Y956426D01*
X51930Y956460D01*
X51938Y956496D01*
X51941Y956535D01*
G01X51802Y959488D02*
X51829Y959492D01*
X51855Y959503D01*
X51879Y959521D01*
X51900Y959546D01*
X51917Y959576D01*
X51930Y959609D01*
X51938Y959646D01*
X51941Y959685D01*
G01X51802Y962638D02*
X51829Y962641D01*
X51855Y962652D01*
X51879Y962670D01*
X51900Y962695D01*
X51917Y962725D01*
X51930Y962759D01*
X51938Y962796D01*
X51941Y962835D01*
G01X51802Y965787D02*
X51829Y965791D01*
X51855Y965802D01*
X51879Y965820D01*
X51900Y965845D01*
X51917Y965875D01*
X51930Y965909D01*
X51938Y965945D01*
X51941Y965984D01*
G01X51802Y968937D02*
X51829Y968941D01*
X51855Y968952D01*
X51879Y968970D01*
X51900Y968994D01*
X51917Y969024D01*
X51930Y969058D01*
X51938Y969095D01*
X51941Y969134D01*
G01X51802Y972087D02*
X51829Y972090D01*
X51855Y972101D01*
X51879Y972119D01*
X51900Y972144D01*
X51917Y972174D01*
X51930Y972208D01*
X51938Y972244D01*
X51941Y972283D01*
G01X51802Y975236D02*
X51829Y975240D01*
X51855Y975251D01*
X51879Y975269D01*
X51900Y975294D01*
X51917Y975324D01*
X51930Y975357D01*
X51938Y975394D01*
X51941Y975433D01*
G01X70957Y979429D02*
X70608Y979344D01*
G01X69302Y979685D02*
X68953Y979600D01*
G01X74724Y951398D02*
G03X74331Y951004I1J-394D01*
G01Y948366D02*
G03X74724Y947972I394J0D01*
G01Y946398D02*
G03X74331Y946004I1J-394D01*
G01Y973366D02*
G03X74724Y972972I394J0D01*
G01Y971398D02*
G03X74331Y971004I1J-394D01*
G01Y963366D02*
G03X74724Y962972I394J0D01*
G01Y961398D02*
G03X74331Y961004I1J-394D01*
G01Y968366D02*
G03X74724Y967972I394J0D01*
G01Y966398D02*
G03X74331Y966004I1J-394D01*
G01Y958366D02*
G03X74724Y957972I394J0D01*
G01Y956398D02*
G03X74331Y956004I1J-394D01*
G01Y953366D02*
G03X74724Y952972I394J0D01*
G01X74331Y978366D02*
G03X74724Y977972I394J0D01*
G01Y976398D02*
G03X74331Y976004I1J-394D01*
G01X86614Y989488D02*
G03I-4528J0D01*
G01X43531Y945406D02*
Y950787D01*
G01X43701D02*
Y981791D01*
G01X46279Y946988D02*
Y947382D01*
G01X46369Y951988D02*
Y952382D01*
G01Y956988D02*
Y957382D01*
G01Y961988D02*
Y962382D01*
G01Y966988D02*
Y967382D01*
G01Y971988D02*
Y972382D01*
G01Y976988D02*
Y977382D01*
G01X46506Y975827D02*
Y975433D01*
G01Y972677D02*
Y972283D01*
G01Y969528D02*
Y969134D01*
G01Y966378D02*
Y965984D01*
G01Y963228D02*
Y962835D01*
G01Y960079D02*
Y959685D01*
G01Y956929D02*
Y956535D01*
G01Y953780D02*
Y953386D01*
G01Y950630D02*
Y950236D01*
G01Y947480D02*
Y947087D01*
G01X50987Y946988D02*
Y947382D01*
G01Y951988D02*
Y952382D01*
G01Y956988D02*
Y957382D01*
G01Y961988D02*
Y962382D01*
G01Y966988D02*
Y967382D01*
G01Y971988D02*
Y972382D01*
G01Y976988D02*
Y977382D01*
G01Y976988D02*
X50909Y976398D01*
G01X50987Y971988D02*
X50909Y971398D01*
G01X50987Y966988D02*
X50909Y966398D01*
G01X50987Y961988D02*
X50909Y961398D01*
G01X50987Y956988D02*
X50909Y956398D01*
G01X50987Y951988D02*
X50909Y951398D01*
G01X46506Y947087D02*
X46538Y946989D01*
X46626Y946917D01*
X46753Y946890D01*
G01X46506Y950236D02*
X46538Y950139D01*
X46626Y950067D01*
X46753Y950039D01*
G01X46506Y953386D02*
X46538Y953289D01*
X46626Y953217D01*
X46753Y953189D01*
G01X46506Y956535D02*
X46538Y956438D01*
X46626Y956366D01*
X46753Y956339D01*
G01X46506Y959685D02*
X46538Y959588D01*
X46626Y959516D01*
X46753Y959488D01*
G01X46506Y962835D02*
X46538Y962737D01*
X46626Y962665D01*
X46753Y962638D01*
G01X46506Y965984D02*
X46538Y965887D01*
X46626Y965815D01*
X46753Y965787D01*
G01X46506Y969134D02*
X46538Y969037D01*
X46626Y968965D01*
X46753Y968937D01*
G01X50987Y947382D02*
X50909Y947972D01*
G01X50987Y952382D02*
X50909Y952972D01*
G01X50987Y957382D02*
X50909Y957972D01*
G01X50987Y962382D02*
X50909Y962972D01*
G01X50987Y967382D02*
X50909Y967972D01*
G01X50987Y972382D02*
X50909Y972972D01*
G01X50987Y977382D02*
X50909Y977972D01*
G01X50987Y946988D02*
X50909Y946398D01*
G01X46369Y951988D02*
X46506Y951791D01*
X46644Y951594D01*
X46784Y951398D01*
G01X46369Y956988D02*
X46506Y956791D01*
X46644Y956594D01*
X46784Y956398D01*
G01X46369Y961988D02*
X46506Y961791D01*
X46644Y961594D01*
X46784Y961398D01*
G01X46369Y966988D02*
X46506Y966791D01*
X46644Y966594D01*
X46784Y966398D01*
G01X46369Y971988D02*
X46506Y971791D01*
X46644Y971594D01*
X46784Y971398D01*
G01X46369Y976988D02*
X46506Y976791D01*
X46644Y976594D01*
X46784Y976398D01*
G01X46279Y946988D02*
X46413Y946791D01*
X46548Y946594D01*
X46684Y946398D01*
G01X46506Y972283D02*
X46538Y972186D01*
X46626Y972114D01*
X46753Y972087D01*
G01X46506Y975433D02*
X46538Y975336D01*
X46626Y975264D01*
X46753Y975236D01*
G01X46684Y947972D02*
X46548Y947776D01*
X46413Y947579D01*
X46279Y947382D01*
G01X46784Y977972D02*
X46644Y977776D01*
X46506Y977580D01*
X46369Y977382D01*
G01X46784Y972972D02*
X46644Y972776D01*
X46506Y972580D01*
X46369Y972382D01*
G01X46784Y967972D02*
X46644Y967776D01*
X46506Y967580D01*
X46369Y967382D01*
G01X46784Y962972D02*
X46644Y962776D01*
X46506Y962580D01*
X46369Y962382D01*
G01X46784Y957972D02*
X46644Y957776D01*
X46506Y957580D01*
X46369Y957382D01*
G01X46784Y952972D02*
X46644Y952776D01*
X46506Y952580D01*
X46369Y952382D01*
G01X44488Y985925D02*
X42520Y983957D01*
G01Y982972D02*
X44488Y981004D01*
G01X42520Y945610D02*
X48989D01*
G01X52597Y946398D02*
X46684D01*
G01X44488Y946791D02*
X71181D01*
G01X46753Y946890D02*
X52838D01*
G01X46279Y946988D02*
X53021D01*
G01X53118Y947087D02*
X46506D01*
G01X53021Y947382D02*
X46279D01*
G01X46506Y947480D02*
X53118D01*
G01X46753Y947677D02*
X52838D01*
G01X52597Y947972D02*
X46684D01*
G01X46753Y950039D02*
X52838D01*
G01X53118Y950236D02*
X46506D01*
G01Y950630D02*
X53118D01*
G01X62992Y950787D02*
X43531D01*
G01X46753Y950827D02*
X52838D01*
G01X46784Y951398D02*
X52529D01*
G01X46369Y951988D02*
X52956D01*
G01Y952382D02*
X46369D01*
G01X52529Y952972D02*
X46784D01*
G01X46753Y953189D02*
X52838D01*
G01X53118Y953386D02*
X46506D01*
G01Y953780D02*
X53118D01*
G01X46753Y953976D02*
X52838D01*
G01X46753Y956339D02*
X52838D01*
G01X46784Y956398D02*
X52529D01*
G01X53118Y956535D02*
X46506D01*
G01Y956929D02*
X53118D01*
G01X46369Y956988D02*
X52956D01*
G01X46753Y957126D02*
X52838D01*
G01X52956Y957382D02*
X46369D01*
G01X52529Y957972D02*
X46784D01*
G01X46753Y959488D02*
X52838D01*
G01X53118Y959685D02*
X46506D01*
G01Y960079D02*
X53118D01*
G01X46753Y960276D02*
X52838D01*
G01X46784Y961398D02*
X52529D01*
G01X46369Y961988D02*
X52956D01*
G01X71181Y962028D02*
X44488D01*
G01X52956Y962382D02*
X46369D01*
G01X46753Y962638D02*
X52838D01*
G01X53118Y962835D02*
X46506D01*
G01X52529Y962972D02*
X46784D01*
G01X46506Y963228D02*
X53118D01*
G01X46753Y963425D02*
X52838D01*
G01X44488Y964390D02*
X71181D01*
G01X46753Y965787D02*
X52838D01*
G01X53118Y965984D02*
X46506D01*
G01Y966378D02*
X53118D01*
G01X46784Y966398D02*
X52529D01*
G01X46753Y966575D02*
X52838D01*
G01X46369Y966988D02*
X52956D01*
G01Y967382D02*
X46369D01*
G01X52529Y967972D02*
X46784D01*
G01X46753Y968937D02*
X52838D01*
G01X53118Y969134D02*
X46506D01*
G01Y969528D02*
X53118D01*
G01X46753Y969724D02*
X52838D01*
G01X46784Y971398D02*
X52529D01*
G01X46369Y971988D02*
X52956D01*
G01X46753Y972087D02*
X52838D01*
G01X53118Y972283D02*
X46506D01*
G01X52956Y972382D02*
X46369D01*
G01X46506Y972677D02*
X53118D01*
G01X46753Y972874D02*
X52838D01*
G01X52529Y972972D02*
X46784D01*
G01X46753Y975236D02*
X52838D01*
G01X53118Y975433D02*
X46506D01*
G01Y975827D02*
X53118D01*
G01X46753Y976024D02*
X52838D01*
G01X46784Y976398D02*
X52529D01*
G01X46369Y976988D02*
X52956D01*
G01Y977382D02*
X46369D01*
G01X52529Y977972D02*
X46784D01*
G01X62992Y981004D02*
X44488D01*
G01X73228Y981398D02*
X42520D01*
G01X46753Y947677D02*
X46626Y947649D01*
X46537Y947576D01*
X46506Y947480D01*
G01X46753Y950827D02*
X46626Y950799D01*
X46537Y950726D01*
X46506Y950630D01*
G01X46753Y953976D02*
X46626Y953948D01*
X46537Y953876D01*
X46506Y953780D01*
G01X46753Y957126D02*
X46626Y957098D01*
X46537Y957025D01*
X46506Y956929D01*
G01X46753Y960276D02*
X46626Y960248D01*
X46537Y960175D01*
X46506Y960079D01*
G01X46753Y963425D02*
X46626Y963397D01*
X46537Y963324D01*
X46506Y963228D01*
G01X46753Y966575D02*
X46626Y966547D01*
X46537Y966474D01*
X46506Y966378D01*
G01X46753Y969724D02*
X46626Y969696D01*
X46537Y969624D01*
X46506Y969528D01*
G01X46753Y972874D02*
X46626Y972846D01*
X46537Y972773D01*
X46506Y972677D01*
G01X46753Y976024D02*
X46626Y975996D01*
X46537Y975923D01*
X46506Y975827D01*
G01X66929Y994272D02*
Y985925D01*
G01X68565Y987810D02*
Y987146D01*
G01X70866Y992303D02*
Y988524D01*
G01X72404Y987146D02*
Y987884D01*
G01X73585Y993051D02*
Y992313D01*
G01X76390Y988843D02*
Y988696D01*
G01X77202D02*
Y988843D01*
G01X77497Y992608D02*
Y993051D01*
G01X89013Y987810D02*
Y987146D01*
G01X92852D02*
Y987884D01*
G01X77202Y988696D02*
X77115Y988219D01*
X76868Y987777D01*
X76480Y987425D01*
X75973Y987205D01*
X75395Y987149D01*
X74832Y987271D01*
X74356Y987553D01*
X74017Y987958D01*
X73837Y988415D01*
X73822Y988895D01*
X73979Y989365D01*
X74294Y989782D01*
G01X76323Y988391D02*
X76390Y988696D01*
G01X74865Y989257D02*
X74682Y988992D01*
X74619Y988694D01*
X74683Y988397D01*
G01X76133Y988124D02*
X76323Y988392D01*
G01X74294Y989782D02*
X73956Y989321D01*
X73811Y988802D01*
X73871Y988285D01*
X74122Y987801D01*
X74559Y987406D01*
X75132Y987183D01*
X75767Y987164D01*
X76351Y987350D01*
X76806Y987703D01*
X77098Y988175D01*
X77202Y988696D01*
G01X79474Y989794D02*
X79151Y989375D01*
X78989Y988892D01*
X79010Y988387D01*
X79213Y987910D01*
X79580Y987507D01*
X80086Y987239D01*
X80678Y987146D01*
X81267Y987243D01*
X81769Y987511D01*
X82133Y987915D01*
X82334Y988393D01*
X82354Y988898D01*
X82190Y989380D01*
X81869Y989794D01*
G01X84641D02*
X84319Y989375D01*
X84156Y988892D01*
X84178Y988387D01*
X84381Y987910D01*
X84748Y987507D01*
X85254Y987239D01*
X85845Y987146D01*
X86434Y987243D01*
X86936Y987511D01*
X87300Y987915D01*
X87502Y988393D01*
X87521Y988898D01*
X87357Y989380D01*
X87037Y989794D01*
G01X76428Y990785D02*
X74865Y989257D01*
G01X79474Y989794D02*
X79022Y990235D01*
X78752Y990770D01*
X78682Y991341D01*
X78824Y991905D01*
X79170Y992430D01*
X79698Y992823D01*
X80340Y993026D01*
X81019Y993024D01*
X81659Y992816D01*
X82182Y992420D01*
X82524Y991896D01*
X82662Y991335D01*
X82590Y990767D01*
X82320Y990233D01*
G01X84641Y989794D02*
X84189Y990235D01*
X83919Y990770D01*
X83849Y991341D01*
X83991Y991905D01*
X84337Y992430D01*
X84865Y992823D01*
X85507Y993026D01*
X86187Y993024D01*
X86827Y992816D01*
X87350Y992420D01*
X87691Y991896D01*
X87829Y991335D01*
X87757Y990767D01*
X87487Y990233D01*
G01X81869Y989794D02*
X82192Y989375D01*
X82355Y988892D01*
X82333Y988387D01*
X82130Y987910D01*
X81763Y987507D01*
X81257Y987239D01*
X80666Y987146D01*
X80077Y987243D01*
X79574Y987511D01*
X79210Y987915D01*
X79009Y988393D01*
X78989Y988898D01*
X79154Y989380D01*
X79474Y989794D01*
G01X87037D02*
X87359Y989375D01*
X87522Y988892D01*
X87500Y988387D01*
X87297Y987910D01*
X86930Y987507D01*
X86424Y987239D01*
X85833Y987146D01*
X85244Y987243D01*
X84742Y987511D01*
X84377Y987915D01*
X84176Y988393D01*
X84157Y988898D01*
X84321Y989380D01*
X84641Y989794D01*
G01X74866Y988133D02*
X74683Y988398D01*
X74619Y988697D01*
X74683Y988994D01*
G01X81869Y989794D02*
X82321Y990235D01*
X82591Y990770D01*
X82661Y991341D01*
X82520Y991905D01*
X82173Y992430D01*
X81646Y992823D01*
X81003Y993026D01*
X80324Y993024D01*
X79684Y992816D01*
X79161Y992420D01*
X78820Y991896D01*
X78681Y991335D01*
X78753Y990767D01*
X79024Y990233D01*
G01X87037Y989794D02*
X87488Y990235D01*
X87759Y990770D01*
X87829Y991341D01*
X87687Y991905D01*
X87341Y992430D01*
X86813Y992823D01*
X86170Y993026D01*
X85491Y993024D01*
X84851Y992816D01*
X84328Y992420D01*
X83987Y991896D01*
X83849Y991335D01*
X83920Y990767D01*
X84191Y990233D01*
G01X75922Y991329D02*
X74294Y989782D01*
G01X80249Y992235D02*
X79888Y991999D01*
X79650Y991649D01*
X79565Y991245D01*
X79647Y990843D01*
X79883Y990491D01*
X80247Y990251D01*
X80672Y990166D01*
G01X81094Y990250D02*
X81455Y990486D01*
X81693Y990836D01*
X81779Y991240D01*
X81696Y991642D01*
X81460Y991994D01*
X81096Y992234D01*
X80672Y992319D01*
G01X85416Y992235D02*
X85056Y991999D01*
X84817Y991649D01*
X84732Y991245D01*
X84814Y990843D01*
X85051Y990491D01*
X85414Y990251D01*
X85839Y990166D01*
G01X86262Y990250D02*
X86622Y990486D01*
X86861Y990836D01*
X86946Y991240D01*
X86864Y991642D01*
X86627Y991994D01*
X86264Y992234D01*
X85839Y992319D01*
G01X80323Y989443D02*
X80040Y989265D01*
X79853Y989000D01*
X79786Y988698D01*
X79850Y988398D01*
X80036Y988131D01*
X80321Y987949D01*
X80672Y987884D01*
G01X81020Y987949D02*
X81303Y988126D01*
X81490Y988392D01*
X81557Y988694D01*
X81493Y988994D01*
X81307Y989261D01*
X81022Y989442D01*
X80672Y989508D01*
G01X85490Y989443D02*
X85207Y989265D01*
X85020Y989000D01*
X84953Y988698D01*
X85018Y988398D01*
X85203Y988131D01*
X85489Y987949D01*
X85839Y987884D01*
G01X76133Y988124D02*
X75846Y987946D01*
X75492Y987884D01*
G01X80323Y987949D02*
X80040Y988126D01*
X79853Y988392D01*
X79786Y988694D01*
X79850Y988994D01*
X80036Y989261D01*
X80321Y989442D01*
X80672Y989508D01*
G01X81020Y989443D02*
X81303Y989265D01*
X81490Y989000D01*
X81557Y988698D01*
X81493Y988398D01*
X81307Y988131D01*
X81022Y987949D01*
X80672Y987884D01*
G01X85490Y987949D02*
X85207Y988126D01*
X85020Y988392D01*
X84953Y988694D01*
X85018Y988994D01*
X85203Y989261D01*
X85489Y989442D01*
X85839Y989508D01*
G01X86188Y989443D02*
X86470Y989265D01*
X86657Y989000D01*
X86724Y988698D01*
X86660Y988398D01*
X86475Y988131D01*
X86189Y987949D01*
X85839Y987884D01*
G01X75145Y987953D02*
X74865Y988134D01*
G01X80249Y990250D02*
X79888Y990486D01*
X79650Y990836D01*
X79565Y991240D01*
X79647Y991642D01*
X79883Y991994D01*
X80247Y992234D01*
X80672Y992319D01*
G01X81094Y992235D02*
X81455Y991999D01*
X81693Y991649D01*
X81779Y991245D01*
X81696Y990843D01*
X81460Y990491D01*
X81096Y990251D01*
X80672Y990166D01*
G01X85416Y990250D02*
X85056Y990486D01*
X84817Y990836D01*
X84732Y991240D01*
X84814Y991642D01*
X85051Y991994D01*
X85414Y992234D01*
X85839Y992319D01*
G01X86262Y992235D02*
X86622Y991999D01*
X86861Y991649D01*
X86946Y991245D01*
X86864Y990843D01*
X86627Y990491D01*
X86264Y990251D01*
X85839Y990166D01*
G01X86188Y987949D02*
X86470Y988126D01*
X86657Y988392D01*
X86724Y988694D01*
X86660Y988994D01*
X86475Y989261D01*
X86189Y989442D01*
X85839Y989508D01*
G01X75492Y987884D02*
X75144Y987953D01*
G01X94488Y986555D02*
X70866D01*
G01X68565Y987146D02*
X72404D01*
G01X89013D02*
X92852D01*
G01Y987884D02*
X89899D01*
G01X72404D02*
X69451D01*
G01X70866Y988524D02*
X94488D01*
G01X77202Y988843D02*
X76390D01*
G01X94488Y992303D02*
X70866D01*
G01X73585Y992313D02*
X76464D01*
G01X92113Y993051D02*
X91228D01*
G01X77497D02*
X73585D01*
G01X71666D02*
X70780D01*
G01X68565Y987810D02*
G03X70780Y993051I-7141J6107D01*
G01X69451Y987884D02*
G03X71666Y993051I-6937J6032D01*
G01X76428Y990785D02*
G03X77498Y992608I-2810J2875D01*
G01X75922Y991329D02*
G03X76464Y992313I-1276J1344D01*
G01X89013Y987810D02*
G03X91228Y993051I-7141J6107D01*
G01X89899Y987884D02*
G03X92113Y993051I-6938J6031D01*
G01X85591Y989488D02*
G03I-3505J0D01*
G01X85433D02*
G03I-3347J0D01*
G01X84252D02*
G03I-2166J0D01*
G01X40551Y993091D02*
Y985925D01*
G01X40492Y993550D02*
X40547Y993164D01*
G01X42520Y985925D02*
X39236D01*
G01X44488D02*
X94488D01*
G01X66929Y993091D02*
X40551D01*
G01X51941Y922283D02*
X51938Y922322D01*
X51930Y922358D01*
X51917Y922392D01*
X51900Y922422D01*
X51879Y922447D01*
X51856Y922465D01*
X51830Y922476D01*
X51802Y922480D01*
G01X51941Y925433D02*
X51938Y925471D01*
X51930Y925508D01*
X51917Y925542D01*
X51900Y925572D01*
X51879Y925596D01*
X51856Y925615D01*
X51830Y925626D01*
X51802Y925630D01*
G01X51941Y928583D02*
X51938Y928621D01*
X51930Y928657D01*
X51917Y928691D01*
X51900Y928722D01*
X51879Y928746D01*
X51856Y928764D01*
X51830Y928776D01*
X51802Y928780D01*
G01X51941Y931732D02*
X51938Y931770D01*
X51930Y931807D01*
X51917Y931841D01*
X51900Y931871D01*
X51879Y931896D01*
X51856Y931914D01*
X51830Y931925D01*
X51802Y931929D01*
G01X51941Y934882D02*
X51938Y934920D01*
X51930Y934957D01*
X51917Y934991D01*
X51900Y935021D01*
X51879Y935045D01*
X51856Y935063D01*
X51830Y935075D01*
X51802Y935079D01*
G01X51941Y938031D02*
X51938Y938070D01*
X51930Y938106D01*
X51917Y938140D01*
X51900Y938170D01*
X51879Y938195D01*
X51856Y938213D01*
X51830Y938224D01*
X51802Y938228D01*
G01X51941Y941181D02*
X51938Y941219D01*
X51930Y941256D01*
X51917Y941290D01*
X51900Y941320D01*
X51879Y941344D01*
X51856Y941363D01*
X51830Y941374D01*
X51802Y941378D01*
G01X51941Y944331D02*
X51938Y944369D01*
X51930Y944406D01*
X51917Y944439D01*
X51900Y944470D01*
X51879Y944494D01*
X51856Y944512D01*
X51830Y944524D01*
X51802Y944528D01*
G01X51428Y944331D02*
Y943937D01*
G01Y938031D02*
Y937638D01*
G01Y941181D02*
Y940787D01*
G01Y934882D02*
Y934488D01*
G01Y928583D02*
Y928189D01*
G01Y931732D02*
Y931339D01*
G01Y925433D02*
Y925039D01*
G01Y922283D02*
Y921890D01*
G01X51872Y943049D02*
Y942065D01*
G01Y939899D02*
Y938915D01*
G01Y933600D02*
Y932616D01*
G01Y936750D02*
Y935765D01*
G01Y930450D02*
Y929466D01*
G01Y927301D02*
Y926317D01*
G01X51941Y921890D02*
Y922283D01*
G01Y925039D02*
Y925433D01*
G01Y928189D02*
Y928583D01*
G01Y931339D02*
Y931732D01*
G01Y934488D02*
Y934882D01*
G01Y937638D02*
Y938031D01*
G01Y940787D02*
Y941181D01*
G01Y943937D02*
Y944331D01*
G01X52112Y922382D02*
Y921988D01*
G01X52814Y943049D02*
Y942065D01*
G01Y939899D02*
Y938915D01*
G01Y933600D02*
Y932616D01*
G01Y936750D02*
Y935765D01*
G01Y930450D02*
Y929466D01*
G01Y927301D02*
Y926317D01*
G01X53021Y922382D02*
Y921988D01*
G01X53118Y921890D02*
Y922283D01*
G01Y925039D02*
Y925433D01*
G01Y928189D02*
Y928583D01*
G01Y931339D02*
Y931732D01*
G01Y934488D02*
Y934882D01*
G01Y937638D02*
Y938031D01*
G01Y940787D02*
Y941181D01*
G01Y943937D02*
Y944331D01*
G01X51872Y942065D02*
X51869Y942026D01*
X51861Y941990D01*
X51847Y941956D01*
X51829Y941926D01*
X51807Y941901D01*
X51781Y941883D01*
X51754Y941872D01*
X51724Y941868D01*
G01X51872Y938915D02*
X51869Y938877D01*
X51861Y938840D01*
X51847Y938806D01*
X51829Y938776D01*
X51807Y938752D01*
X51781Y938733D01*
X51754Y938722D01*
X51724Y938718D01*
G01X51872Y935765D02*
X51869Y935727D01*
X51861Y935691D01*
X51847Y935657D01*
X51829Y935626D01*
X51807Y935602D01*
X51781Y935584D01*
X51754Y935572D01*
X51724Y935569D01*
G01X51872Y932616D02*
X51869Y932578D01*
X51861Y932541D01*
X51847Y932507D01*
X51829Y932477D01*
X51807Y932452D01*
X51781Y932434D01*
X51754Y932423D01*
X51724Y932419D01*
G01X51872Y929466D02*
X51869Y929428D01*
X51861Y929391D01*
X51847Y929357D01*
X51829Y929327D01*
X51807Y929303D01*
X51781Y929285D01*
X51754Y929273D01*
X51724Y929269D01*
G01X51872Y926317D02*
X51869Y926278D01*
X51861Y926242D01*
X51847Y926208D01*
X51829Y926178D01*
X51807Y926153D01*
X51781Y926135D01*
X51754Y926124D01*
X51724Y926120D01*
G01X51428Y943937D02*
X51417Y943839D01*
X51389Y943767D01*
X51351Y943740D01*
G01X51428Y940787D02*
X51417Y940689D01*
X51389Y940617D01*
X51351Y940591D01*
G01X51428Y937638D02*
X51417Y937539D01*
X51389Y937467D01*
X51351Y937441D01*
G01X51428Y934488D02*
X51417Y934390D01*
X51389Y934318D01*
X51351Y934291D01*
G01X51428Y928189D02*
X51417Y928091D01*
X51389Y928019D01*
X51351Y927992D01*
G01X51428Y925039D02*
X51417Y924941D01*
X51389Y924869D01*
X51351Y924843D01*
G01X69213Y924941D02*
Y944429D01*
G01X74409Y925039D02*
Y944331D01*
G01X74724D02*
Y925039D01*
G01X75170Y944528D02*
Y943740D01*
G01Y938228D02*
Y937441D01*
G01Y941378D02*
Y940591D01*
G01Y935079D02*
Y934291D01*
G01Y928780D02*
Y927992D01*
G01Y931929D02*
Y931142D01*
G01Y925630D02*
Y924843D01*
G01Y922480D02*
Y921693D01*
G01X75197Y944528D02*
Y943740D01*
G01Y938228D02*
Y937441D01*
G01Y941378D02*
Y940591D01*
G01Y935079D02*
Y934291D01*
G01Y928780D02*
Y927992D01*
G01Y931929D02*
Y931142D01*
G01Y925630D02*
Y924843D01*
G01Y922480D02*
Y921693D01*
G01X75237Y943740D02*
Y941378D01*
G01Y937441D02*
Y935079D01*
G01Y940591D02*
Y938228D01*
G01Y934291D02*
Y931929D01*
G01Y931142D02*
Y928780D01*
G01Y927992D02*
Y925630D01*
G01X75512Y944331D02*
Y925039D01*
G01X75573Y944528D02*
Y943740D01*
G01Y938228D02*
Y937441D01*
G01Y941378D02*
Y940591D01*
G01Y935079D02*
Y934291D01*
G01Y928780D02*
Y927992D01*
G01Y931929D02*
Y931142D01*
G01Y925630D02*
Y924843D01*
G01Y922480D02*
Y921693D01*
G01X75787Y922972D02*
Y921398D01*
G01X76012Y925039D02*
Y944331D01*
G01X76222Y943839D02*
Y925531D01*
G01X76929Y944331D02*
Y925039D01*
G01X77206Y943150D02*
Y941969D01*
G01Y940000D02*
Y938819D01*
G01Y933701D02*
Y932520D01*
G01Y936850D02*
Y935669D01*
G01Y930551D02*
Y929370D01*
G01Y927402D02*
Y926220D01*
G01X78740Y922972D02*
Y921398D01*
G01X78935Y921693D02*
Y922480D01*
G01Y924843D02*
Y925630D01*
G01Y927992D02*
Y928780D01*
G01Y931142D02*
Y931929D01*
G01Y934291D02*
Y935079D01*
G01Y937441D02*
Y938228D01*
G01Y940591D02*
Y941378D01*
G01Y943740D02*
Y944528D01*
G01X80285Y944331D02*
Y925039D01*
G01X80337Y928858D02*
Y931063D01*
G01Y938307D02*
Y940512D01*
G01X80356Y926220D02*
Y927402D01*
G01Y929370D02*
Y930551D01*
G01Y932520D02*
Y933701D01*
G01Y935669D02*
Y936850D01*
G01Y938819D02*
Y940000D01*
G01Y941969D02*
Y943150D01*
G01X80763Y944331D02*
Y940512D01*
G01Y938307D02*
Y931063D01*
G01Y928858D02*
Y925039D01*
G01X80919Y921693D02*
Y922480D01*
G01Y924843D02*
Y925630D01*
G01Y927992D02*
Y928780D01*
G01Y931142D02*
Y931929D01*
G01Y934291D02*
Y935079D01*
G01Y937441D02*
Y938228D01*
G01Y940591D02*
Y941378D01*
G01Y943740D02*
Y944528D01*
G01X81890Y921398D02*
Y922972D01*
G01X82220Y940512D02*
Y938307D01*
G01Y931063D02*
Y928858D01*
G01X82570Y944528D02*
Y943740D01*
G01Y938228D02*
Y937441D01*
G01Y941378D02*
Y940591D01*
G01Y935079D02*
Y934291D01*
G01Y928780D02*
Y927992D01*
G01Y931929D02*
Y931142D01*
G01Y925630D02*
Y924843D01*
G01Y922480D02*
Y921693D01*
G01X84298Y922480D02*
Y924843D01*
G01Y925630D02*
Y927992D01*
G01Y928780D02*
Y931142D01*
G01Y931929D02*
Y934291D01*
G01Y935079D02*
Y937441D01*
G01Y938228D02*
Y940591D01*
G01Y941378D02*
Y943740D01*
G01Y944528D02*
Y946890D01*
G01X85237Y944528D02*
Y943740D01*
G01Y938228D02*
Y937441D01*
G01Y941378D02*
Y940591D01*
G01Y935079D02*
Y934291D01*
G01Y928780D02*
Y927992D01*
G01Y931929D02*
Y931142D01*
G01Y925630D02*
Y924843D01*
G01Y922480D02*
Y921693D01*
G01X85384Y944528D02*
Y943740D01*
G01Y938228D02*
Y937441D01*
G01Y941378D02*
Y940591D01*
G01Y935079D02*
Y934291D01*
G01Y928780D02*
Y927992D01*
G01Y931929D02*
Y931142D01*
G01Y925630D02*
Y924843D01*
G01Y922480D02*
Y921693D01*
G01X86976Y944528D02*
Y943740D01*
G01Y938228D02*
Y937441D01*
G01Y941378D02*
Y940591D01*
G01Y935079D02*
Y934291D01*
G01Y928780D02*
Y927992D01*
G01Y931929D02*
Y931142D01*
G01Y925630D02*
Y924843D01*
G01Y922480D02*
Y921693D01*
G01X87918D02*
Y922480D01*
G01Y924843D02*
Y925630D01*
G01Y927992D02*
Y928780D01*
G01Y931142D02*
Y931929D01*
G01Y934291D02*
Y935079D01*
G01Y937441D02*
Y938228D01*
G01Y940591D02*
Y941378D01*
G01Y943740D02*
Y944528D01*
G01X90754Y921693D02*
Y922480D01*
G01Y924843D02*
Y925630D01*
G01Y927992D02*
Y928780D01*
G01Y931142D02*
Y931929D01*
G01Y934291D02*
Y935079D01*
G01Y937441D02*
Y938228D01*
G01Y940591D02*
Y941378D01*
G01Y943740D02*
Y944528D01*
G01X90943D02*
Y943740D01*
G01Y938228D02*
Y937441D01*
G01Y941378D02*
Y940591D01*
G01Y935079D02*
Y934291D01*
G01Y928780D02*
Y927992D01*
G01Y931929D02*
Y931142D01*
G01Y925630D02*
Y924843D01*
G01Y922480D02*
Y921693D01*
G01X92717Y944528D02*
Y943740D01*
G01Y938228D02*
Y937441D01*
G01Y941378D02*
Y940591D01*
G01Y935079D02*
Y934291D01*
G01Y928780D02*
Y927992D01*
G01Y931929D02*
Y931142D01*
G01Y925630D02*
Y924843D01*
G01Y922480D02*
Y921693D01*
G01X51428Y921890D02*
X51417Y921791D01*
X51389Y921719D01*
X51351Y921693D01*
G01X52112Y921988D02*
X51839Y921398D01*
G01X52597Y922972D02*
X53021Y922382D01*
G01X51839Y922972D02*
X52112Y922382D01*
G01X52597Y921398D02*
X53021Y921988D01*
G01X51351Y922480D02*
X51389Y922454D01*
X51417Y922382D01*
X51428Y922283D01*
G01X51351Y925630D02*
X51389Y925604D01*
X51417Y925531D01*
X51428Y925433D01*
G01X51351Y928780D02*
X51389Y928753D01*
X51417Y928681D01*
X51428Y928583D01*
G01X51351Y931929D02*
X51389Y931903D01*
X51417Y931831D01*
X51428Y931732D01*
G01X51351Y935079D02*
X51389Y935052D01*
X51417Y934980D01*
X51428Y934882D01*
G01X51351Y938228D02*
X51389Y938202D01*
X51417Y938130D01*
X51428Y938031D01*
G01X51351Y941378D02*
X51389Y941352D01*
X51417Y941280D01*
X51428Y941181D01*
G01X51351Y944528D02*
X51389Y944501D01*
X51417Y944429D01*
X51428Y944331D01*
G01X51351Y931142D02*
X51389Y931168D01*
X51417Y931240D01*
X51428Y931339D01*
G01X77756Y920807D02*
X76772D01*
G01X77756Y921201D02*
X76772D01*
G01X74724Y921398D02*
X81890D01*
G01X92717Y921693D02*
X85384D01*
G01X85237D02*
X73228D01*
G01X85237Y922480D02*
X73228D01*
G01X85384D02*
X92717D01*
G01X74724Y922972D02*
X81890D01*
G01X77756Y923169D02*
X76772D01*
G01X77756Y923563D02*
X76772D01*
G01X77756Y923760D02*
X76772D01*
G01X92717Y924843D02*
X85384D01*
G01X85237D02*
X73228D01*
G01X74331Y924921D02*
X73228D01*
G01Y925039D02*
X80763D01*
G01X76222Y925531D02*
X78346D01*
G01X85237Y925630D02*
X73228D01*
G01X85384D02*
X92717D01*
G01X76222Y925827D02*
X75237D01*
G01X76222Y926024D02*
X75237D01*
G01X74331Y926220D02*
X80356D01*
G01X74331Y927402D02*
X80356D01*
G01X76222Y927598D02*
X75237D01*
G01X76222Y927795D02*
X75237D01*
G01X92717Y927992D02*
X85384D01*
G01X85237D02*
X73228D01*
G01X85237Y928780D02*
X73228D01*
G01X85384D02*
X92717D01*
G01X82220Y928858D02*
X80337D01*
G01X76222Y928976D02*
X75237D01*
G01X76222Y929173D02*
X75237D01*
G01X74331Y929370D02*
X80356D01*
G01X51724Y927498D02*
X51753Y927494D01*
X51781Y927483D01*
X51806Y927465D01*
X51829Y927440D01*
X51847Y927410D01*
X51861Y927376D01*
X51869Y927340D01*
X51872Y927301D01*
G01X51724Y930647D02*
X51753Y930644D01*
X51781Y930632D01*
X51806Y930615D01*
X51829Y930590D01*
X51847Y930560D01*
X51861Y930526D01*
X51869Y930489D01*
X51872Y930450D01*
G01X51724Y933797D02*
X51753Y933793D01*
X51781Y933782D01*
X51806Y933764D01*
X51829Y933739D01*
X51847Y933709D01*
X51861Y933676D01*
X51869Y933639D01*
X51872Y933600D01*
G01X51724Y936946D02*
X51753Y936943D01*
X51781Y936931D01*
X51806Y936914D01*
X51829Y936889D01*
X51847Y936859D01*
X51861Y936825D01*
X51869Y936789D01*
X51872Y936750D01*
G01X51724Y940096D02*
X51753Y940093D01*
X51781Y940081D01*
X51806Y940063D01*
X51829Y940039D01*
X51847Y940009D01*
X51861Y939975D01*
X51869Y939938D01*
X51872Y939899D01*
G01X51724Y943246D02*
X51753Y943242D01*
X51781Y943231D01*
X51806Y943213D01*
X51829Y943188D01*
X51847Y943158D01*
X51861Y943124D01*
X51869Y943088D01*
X51872Y943049D01*
G01X51802Y921693D02*
X51829Y921696D01*
X51855Y921707D01*
X51879Y921726D01*
X51900Y921750D01*
X51917Y921780D01*
X51930Y921814D01*
X51938Y921851D01*
X51941Y921890D01*
G01X51802Y924843D02*
X51829Y924846D01*
X51855Y924857D01*
X51879Y924875D01*
X51900Y924900D01*
X51917Y924930D01*
X51930Y924964D01*
X51938Y925000D01*
X51941Y925039D01*
G01X51802Y927992D02*
X51829Y927996D01*
X51855Y928007D01*
X51879Y928025D01*
X51900Y928050D01*
X51917Y928080D01*
X51930Y928113D01*
X51938Y928150D01*
X51941Y928189D01*
G01X51802Y931142D02*
X51829Y931145D01*
X51855Y931156D01*
X51879Y931174D01*
X51900Y931199D01*
X51917Y931229D01*
X51930Y931263D01*
X51938Y931300D01*
X51941Y931339D01*
G01X51802Y934291D02*
X51829Y934295D01*
X51855Y934306D01*
X51879Y934324D01*
X51900Y934349D01*
X51917Y934379D01*
X51930Y934413D01*
X51938Y934449D01*
X51941Y934488D01*
G01X51802Y937441D02*
X51829Y937444D01*
X51855Y937456D01*
X51879Y937474D01*
X51900Y937498D01*
X51917Y937528D01*
X51930Y937562D01*
X51938Y937599D01*
X51941Y937638D01*
G01X51802Y940591D02*
X51829Y940594D01*
X51855Y940605D01*
X51879Y940623D01*
X51900Y940648D01*
X51917Y940678D01*
X51930Y940712D01*
X51938Y940748D01*
X51941Y940787D01*
G01X74331Y930551D02*
X80356D01*
G01X76222Y930748D02*
X75237D01*
G01X76222Y930945D02*
X75237D01*
G01X82220Y931063D02*
X80337D01*
G01X92717Y931142D02*
X85384D01*
G01X85237D02*
X73228D01*
G01X85237Y931929D02*
X73228D01*
G01X85384D02*
X92717D01*
G01X76222Y932126D02*
X75237D01*
G01X76222Y932323D02*
X75237D01*
G01X74331Y932520D02*
X80356D01*
G01X74331Y933701D02*
X80356D01*
G01X76222Y933898D02*
X75237D01*
G01X76222Y934094D02*
X75237D01*
G01X92717Y934291D02*
X85384D01*
G01X85237D02*
X73228D01*
G01X85237Y935079D02*
X73228D01*
G01X85384D02*
X92717D01*
G01X76222Y935276D02*
X75237D01*
G01X76222Y935472D02*
X75237D01*
G01X74331Y935669D02*
X80356D01*
G01X74331Y936850D02*
X80356D01*
G01X76222Y937047D02*
X75237D01*
G01X76222Y937244D02*
X75237D01*
G01X92717Y937441D02*
X85384D01*
G01X85237D02*
X73228D01*
G01X85237Y938228D02*
X73228D01*
G01X85384D02*
X92717D01*
G01X82220Y938307D02*
X80337D01*
G01X76222Y938425D02*
X75237D01*
G01X76222Y938622D02*
X75237D01*
G01X74331Y938819D02*
X80356D01*
G01X74331Y940000D02*
X80356D01*
G01X76222Y940197D02*
X75237D01*
G01X76222Y940394D02*
X75237D01*
G01X82220Y940512D02*
X80337D01*
G01X92717Y940591D02*
X85384D01*
G01X85237D02*
X73228D01*
G01X85237Y941378D02*
X73228D01*
G01X85384D02*
X92717D01*
G01X76222Y941575D02*
X75237D01*
G01X76222Y941772D02*
X75237D01*
G01X74331Y941969D02*
X80356D01*
G01X74331Y943150D02*
X80356D01*
G01X76222Y943346D02*
X75237D01*
G01X76222Y943543D02*
X75237D01*
G01X92717Y943740D02*
X85384D01*
G01X85237D02*
X73228D01*
G01X78346Y943839D02*
X76222D01*
G01X73228Y944331D02*
X80763D01*
G01X74331Y944449D02*
X73228D01*
G01X85237Y944528D02*
X73228D01*
G01X85384D02*
X92717D01*
G01X51802Y943740D02*
X51829Y943744D01*
X51855Y943755D01*
X51879Y943773D01*
X51900Y943798D01*
X51917Y943828D01*
X51930Y943861D01*
X51938Y943898D01*
X51941Y943937D01*
G01X74331Y923366D02*
G03X74724Y922972I394J0D01*
G01Y921398D02*
G03X74331Y921004I1J-394D01*
G01X43701Y945610D02*
Y923760D01*
G01X46279Y921988D02*
Y922382D01*
G01X46496Y926317D02*
Y927301D01*
G01Y929466D02*
Y930450D01*
G01Y932616D02*
Y933600D01*
G01Y935765D02*
Y936750D01*
G01Y938915D02*
Y939899D01*
G01Y942065D02*
Y943049D01*
G01X46506Y944331D02*
Y943937D01*
G01Y938031D02*
Y937638D01*
G01Y941181D02*
Y940787D01*
G01Y934882D02*
Y934488D01*
G01Y928583D02*
Y928189D01*
G01Y931732D02*
Y931339D01*
G01Y925433D02*
Y925039D01*
G01Y922283D02*
Y921890D01*
G01X48989Y923760D02*
Y924941D01*
G01Y944429D02*
Y945610D01*
G01X50720Y943049D02*
Y942065D01*
G01Y939899D02*
Y938915D01*
G01Y933600D02*
Y932616D01*
G01Y936750D02*
Y935765D01*
G01Y930450D02*
Y929466D01*
G01Y927301D02*
Y926317D01*
G01X50987Y921988D02*
Y922382D01*
G01X50720Y942065D02*
Y942026D01*
X50718Y941990D01*
X50715Y941956D01*
X50711Y941926D01*
X50706Y941901D01*
X50700Y941883D01*
X50694Y941872D01*
X50687Y941868D01*
G01X50720Y938915D02*
Y938877D01*
X50718Y938840D01*
X50715Y938806D01*
X50711Y938776D01*
X50706Y938752D01*
X50700Y938733D01*
X50694Y938722D01*
X50687Y938718D01*
G01X50720Y935765D02*
Y935727D01*
X50718Y935691D01*
X50715Y935657D01*
X50711Y935626D01*
X50706Y935602D01*
X50700Y935584D01*
X50694Y935572D01*
X50687Y935569D01*
G01X50720Y932616D02*
Y932578D01*
X50718Y932541D01*
X50715Y932507D01*
X50711Y932477D01*
X50706Y932452D01*
X50700Y932434D01*
X50694Y932423D01*
X50687Y932419D01*
G01X50720Y929466D02*
Y929428D01*
X50718Y929391D01*
X50715Y929357D01*
X50711Y929327D01*
X50706Y929303D01*
X50700Y929285D01*
X50694Y929273D01*
X50687Y929269D01*
G01X50720Y926317D02*
Y926278D01*
X50718Y926242D01*
X50715Y926208D01*
X50711Y926178D01*
X50706Y926153D01*
X50700Y926135D01*
X50694Y926124D01*
X50687Y926120D01*
G01X46496Y926317D02*
X46530Y926218D01*
X46618Y926147D01*
X46744Y926120D01*
G01X46496Y929466D02*
X46530Y929367D01*
X46618Y929296D01*
X46744Y929269D01*
G01X46496Y932616D02*
X46530Y932517D01*
X46618Y932446D01*
X46744Y932419D01*
G01X46496Y935765D02*
X46530Y935667D01*
X46618Y935596D01*
X46744Y935569D01*
G01X46496Y938915D02*
X46530Y938816D01*
X46618Y938745D01*
X46744Y938718D01*
G01X46496Y942065D02*
X46530Y941966D01*
X46618Y941895D01*
X46744Y941868D01*
G01X46506Y921890D02*
X46538Y921793D01*
X46626Y921720D01*
X46753Y921693D01*
G01X46506Y925039D02*
X46538Y924942D01*
X46626Y924870D01*
X46753Y924843D01*
G01X46506Y928189D02*
X46538Y928092D01*
X46626Y928020D01*
X46753Y927992D01*
G01X46506Y931339D02*
X46538Y931241D01*
X46626Y931169D01*
X46753Y931142D01*
G01X46506Y934488D02*
X46538Y934391D01*
X46626Y934319D01*
X46753Y934291D01*
G01X46506Y937638D02*
X46538Y937541D01*
X46626Y937469D01*
X46753Y937441D01*
G01X46506Y940787D02*
X46538Y940690D01*
X46626Y940618D01*
X46753Y940591D01*
G01X46506Y943937D02*
X46538Y943840D01*
X46626Y943768D01*
X46753Y943740D01*
G01X50987Y922382D02*
X50909Y922972D01*
G01X50987Y921988D02*
X50909Y921398D01*
G01X46279Y921988D02*
X46413Y921791D01*
X46548Y921594D01*
X46684Y921398D01*
G01Y922972D02*
X46548Y922776D01*
X46413Y922579D01*
X46279Y922382D01*
G01X44488Y944449D02*
X42520Y946417D01*
G01Y922953D02*
X44488Y924921D01*
G01X50687Y927498D02*
X50694Y927494D01*
X50700Y927483D01*
X50706Y927465D01*
X50711Y927440D01*
X50715Y927410D01*
X50718Y927376D01*
X50720Y927340D01*
Y927301D01*
G01X50687Y930647D02*
X50694Y930644D01*
X50700Y930632D01*
X50706Y930615D01*
X50711Y930590D01*
X50715Y930560D01*
X50718Y930526D01*
X50720Y930489D01*
Y930450D01*
G01X50687Y933797D02*
X50694Y933793D01*
X50700Y933782D01*
X50706Y933764D01*
X50711Y933739D01*
X50715Y933709D01*
X50718Y933676D01*
X50720Y933639D01*
Y933600D01*
G01X50687Y936946D02*
X50694Y936943D01*
X50700Y936931D01*
X50706Y936914D01*
X50711Y936889D01*
X50715Y936859D01*
X50718Y936825D01*
X50720Y936789D01*
Y936750D01*
G01X50687Y940096D02*
X50694Y940093D01*
X50700Y940081D01*
X50706Y940063D01*
X50711Y940039D01*
X50715Y940009D01*
X50718Y939975D01*
X50720Y939938D01*
Y939899D01*
G01X50687Y943246D02*
X50694Y943242D01*
X50700Y943231D01*
X50706Y943213D01*
X50711Y943188D01*
X50715Y943158D01*
X50718Y943124D01*
X50720Y943088D01*
Y943049D01*
G01X52597Y921398D02*
X46684D01*
G01X46753Y921693D02*
X52838D01*
G01X53118Y921890D02*
X46506D01*
G01X46279Y921988D02*
X53021D01*
G01X46506Y922283D02*
X53118D01*
G01X53021Y922382D02*
X46279D01*
G01X46753Y922480D02*
X52838D01*
G01X71181Y922579D02*
X44488D01*
G01X52597Y922972D02*
X46684D01*
G01X48989Y923760D02*
X42520D01*
G01X46753Y924843D02*
X52838D01*
G01X62992Y924921D02*
X44488D01*
G01X48989Y924941D02*
X71181D01*
G01X53118Y925039D02*
X46506D01*
G01Y925433D02*
X53118D01*
G01X46753Y925630D02*
X52838D01*
G01X52552Y926120D02*
X46744D01*
G01X46496Y926317D02*
X52814D01*
G01Y927301D02*
X46496D01*
G01X52552Y927498D02*
X46744D01*
G01X46753Y927992D02*
X52838D01*
G01X53118Y928189D02*
X46506D01*
G01Y928583D02*
X53118D01*
G01X46753Y928780D02*
X52838D01*
G01X52552Y929269D02*
X46744D01*
G01X46496Y929466D02*
X52814D01*
G01Y930450D02*
X46496D01*
G01X52552Y930647D02*
X46744D01*
G01X46753Y931142D02*
X52838D01*
G01X53118Y931339D02*
X46506D01*
G01Y931732D02*
X53118D01*
G01X46753Y931929D02*
X52838D01*
G01X52552Y932419D02*
X46744D01*
G01X46496Y932616D02*
X52814D01*
G01Y933600D02*
X46496D01*
G01X52552Y933797D02*
X46744D01*
G01X46753Y934291D02*
X52838D01*
G01X53118Y934488D02*
X46506D01*
G01Y934882D02*
X53118D01*
G01X46753Y935079D02*
X52838D01*
G01X52552Y935569D02*
X46744D01*
G01X46496Y935765D02*
X52814D01*
G01Y936750D02*
X46496D01*
G01X52552Y936946D02*
X46744D01*
G01X46753Y937441D02*
X52838D01*
G01X53118Y937638D02*
X46506D01*
G01Y938031D02*
X53118D01*
G01X46753Y938228D02*
X52838D01*
G01X52552Y938718D02*
X46744D01*
G01X46496Y938915D02*
X52814D01*
G01Y939899D02*
X46496D01*
G01X52552Y940096D02*
X46744D01*
G01X46753Y940591D02*
X52838D01*
G01X53118Y940787D02*
X46506D01*
G01Y941181D02*
X53118D01*
G01X46753Y941378D02*
X52838D01*
G01X52552Y941868D02*
X46744D01*
G01X46496Y942065D02*
X52814D01*
G01Y943049D02*
X46496D01*
G01X52552Y943246D02*
X46744D01*
G01X46753Y943740D02*
X52838D01*
G01X53118Y943937D02*
X46506D01*
G01Y944331D02*
X53118D01*
G01X71181Y944429D02*
X48989D01*
G01X62992Y944449D02*
X44488D01*
G01X46753Y944528D02*
X52838D01*
G01X46753Y922480D02*
X46626Y922452D01*
X46537Y922380D01*
X46506Y922283D01*
G01X46753Y925630D02*
X46626Y925602D01*
X46537Y925529D01*
X46506Y925433D01*
G01X46753Y928780D02*
X46626Y928752D01*
X46537Y928679D01*
X46506Y928583D01*
G01X46753Y931929D02*
X46626Y931901D01*
X46537Y931828D01*
X46506Y931732D01*
G01X46753Y935079D02*
X46626Y935051D01*
X46537Y934978D01*
X46506Y934882D01*
G01X46753Y938228D02*
X46626Y938200D01*
X46537Y938128D01*
X46506Y938031D01*
G01X46753Y941378D02*
X46626Y941350D01*
X46537Y941277D01*
X46506Y941181D01*
G01X46753Y944528D02*
X46626Y944500D01*
X46537Y944427D01*
X46506Y944331D01*
G01X46744Y927498D02*
X46617Y927470D01*
X46528Y927398D01*
X46496Y927301D01*
G01X46744Y930647D02*
X46617Y930620D01*
X46528Y930547D01*
X46496Y930450D01*
G01X46744Y933797D02*
X46617Y933770D01*
X46528Y933697D01*
X46496Y933600D01*
G01X46744Y936946D02*
X46617Y936919D01*
X46528Y936846D01*
X46496Y936750D01*
G01X46744Y940096D02*
X46617Y940069D01*
X46528Y939996D01*
X46496Y939899D01*
G01X46744Y943246D02*
X46617Y943219D01*
X46528Y943146D01*
X46496Y943049D01*
G01X68110Y1021555D02*
Y1019587D01*
G01Y1017028D02*
Y1018996D01*
G01X69602Y1018013D02*
Y1018141D01*
G01X69685Y1021850D02*
Y1021260D01*
G01Y1020079D02*
Y1018504D01*
G01Y1017323D02*
Y1016732D01*
G01X69696Y1017504D02*
Y1018124D01*
G01X69789Y1018252D02*
Y1017504D01*
G01X70669Y1016732D02*
Y1021850D01*
G01X70866D02*
Y1016732D01*
G01X71260Y1018996D02*
Y1017028D01*
G01Y1019587D02*
Y1021555D01*
G01X74409Y1018996D02*
Y1017028D01*
G01Y1019587D02*
Y1021555D01*
G01X74803Y1021850D02*
Y1016732D01*
G01X75000D02*
Y1021850D01*
G01X75984Y1016732D02*
Y1017323D01*
G01Y1018504D02*
Y1020079D01*
G01Y1021260D02*
Y1021850D01*
G01X77559Y1021555D02*
Y1019587D01*
G01Y1017028D02*
Y1018996D01*
G01X69602Y1018141D02*
X69696Y1018252D01*
G01Y1018124D02*
X69602Y1018013D01*
G01X81024Y1007205D02*
X64646D01*
G01X69685Y1016732D02*
X75984D01*
G01X71260Y1017028D02*
X68110D01*
G01X74409D02*
X77559D01*
G01X69789Y1017504D02*
X69696D01*
G01Y1018252D02*
X69789D01*
G01X77559Y1018996D02*
X74409D01*
G01X68110D02*
X71260D01*
G01X77559Y1019587D02*
X74409D01*
G01X68110D02*
X71260D01*
G01Y1021555D02*
X68110D01*
G01X74409D02*
X77559D01*
G01X75984Y1021850D02*
X69685D01*
G01X75984Y1021260D02*
G03Y1020079I0J-591D01*
G01X69685D02*
G03Y1021260I0J590D01*
G01Y1017323D02*
G03Y1018504I0J591D01*
G01X75984D02*
G03Y1017323I0J-591D01*
G01X70044Y1002087D02*
Y1000512D01*
G01X70079D02*
Y1002087D01*
G01X70103Y1000512D02*
Y1002087D01*
G01X71426D02*
Y1000512D01*
G01X71796D02*
Y1002087D01*
G01X73873D02*
Y1000512D01*
G01X74243D02*
Y1002087D01*
G01X75567D02*
Y1000512D01*
G01X75591Y1002087D02*
Y1000512D01*
G01X75625D02*
Y1002087D01*
G01X81024Y1007205D02*
Y994272D01*
G01Y997028D02*
X64646D01*
G01X75000Y999724D02*
X70669D01*
G01X75625Y1000512D02*
X70044D01*
G01Y1002087D02*
X75625D01*
G01X70669Y1002874D02*
X75000D01*
G01X70669D02*
G03Y999724I0J-1575D01*
G01X75000D02*
G03Y1002874I0J1575D01*
G01X40519Y994241D02*
X40462Y994100D01*
X40457Y993861D01*
G01X40519Y994241D02*
X40463Y994106D01*
X40456Y993870D01*
X40493Y993541D01*
G01X40551Y994272D02*
X94488D01*
G01X52112Y1282500D02*
X51839Y1281909D01*
G01X52112Y1277500D02*
X51839Y1276909D01*
G01X52112Y1267500D02*
X51839Y1266909D01*
G01X52112Y1262500D02*
X51839Y1261909D01*
G01X52529Y1281909D02*
X52956Y1282500D01*
G01X52529Y1276909D02*
X52956Y1277500D01*
G01X52529Y1266909D02*
X52956Y1267500D01*
G01X52529Y1261909D02*
X52956Y1262500D01*
G01X51428Y1283701D02*
Y1283307D01*
G01Y1280551D02*
Y1280157D01*
G01Y1277402D02*
Y1277008D01*
G01Y1271102D02*
Y1270709D01*
G01Y1274252D02*
Y1273858D01*
G01Y1267953D02*
Y1267559D01*
G01Y1264803D02*
Y1264409D01*
G01Y1261654D02*
Y1261260D01*
G01Y1258504D02*
Y1258110D01*
G01X51941D02*
Y1258504D01*
G01Y1264409D02*
Y1264803D01*
G01Y1261260D02*
Y1261654D01*
G01Y1267559D02*
Y1267953D01*
G01Y1270709D02*
Y1271102D01*
G01Y1273858D02*
Y1274252D01*
G01Y1277008D02*
Y1277402D01*
G01Y1280157D02*
Y1280551D01*
G01Y1283307D02*
Y1283701D01*
G01X52112Y1282894D02*
Y1282500D01*
G01Y1277894D02*
Y1277500D01*
G01Y1267894D02*
Y1267500D01*
G01Y1262894D02*
Y1262500D01*
G01Y1257894D02*
Y1257500D01*
G01X52956Y1282894D02*
Y1282500D01*
G01Y1277894D02*
Y1277500D01*
G01Y1267894D02*
Y1267500D01*
G01Y1262894D02*
Y1262500D01*
G01Y1257894D02*
Y1257500D01*
G01X53118Y1258110D02*
Y1258504D01*
G01Y1264409D02*
Y1264803D01*
G01Y1261260D02*
Y1261654D01*
G01Y1267559D02*
Y1267953D01*
G01Y1270709D02*
Y1271102D01*
G01Y1273858D02*
Y1274252D01*
G01Y1277008D02*
Y1277402D01*
G01Y1280157D02*
Y1280551D01*
G01Y1283307D02*
Y1283701D01*
G01X51428Y1283307D02*
X51417Y1283209D01*
X51389Y1283137D01*
X51351Y1283110D01*
G01X51428Y1280157D02*
X51417Y1280059D01*
X51389Y1279987D01*
X51351Y1279961D01*
G01X51428Y1277008D02*
X51417Y1276909D01*
X51389Y1276837D01*
X51351Y1276811D01*
G01X51428Y1273858D02*
X51417Y1273760D01*
X51389Y1273688D01*
X51351Y1273661D01*
G01X51428Y1270709D02*
X51417Y1270610D01*
X51389Y1270538D01*
X51351Y1270512D01*
G01X51428Y1267559D02*
X51417Y1267461D01*
X51389Y1267389D01*
X51351Y1267362D01*
G01X51428Y1264409D02*
X51417Y1264311D01*
X51389Y1264239D01*
X51351Y1264213D01*
G01X51428Y1261260D02*
X51417Y1261161D01*
X51389Y1261089D01*
X51351Y1261063D01*
G01X51428Y1258110D02*
X51417Y1258012D01*
X51389Y1257940D01*
X51351Y1257913D01*
G01X84041Y1248110D02*
X84059Y1248166D01*
X84111Y1248331D01*
X84190Y1248589D01*
X84285Y1248917D01*
X84390Y1249291D01*
G01X52112Y1257500D02*
X51839Y1256909D01*
G01X79328Y1251319D02*
X79583Y1251713D01*
G01X52529Y1256909D02*
X52956Y1257500D01*
G01X51941Y1258504D02*
X51938Y1258542D01*
X51930Y1258579D01*
X51917Y1258613D01*
X51900Y1258643D01*
X51879Y1258667D01*
X51856Y1258685D01*
X51830Y1258697D01*
X51802Y1258701D01*
G01X51941Y1261654D02*
X51938Y1261692D01*
X51930Y1261728D01*
X51917Y1261762D01*
X51900Y1261793D01*
X51879Y1261817D01*
X51856Y1261835D01*
X51830Y1261846D01*
X51802Y1261850D01*
G01X51941Y1264803D02*
X51938Y1264841D01*
X51930Y1264878D01*
X51917Y1264912D01*
X51900Y1264942D01*
X51879Y1264967D01*
X51856Y1264985D01*
X51830Y1264996D01*
X51802Y1265000D01*
G01X51941Y1267953D02*
X51938Y1267991D01*
X51930Y1268028D01*
X51917Y1268061D01*
X51900Y1268092D01*
X51879Y1268116D01*
X51856Y1268134D01*
X51830Y1268146D01*
X51802Y1268150D01*
G01X51941Y1271102D02*
X51938Y1271141D01*
X51930Y1271177D01*
X51917Y1271211D01*
X51900Y1271241D01*
X51879Y1271266D01*
X51856Y1271284D01*
X51830Y1271295D01*
X51802Y1271299D01*
G01X51941Y1274252D02*
X51938Y1274290D01*
X51930Y1274327D01*
X51917Y1274361D01*
X51900Y1274391D01*
X51879Y1274415D01*
X51856Y1274433D01*
X51830Y1274445D01*
X51802Y1274449D01*
G01X51941Y1277402D02*
X51938Y1277440D01*
X51930Y1277476D01*
X51917Y1277510D01*
X51900Y1277541D01*
X51879Y1277565D01*
X51856Y1277583D01*
X51830Y1277594D01*
X51802Y1277598D01*
G01X51941Y1280551D02*
X51938Y1280589D01*
X51930Y1280626D01*
X51917Y1280660D01*
X51900Y1280690D01*
X51879Y1280715D01*
X51856Y1280733D01*
X51830Y1280744D01*
X51802Y1280748D01*
G01X51941Y1283701D02*
X51938Y1283739D01*
X51930Y1283776D01*
X51917Y1283809D01*
X51900Y1283840D01*
X51879Y1283864D01*
X51856Y1283882D01*
X51830Y1283894D01*
X51802Y1283898D01*
G01X62992Y1253878D02*
Y1386516D01*
G01X64961Y1254665D02*
Y1252894D01*
G01X69213Y1290492D02*
Y1273957D01*
G01Y1271594D02*
Y1254075D01*
G01X70113Y1246019D02*
Y1245462D01*
G01X70866Y1250728D02*
Y1248327D01*
G01X71181Y1386319D02*
Y1254075D01*
G01X73228Y1251260D02*
Y1389134D01*
G01X74331Y1388681D02*
Y1251713D01*
G01X74803Y1274272D02*
Y1271122D01*
G01X75170Y1283898D02*
Y1283110D01*
G01Y1280748D02*
Y1279961D01*
G01Y1274449D02*
Y1273661D01*
G01Y1277598D02*
Y1276811D01*
G01Y1271299D02*
Y1270512D01*
G01Y1265000D02*
Y1264213D01*
G01Y1268150D02*
Y1267362D01*
G01Y1261850D02*
Y1261063D01*
G01Y1258701D02*
Y1257913D01*
G01X75197Y1283898D02*
Y1283110D01*
G01Y1280748D02*
Y1279961D01*
G01Y1274449D02*
Y1273661D01*
G01Y1277598D02*
Y1276811D01*
G01Y1271299D02*
Y1270512D01*
G01Y1265000D02*
Y1264213D01*
G01Y1268150D02*
Y1267362D01*
G01Y1261850D02*
Y1261063D01*
G01Y1258701D02*
Y1257913D01*
G01X75573Y1283898D02*
Y1283110D01*
G01Y1280748D02*
Y1279961D01*
G01Y1274449D02*
Y1273661D01*
G01Y1277598D02*
Y1276811D01*
G01Y1271299D02*
Y1270512D01*
G01Y1265000D02*
Y1264213D01*
G01Y1268150D02*
Y1267362D01*
G01Y1261850D02*
Y1261063D01*
G01Y1258701D02*
Y1257913D01*
G01X75787Y1283484D02*
Y1281909D01*
G01Y1278484D02*
Y1276909D01*
G01Y1274272D02*
Y1271122D01*
G01Y1268484D02*
Y1266909D01*
G01Y1263484D02*
Y1261909D01*
G01Y1258484D02*
Y1256909D01*
G01X76772Y1284272D02*
Y1281122D01*
G01Y1279272D02*
Y1276122D01*
G01Y1273484D02*
Y1271909D01*
G01Y1269272D02*
Y1266122D01*
G01Y1264272D02*
Y1261122D01*
G01Y1259272D02*
Y1256122D01*
G01Y1248957D02*
Y1251260D01*
G01X77756Y1284272D02*
Y1281122D01*
G01Y1279272D02*
Y1276122D01*
G01Y1269272D02*
Y1266122D01*
G01Y1264272D02*
Y1261122D01*
G01Y1259272D02*
Y1256122D01*
G01X78346Y1388681D02*
Y1251713D01*
G01X78740Y1283484D02*
Y1281909D01*
G01Y1278484D02*
Y1276909D01*
G01Y1268484D02*
Y1266909D01*
G01Y1263484D02*
Y1261909D01*
G01Y1258484D02*
Y1256909D01*
G01X78801Y1386102D02*
Y1254488D01*
G01X78935Y1257913D02*
Y1258701D01*
G01Y1261063D02*
Y1261850D01*
G01Y1264213D02*
Y1265000D01*
G01Y1267362D02*
Y1268150D01*
G01Y1270512D02*
Y1271299D01*
G01Y1273661D02*
Y1274449D01*
G01Y1276811D02*
Y1277598D01*
G01Y1279961D02*
Y1280748D01*
G01Y1283110D02*
Y1283898D01*
G01X79328Y1251260D02*
Y1251319D01*
G01X79921Y1271909D02*
Y1273484D01*
G01X79967Y1251713D02*
Y1248957D01*
G01X80919Y1257913D02*
Y1258701D01*
G01Y1261063D02*
Y1261850D01*
G01Y1264213D02*
Y1265000D01*
G01Y1267362D02*
Y1268150D01*
G01Y1270512D02*
Y1271299D01*
G01Y1273661D02*
Y1274449D01*
G01Y1276811D02*
Y1277598D01*
G01Y1279961D02*
Y1280748D01*
G01Y1283110D02*
Y1283898D01*
G01X81890Y1256909D02*
Y1258484D01*
G01Y1261909D02*
Y1263484D01*
G01Y1266909D02*
Y1268484D01*
G01Y1276909D02*
Y1278484D01*
G01Y1281909D02*
Y1283484D01*
G01X82570Y1283898D02*
Y1283110D01*
G01Y1280748D02*
Y1279961D01*
G01Y1274449D02*
Y1273661D01*
G01Y1277598D02*
Y1276811D01*
G01Y1271299D02*
Y1270512D01*
G01Y1265000D02*
Y1264213D01*
G01Y1268150D02*
Y1267362D01*
G01Y1261850D02*
Y1261063D01*
G01Y1258701D02*
Y1257913D01*
G01X84298Y1256240D02*
Y1257913D01*
G01Y1258701D02*
Y1261063D01*
G01Y1261850D02*
Y1264213D01*
G01Y1265000D02*
Y1267362D01*
G01Y1268150D02*
Y1270512D01*
G01Y1271299D02*
Y1273661D01*
G01Y1274449D02*
Y1276811D01*
G01Y1277598D02*
Y1279961D01*
G01Y1280748D02*
Y1283110D01*
G01Y1283898D02*
Y1286260D01*
G01X85237Y1283898D02*
Y1283110D01*
G01Y1280748D02*
Y1279961D01*
G01Y1274449D02*
Y1273661D01*
G01Y1277598D02*
Y1276811D01*
G01Y1271299D02*
Y1270512D01*
G01Y1265000D02*
Y1264213D01*
G01Y1268150D02*
Y1267362D01*
G01Y1261850D02*
Y1261063D01*
G01Y1258701D02*
Y1257913D01*
G01X85384Y1283898D02*
Y1283110D01*
G01Y1280748D02*
Y1279961D01*
G01Y1274449D02*
Y1273661D01*
G01Y1277598D02*
Y1276811D01*
G01Y1271299D02*
Y1270512D01*
G01Y1265000D02*
Y1264213D01*
G01Y1268150D02*
Y1267362D01*
G01Y1261850D02*
Y1261063D01*
G01Y1258701D02*
Y1257913D01*
G01X86976Y1283898D02*
Y1283110D01*
G01Y1280748D02*
Y1279961D01*
G01Y1274449D02*
Y1273661D01*
G01Y1277598D02*
Y1276811D01*
G01Y1271299D02*
Y1270512D01*
G01Y1265000D02*
Y1264213D01*
G01Y1268150D02*
Y1267362D01*
G01Y1261850D02*
Y1261063D01*
G01Y1258701D02*
Y1257913D01*
G01X87331Y1251713D02*
Y1388681D01*
G01X87841Y1251713D02*
Y1248957D01*
G01X87918Y1257913D02*
Y1258701D01*
G01Y1261063D02*
Y1261850D01*
G01Y1264213D02*
Y1265000D01*
G01Y1267362D02*
Y1268150D01*
G01Y1270512D02*
Y1271299D01*
G01Y1273661D02*
Y1274449D01*
G01Y1276811D02*
Y1277598D01*
G01Y1279961D02*
Y1280748D01*
G01Y1283110D02*
Y1283898D01*
G01X90754Y1257913D02*
Y1258701D01*
G01Y1261063D02*
Y1261850D01*
G01Y1264213D02*
Y1265000D01*
G01Y1267362D02*
Y1268150D01*
G01Y1270512D02*
Y1271299D01*
G01Y1273661D02*
Y1274449D01*
G01Y1276811D02*
Y1277598D01*
G01Y1279961D02*
Y1280748D01*
G01Y1283110D02*
Y1283898D01*
G01X90943D02*
Y1283110D01*
G01Y1280748D02*
Y1279961D01*
G01Y1274449D02*
Y1273661D01*
G01Y1277598D02*
Y1276811D01*
G01Y1271299D02*
Y1270512D01*
G01Y1265000D02*
Y1264213D01*
G01Y1268150D02*
Y1267362D01*
G01Y1261850D02*
Y1261063D01*
G01Y1258701D02*
Y1257913D01*
G01X92717Y1283898D02*
Y1283110D01*
G01Y1280748D02*
Y1279961D01*
G01Y1274449D02*
Y1273661D01*
G01Y1277598D02*
Y1276811D01*
G01Y1271299D02*
Y1270512D01*
G01Y1265000D02*
Y1264213D01*
G01Y1268150D02*
Y1267362D01*
G01Y1261850D02*
Y1261063D01*
G01Y1258701D02*
Y1257913D01*
G01X93696Y1251713D02*
Y1254488D01*
G01X94170Y1248957D02*
Y1254488D01*
G01X51839Y1258484D02*
X52112Y1257894D01*
G01X51839Y1263484D02*
X52112Y1262894D01*
G01X51839Y1268484D02*
X52112Y1267894D01*
G01X51839Y1278484D02*
X52112Y1277894D01*
G01X80132Y1248110D02*
X80114Y1248166D01*
X80062Y1248331D01*
X79983Y1248590D01*
X79887Y1248917D01*
X79783Y1249291D01*
G01X51839Y1283484D02*
X52112Y1282894D01*
G01X52529Y1258484D02*
X52956Y1257894D01*
G01X52529Y1263484D02*
X52956Y1262894D01*
G01X52529Y1268484D02*
X52956Y1267894D01*
G01X52529Y1278484D02*
X52956Y1277894D01*
G01X52529Y1283484D02*
X52956Y1282894D01*
G01X51351Y1258701D02*
X51389Y1258674D01*
X51417Y1258602D01*
X51428Y1258504D01*
G01X51351Y1261850D02*
X51389Y1261824D01*
X51417Y1261752D01*
X51428Y1261654D01*
G01X51351Y1265000D02*
X51389Y1264974D01*
X51417Y1264902D01*
X51428Y1264803D01*
G01X51351Y1268150D02*
X51389Y1268123D01*
X51417Y1268051D01*
X51428Y1267953D01*
G01X51351Y1271299D02*
X51389Y1271273D01*
X51417Y1271201D01*
X51428Y1271102D01*
G01X51351Y1274449D02*
X51389Y1274422D01*
X51417Y1274350D01*
X51428Y1274252D01*
G01X51351Y1277598D02*
X51389Y1277572D01*
X51417Y1277500D01*
X51428Y1277402D01*
G01X51351Y1280748D02*
X51389Y1280722D01*
X51417Y1280650D01*
X51428Y1280551D01*
G01X51351Y1283898D02*
X51389Y1283871D01*
X51417Y1283799D01*
X51428Y1283701D01*
G01X90044Y1246019D02*
X88428D01*
G01X92721D02*
X91339D01*
G01X70113D02*
X68670D01*
G01X94488Y1246358D02*
X70866D01*
G01X83082Y1247766D02*
X81622D01*
G01X80132Y1248110D02*
X84041D01*
G01X94488Y1248327D02*
X70866D01*
G01X84390Y1249291D02*
X79783D01*
G01X94488Y1250728D02*
X70866D01*
G01X79328Y1251260D02*
X73228D01*
G01X79328Y1251319D02*
X73228D01*
G01X93696Y1251713D02*
X73228D01*
G01X74331Y1252894D02*
X64961D01*
G01X64646Y1254075D02*
X71181D01*
G01X94488Y1254488D02*
X74331D01*
G01Y1254665D02*
X64961D01*
G01X77756Y1256122D02*
X76772D01*
G01X87331Y1256240D02*
X78346D01*
G01X77756Y1256319D02*
X76772D01*
G01X77756Y1256713D02*
X76772D01*
G01X74724Y1256909D02*
X81890D01*
G01X92717Y1257913D02*
X85384D01*
G01X85237D02*
X73228D01*
G01X74724Y1258484D02*
X81890D01*
G01X77756Y1258681D02*
X76772D01*
G01X85237Y1258701D02*
X73228D01*
G01X85384D02*
X92717D01*
G01X77756Y1259075D02*
X76772D01*
G01X77756Y1259272D02*
X76772D01*
G01X92717Y1261063D02*
X85384D01*
G01X85237D02*
X73228D01*
G01X77756Y1261122D02*
X76772D01*
G01X77756Y1261319D02*
X76772D01*
G01X77756Y1261713D02*
X76772D01*
G01X85237Y1261850D02*
X73228D01*
G01X85384D02*
X92717D01*
G01X81890Y1261909D02*
X74724D01*
G01X81890Y1263484D02*
X74724D01*
G01X77756Y1263681D02*
X76772D01*
G01X77756Y1264075D02*
X76772D01*
G01X92717Y1264213D02*
X85384D01*
G01X85237D02*
X73228D01*
G01X77756Y1264272D02*
X76772D01*
G01X85237Y1265000D02*
X73228D01*
G01X85384D02*
X92717D01*
G01X77756Y1266122D02*
X76772D01*
G01X77756Y1266319D02*
X76772D01*
G01X77756Y1266713D02*
X76772D01*
G01X74724Y1266909D02*
X81890D01*
G01X92717Y1267362D02*
X85384D01*
G01X85237D02*
X73228D01*
G01X85237Y1268150D02*
X73228D01*
G01X85384D02*
X92717D01*
G01X74724Y1268484D02*
X81890D01*
G01X77756Y1268681D02*
X76772D01*
G01X77756Y1269075D02*
X76772D01*
G01X77756Y1269272D02*
X76772D01*
G01X73228Y1270492D02*
X74331D01*
G01X92717Y1270512D02*
X85384D01*
G01X85237D02*
X73228D01*
G01X75787Y1271122D02*
X74803D01*
G01X85237Y1271299D02*
X73228D01*
G01X85384D02*
X92717D01*
G01X75787Y1271319D02*
X74803D01*
G01X75787Y1271713D02*
X74803D01*
G01X74331Y1271909D02*
X79921D01*
G01X74331Y1273484D02*
X79921D01*
G01X92717Y1273661D02*
X85384D01*
G01X85237D02*
X73228D01*
G01X75787Y1273681D02*
X74803D01*
G01X75787Y1274075D02*
X74803D01*
G01X75787Y1274272D02*
X74803D01*
G01X85237Y1274449D02*
X73228D01*
G01X85384D02*
X92717D01*
G01X73228Y1274902D02*
X74331D01*
G01X77756Y1276122D02*
X76772D01*
G01X77756Y1276319D02*
X76772D01*
G01X77756Y1276713D02*
X76772D01*
G01X92717Y1276811D02*
X85384D01*
G01X85237D02*
X73228D01*
G01X74724Y1276909D02*
X81890D01*
G01X85237Y1277598D02*
X73228D01*
G01X85384D02*
X92717D01*
G01X74724Y1278484D02*
X81890D01*
G01X77756Y1278681D02*
X76772D01*
G01X77756Y1279075D02*
X76772D01*
G01X77756Y1279272D02*
X76772D01*
G01X92717Y1279961D02*
X85384D01*
G01X85237D02*
X73228D01*
G01X85237Y1280748D02*
X73228D01*
G01X85384D02*
X92717D01*
G01X77756Y1281122D02*
X76772D01*
G01X77756Y1281319D02*
X76772D01*
G01X77756Y1281713D02*
X76772D01*
G01X74724Y1281909D02*
X81890D01*
G01X92717Y1283110D02*
X85384D01*
G01X85237D02*
X73228D01*
G01X74724Y1283484D02*
X81890D01*
G01X77756Y1283681D02*
X76772D01*
G01X85237Y1283898D02*
X73228D01*
G01X85384D02*
X92717D01*
G01X77756Y1284075D02*
X76772D01*
G01X77756Y1284272D02*
X76772D01*
G01X51802Y1257913D02*
X51829Y1257917D01*
X51855Y1257928D01*
X51879Y1257946D01*
X51900Y1257971D01*
X51917Y1258001D01*
X51930Y1258035D01*
X51938Y1258071D01*
X51941Y1258110D01*
G01X51802Y1261063D02*
X51829Y1261067D01*
X51855Y1261078D01*
X51879Y1261096D01*
X51900Y1261120D01*
X51917Y1261150D01*
X51930Y1261184D01*
X51938Y1261221D01*
X51941Y1261260D01*
G01X51802Y1264213D02*
X51829Y1264216D01*
X51855Y1264227D01*
X51879Y1264245D01*
X51900Y1264270D01*
X51917Y1264300D01*
X51930Y1264334D01*
X51938Y1264370D01*
X51941Y1264409D01*
G01X51802Y1267362D02*
X51829Y1267366D01*
X51855Y1267377D01*
X51879Y1267395D01*
X51900Y1267420D01*
X51917Y1267450D01*
X51930Y1267483D01*
X51938Y1267520D01*
X51941Y1267559D01*
G01X51802Y1270512D02*
X51829Y1270515D01*
X51855Y1270526D01*
X51879Y1270544D01*
X51900Y1270569D01*
X51917Y1270599D01*
X51930Y1270633D01*
X51938Y1270670D01*
X51941Y1270709D01*
G01X51802Y1273661D02*
X51829Y1273665D01*
X51855Y1273676D01*
X51879Y1273694D01*
X51900Y1273719D01*
X51917Y1273749D01*
X51930Y1273783D01*
X51938Y1273819D01*
X51941Y1273858D01*
G01X51802Y1276811D02*
X51829Y1276815D01*
X51855Y1276826D01*
X51879Y1276844D01*
X51900Y1276869D01*
X51917Y1276898D01*
X51930Y1276932D01*
X51938Y1276969D01*
X51941Y1277008D01*
G01X51802Y1279961D02*
X51829Y1279964D01*
X51855Y1279975D01*
X51879Y1279993D01*
X51900Y1280018D01*
X51917Y1280048D01*
X51930Y1280082D01*
X51938Y1280119D01*
X51941Y1280157D01*
G01X51802Y1283110D02*
X51829Y1283114D01*
X51855Y1283125D01*
X51879Y1283143D01*
X51900Y1283168D01*
X51917Y1283198D01*
X51930Y1283231D01*
X51938Y1283268D01*
X51941Y1283307D01*
G01X72893Y1245467D02*
G03X70113Y1245462I-1388J-1207D01*
G01X75529Y1245612D02*
G03X72893Y1245467I-1248J-1351D01*
G01X74724Y1261909D02*
G03X74331Y1261516I0J-393D01*
G01Y1258878D02*
G03X74724Y1258484I394J0D01*
G01Y1256909D02*
G03X74331Y1256516I0J-393D01*
G01Y1263878D02*
G03X74724Y1263484I394J0D01*
G01X74331Y1268878D02*
G03X74724Y1268484I394J0D01*
G01Y1266909D02*
G03X74331Y1266516I0J-393D01*
G01Y1283878D02*
G03X74724Y1283484I394J0D01*
G01Y1281909D02*
G03X74331Y1281516I0J-393D01*
G01Y1278878D02*
G03X74724Y1278484I394J0D01*
G01Y1276909D02*
G03X74331Y1276516I0J-393D01*
G01X80324Y1245665D02*
G03X77277I-1523J-2361D01*
G01X86655Y1246027D02*
G03X85012Y1245984I-757J-2475D01*
G01X79783Y1241496D02*
X79886Y1241865D01*
X79982Y1242194D01*
X80063Y1242457D01*
X80115Y1242622D01*
X80132Y1242677D01*
G01X90453Y1243289D02*
X89662Y1242012D01*
G01X89697Y1244159D02*
X88254Y1242012D01*
G01X91339Y1246019D02*
X90650Y1245033D01*
G01X92721Y1246019D02*
X91426Y1244167D01*
G01X64646Y1254075D02*
Y1227677D01*
G01X66929Y1240610D02*
Y1248957D01*
G01X68670Y1246019D02*
Y1242012D01*
G01X70044Y1234370D02*
Y1232795D01*
G01X70079D02*
Y1234370D01*
G01X70103Y1232795D02*
Y1234370D01*
G01X70110Y1244537D02*
Y1242012D01*
G01X70866Y1246358D02*
Y1242579D01*
G01X71426Y1234370D02*
Y1232795D01*
G01X71541Y1242012D02*
Y1244537D01*
G01X71796Y1232795D02*
Y1234370D01*
G01X73000Y1244537D02*
Y1242012D01*
G01X73873Y1234370D02*
Y1232795D01*
G01X74243D02*
Y1234370D01*
G01X74430Y1242012D02*
Y1244537D01*
G01X75567Y1234370D02*
Y1232795D01*
G01X75591Y1234370D02*
Y1232795D01*
G01X75625D02*
Y1234370D01*
G01X75823Y1244941D02*
Y1242012D01*
G01X81024Y1240610D02*
Y1227677D01*
G01X81622Y1242012D02*
Y1247766D01*
G01X83082D02*
Y1242012D01*
G01X94488Y1240610D02*
Y1254488D01*
G01X84041Y1242677D02*
X84059Y1242621D01*
X84111Y1242456D01*
X84190Y1242197D01*
X84285Y1241870D01*
X84390Y1241496D01*
G01X90044Y1246019D02*
X90650Y1245033D01*
G01X91426Y1244167D02*
X92747Y1242012D01*
G01X90453Y1243289D02*
X91198Y1242012D01*
G01X88428Y1246019D02*
X89697Y1244159D01*
G01X64646Y1227677D02*
X81024D01*
G01X75000Y1232008D02*
X70669D01*
G01X75625Y1232795D02*
X70044D01*
G01Y1234370D02*
X75625D01*
G01X70669Y1235157D02*
X75000D01*
G01X81024Y1237854D02*
X64646D01*
G01X79783Y1241496D02*
X84390D01*
G01X89662Y1242012D02*
X88254D01*
G01X92747D02*
X91198D01*
G01X83082D02*
X81622D01*
G01X75823D02*
X74430D01*
G01X73000D02*
X71541D01*
G01X70110D02*
X68670D01*
G01X94488Y1242579D02*
X70866D01*
G01X84041Y1242677D02*
X80132D01*
G01X88097Y1243168D02*
X86594D01*
G01X88228Y1243611D02*
X85228D01*
G01X86655Y1244437D02*
X85229D01*
G01X70669Y1235157D02*
G03Y1232008I0J-1574D01*
G01X75000D02*
G03Y1235157I0J1575D01*
G01X74430Y1244537D02*
G03X73000I-715J0D01*
G01X71541D02*
G03X70110I-716J0D01*
G01X79502Y1243121D02*
G03Y1244806I-2236J843D01*
G01X75823Y1244941D02*
G03X75529Y1245612I-913J0D01*
G01X77278Y1242221D02*
G03X80324Y1242222I1522J2362D01*
G01X80845Y1242788D02*
G03X80844Y1245100I-2163J1155D01*
G01X76756D02*
G03X76757Y1242786I2163J-1156D01*
G01X78030Y1244806D02*
G03Y1243121I2236J-842D01*
G01X77277Y1245665D02*
G03X76756Y1245100I830J-1289D01*
G01X80844D02*
G03X80323Y1245665I-1351J-723D01*
G01X80324Y1242222D02*
G03X80845Y1242788I-831J1288D01*
G01X76757Y1242786D02*
G03X77278Y1242221I1351J723D01*
G01X79502Y1244806D02*
G03X78029I-736J-278D01*
G01Y1243121D02*
G03X79502I737J277D01*
G01X84390Y1241496D02*
G03Y1249291I-2304J3898D01*
G01X79783D02*
G03Y1241496I2304J-3898D01*
G01X85591Y1245394D02*
G03I-3505J0D01*
G01X80132Y1248110D02*
G03Y1242677I1954J-2717D01*
G01X84041D02*
G03Y1248110I-1954J2716D01*
G01X84252Y1245394D02*
G03I-2166J0D01*
G01X83847Y1244845D02*
G03X83673Y1244185I4018J-1412D01*
G01D02*
G03Y1243688I3525J-249D01*
G01X88228Y1243611D02*
G03X87889Y1245054I-3015J53D01*
G01X83673Y1243689D02*
G03X83935Y1242827I2971J432D01*
G01X83934Y1242830D02*
G03X85672Y1241812I1807J1092D01*
G01X85012Y1245984D02*
G03X83847Y1244845I729J-1911D01*
G01X87889Y1245054D02*
G03X86655Y1246028I-1736J-930D01*
G01X87254Y1242099D02*
G03X88098Y1243168I-703J1423D01*
G01X85229Y1243611D02*
G03X86003Y1242803I792J-16D01*
G01D02*
G03X86594Y1243168I9J646D01*
G01X85669Y1241812D02*
G03X87254Y1242099I262J3073D01*
G01X86654Y1244437D02*
G03X85229I-713J82D01*
G01X46506Y1271102D02*
X46539Y1271201D01*
X46628Y1271272D01*
X46753Y1271299D01*
G01X50143Y1272500D02*
X49871Y1271909D01*
G01X46784Y1283484D02*
X46644Y1283288D01*
X46506Y1283091D01*
X46369Y1282894D01*
G01X46784Y1278484D02*
X46644Y1278288D01*
X46506Y1278091D01*
X46369Y1277894D01*
G01X44815Y1273484D02*
X44676Y1273288D01*
X44538Y1273091D01*
X44401Y1272894D01*
G01X46784Y1268484D02*
X46644Y1268288D01*
X46506Y1268091D01*
X46369Y1267894D01*
G01X46784Y1263484D02*
X46644Y1263288D01*
X46506Y1263091D01*
X46369Y1262894D01*
G01X46784Y1258484D02*
X46644Y1258288D01*
X46506Y1258091D01*
X46369Y1257894D01*
G01X50560Y1271909D02*
X50987Y1272500D01*
G01X42520Y1391437D02*
Y1248957D01*
G01X43642Y1253484D02*
Y1386909D01*
G01X43701Y1253091D02*
Y1323996D01*
G01X44401Y1272500D02*
Y1272894D01*
G01X44488Y1386516D02*
Y1253878D01*
G01X46369Y1257500D02*
Y1257894D01*
G01Y1262500D02*
Y1262894D01*
G01Y1267500D02*
Y1267894D01*
G01Y1277500D02*
Y1277894D01*
G01Y1282500D02*
Y1282894D01*
G01X46506Y1283701D02*
Y1283307D01*
G01Y1280551D02*
Y1280157D01*
G01Y1277402D02*
Y1277008D01*
G01Y1271102D02*
Y1270709D01*
G01Y1274252D02*
Y1273858D01*
G01Y1267953D02*
Y1267559D01*
G01Y1264803D02*
Y1264409D01*
G01Y1261654D02*
Y1261260D01*
G01Y1258504D02*
Y1258110D01*
G01X49019Y1272500D02*
Y1272894D01*
G01X50143D02*
Y1272500D01*
G01X50987Y1272894D02*
Y1272500D01*
G01Y1262894D02*
Y1262500D01*
G01Y1257500D02*
Y1257894D01*
G01Y1267500D02*
Y1267894D01*
G01Y1277500D02*
Y1277894D01*
G01Y1282500D02*
Y1282894D01*
G01X49019Y1272500D02*
X48941Y1271909D01*
G01X50987Y1282500D02*
X50909Y1281909D01*
G01X50987Y1277500D02*
X50909Y1276909D01*
G01X50987Y1267500D02*
X50909Y1266909D01*
G01Y1261909D02*
X50987Y1262500D01*
G01Y1257500D02*
X50909Y1256909D01*
G01X44488Y1253878D02*
X42520Y1251909D01*
G01X50987Y1257894D02*
X50909Y1258484D01*
G01X49019Y1272894D02*
X48941Y1273484D01*
G01X50909Y1263484D02*
X50987Y1262894D01*
G01Y1267894D02*
X50909Y1268484D01*
G01X50987Y1277894D02*
X50909Y1278484D01*
G01X50987Y1282894D02*
X50909Y1283484D01*
G01X49871Y1273484D02*
X50143Y1272894D01*
G01X46506Y1258110D02*
X46538Y1258013D01*
X46626Y1257941D01*
X46753Y1257913D01*
G01X46506Y1261260D02*
X46538Y1261163D01*
X46626Y1261091D01*
X46753Y1261063D01*
G01X46506Y1264409D02*
X46538Y1264312D01*
X46626Y1264240D01*
X46753Y1264213D01*
G01X46506Y1267559D02*
X46538Y1267462D01*
X46626Y1267390D01*
X46753Y1267362D01*
G01X46506Y1273858D02*
X46538Y1273761D01*
X46626Y1273689D01*
X46753Y1273661D01*
G01X46506Y1277008D02*
X46538Y1276911D01*
X46626Y1276839D01*
X46753Y1276811D01*
G01X46506Y1280157D02*
X46538Y1280060D01*
X46626Y1279988D01*
X46753Y1279961D01*
G01X46506Y1283307D02*
X46538Y1283210D01*
X46626Y1283138D01*
X46753Y1283110D01*
G01X46369Y1257500D02*
X46506Y1257302D01*
X46644Y1257106D01*
X46784Y1256909D01*
G01X46369Y1262500D02*
X46506Y1262302D01*
X46644Y1262106D01*
X46784Y1261909D01*
G01X46369Y1267500D02*
X46506Y1267302D01*
X46644Y1267106D01*
X46784Y1266909D01*
G01X44401Y1272500D02*
X44538Y1272302D01*
X44676Y1272106D01*
X44815Y1271909D01*
G01X46369Y1277500D02*
X46506Y1277302D01*
X46644Y1277106D01*
X46784Y1276909D01*
G01X42520Y1250925D02*
X44488Y1248957D01*
G01X50560Y1273484D02*
X50987Y1272894D01*
G01X46369Y1282500D02*
X46506Y1282302D01*
X46644Y1282106D01*
X46784Y1281909D01*
G01X46753Y1270512D02*
X46627Y1270539D01*
X46538Y1270612D01*
X46506Y1270709D01*
G01X42520Y1248957D02*
X39236D01*
G01X44488D02*
X94488D01*
G01X42520Y1253484D02*
X73228D01*
G01X44488Y1253878D02*
X62992D01*
G01X46784Y1256909D02*
X52529D01*
G01X46369Y1257500D02*
X52956D01*
G01Y1257894D02*
X46369D01*
G01X46753Y1257913D02*
X52838D01*
G01X53118Y1258110D02*
X46506D01*
G01X52529Y1258484D02*
X46784D01*
G01X46506Y1258504D02*
X53118D01*
G01X46753Y1258701D02*
X52838D01*
G01X46753Y1261063D02*
X52838D01*
G01X53118Y1261260D02*
X46506D01*
G01Y1261654D02*
X53118D01*
G01X46753Y1261850D02*
X52838D01*
G01X46784Y1261909D02*
X52529D01*
G01X46369Y1262500D02*
X52956D01*
G01Y1262894D02*
X46369D01*
G01X52529Y1263484D02*
X46784D01*
G01X46753Y1264213D02*
X52838D01*
G01X53118Y1264409D02*
X46506D01*
G01Y1264803D02*
X53118D01*
G01X46753Y1265000D02*
X52838D01*
G01X46784Y1266909D02*
X52529D01*
G01X46753Y1267362D02*
X52838D01*
G01X46369Y1267500D02*
X52956D01*
G01X53118Y1267559D02*
X46506D01*
G01X52956Y1267894D02*
X46369D01*
G01X46506Y1267953D02*
X53118D01*
G01X46753Y1268150D02*
X52838D01*
G01X52529Y1268484D02*
X46784D01*
G01X46753Y1270512D02*
X52838D01*
G01X53118Y1270709D02*
X46506D01*
G01Y1271102D02*
X53118D01*
G01X46753Y1271299D02*
X52838D01*
G01X71181Y1271594D02*
X44488D01*
G01X44815Y1271909D02*
X50560D01*
G01X44401Y1272500D02*
X50987D01*
G01Y1272894D02*
X44401D01*
G01X50560Y1273484D02*
X44815D01*
G01X46753Y1273661D02*
X52838D01*
G01X53118Y1273858D02*
X46506D01*
G01X44488Y1273957D02*
X71181D01*
G01X46506Y1274252D02*
X53118D01*
G01X46753Y1274449D02*
X52838D01*
G01X46753Y1276811D02*
X52838D01*
G01X46784Y1276909D02*
X52529D01*
G01X53118Y1277008D02*
X46506D01*
G01Y1277402D02*
X53118D01*
G01X46369Y1277500D02*
X52956D01*
G01X46753Y1277598D02*
X52838D01*
G01X52956Y1277894D02*
X46369D01*
G01X52529Y1278484D02*
X46784D01*
G01X46753Y1279961D02*
X52838D01*
G01X53118Y1280157D02*
X46506D01*
G01Y1280551D02*
X53118D01*
G01X46753Y1280748D02*
X52838D01*
G01X46784Y1281909D02*
X52529D01*
G01X46369Y1282500D02*
X52956D01*
G01Y1282894D02*
X46369D01*
G01X46753Y1283110D02*
X52838D01*
G01X53118Y1283307D02*
X46506D01*
G01X52529Y1283484D02*
X46784D01*
G01X46506Y1283701D02*
X53118D01*
G01X46753Y1283898D02*
X52838D01*
G01X46753Y1258701D02*
X46626Y1258673D01*
X46537Y1258600D01*
X46506Y1258504D01*
G01X46753Y1261850D02*
X46626Y1261822D01*
X46537Y1261750D01*
X46506Y1261654D01*
G01X46753Y1265000D02*
X46626Y1264972D01*
X46537Y1264899D01*
X46506Y1264803D01*
G01X46753Y1268150D02*
X46626Y1268122D01*
X46537Y1268049D01*
X46506Y1267953D01*
G01X46753Y1274449D02*
X46626Y1274421D01*
X46537Y1274348D01*
X46506Y1274252D01*
G01X46753Y1277598D02*
X46626Y1277570D01*
X46537Y1277498D01*
X46506Y1277402D01*
G01X46753Y1280748D02*
X46626Y1280720D01*
X46537Y1280647D01*
X46506Y1280551D01*
G01X46753Y1283898D02*
X46626Y1283870D01*
X46537Y1283797D01*
X46506Y1283701D01*
G01X40551Y1248957D02*
Y1241791D01*
G01X40493Y1241342D02*
X40457Y1241018D01*
X40463Y1240777D01*
X40519Y1240641D01*
G01X40493Y1241340D02*
X40547Y1241718D01*
G01X40519Y1240641D02*
X40462Y1240781D01*
X40457Y1241021D01*
G01X94488Y1240610D02*
X40551D01*
G01Y1241791D02*
X66929D01*
G01X52112Y1327500D02*
X51839Y1326909D01*
G01X52112Y1322500D02*
X51839Y1321909D01*
G01X52112Y1317500D02*
X51839Y1316909D01*
G01X52112Y1307500D02*
X51839Y1306909D01*
G01X52597Y1326909D02*
X53021Y1327500D01*
G01X52529Y1321909D02*
X52956Y1322500D01*
G01X52529Y1316909D02*
X52956Y1317500D01*
G01X52529Y1306909D02*
X52956Y1307500D01*
G01X51351Y1336654D02*
X51389Y1336680D01*
X51417Y1336752D01*
X51428Y1336850D01*
G01Y1343543D02*
Y1343150D01*
G01Y1340394D02*
Y1340000D01*
G01Y1337244D02*
Y1336850D01*
G01Y1334094D02*
Y1333701D01*
G01Y1330945D02*
Y1330551D01*
G01Y1327795D02*
Y1327402D01*
G01Y1324646D02*
Y1324252D01*
G01Y1321496D02*
Y1321102D01*
G01Y1318346D02*
Y1317953D01*
G01Y1315197D02*
Y1314803D01*
G01Y1312047D02*
Y1311654D01*
G01Y1308898D02*
Y1308504D01*
G01Y1305748D02*
Y1305354D01*
G01X51872Y1345411D02*
Y1344427D01*
G01Y1342261D02*
Y1341277D01*
G01Y1335962D02*
Y1334978D01*
G01Y1339112D02*
Y1338128D01*
G01Y1332813D02*
Y1331828D01*
G01X51941Y1305354D02*
Y1305748D01*
G01Y1308504D02*
Y1308898D01*
G01Y1314803D02*
Y1315197D01*
G01Y1311654D02*
Y1312047D01*
G01Y1317953D02*
Y1318346D01*
G01Y1324252D02*
Y1324646D01*
G01Y1321102D02*
Y1321496D01*
G01Y1327402D02*
Y1327795D01*
G01Y1333701D02*
Y1334094D01*
G01Y1330551D02*
Y1330945D01*
G01Y1336850D02*
Y1337244D01*
G01Y1343150D02*
Y1343543D01*
G01Y1340000D02*
Y1340394D01*
G01X52112Y1327894D02*
Y1327500D01*
G01Y1322894D02*
Y1322500D01*
G01Y1317894D02*
Y1317500D01*
G01Y1307894D02*
Y1307500D01*
G01X52814Y1345411D02*
Y1344427D01*
G01Y1342261D02*
Y1341277D01*
G01Y1335962D02*
Y1334978D01*
G01Y1339112D02*
Y1338128D01*
G01Y1332813D02*
Y1331828D01*
G01X52956Y1322894D02*
Y1322500D01*
G01Y1317894D02*
Y1317500D01*
G01Y1307894D02*
Y1307500D01*
G01X53021Y1327894D02*
Y1327500D01*
G01X53118Y1305354D02*
Y1305748D01*
G01Y1308504D02*
Y1308898D01*
G01Y1314803D02*
Y1315197D01*
G01Y1311654D02*
Y1312047D01*
G01Y1317953D02*
Y1318346D01*
G01Y1324252D02*
Y1324646D01*
G01Y1321102D02*
Y1321496D01*
G01Y1327402D02*
Y1327795D01*
G01Y1333701D02*
Y1334094D01*
G01Y1330551D02*
Y1330945D01*
G01Y1336850D02*
Y1337244D01*
G01Y1343150D02*
Y1343543D01*
G01Y1340000D02*
Y1340394D01*
G01X51872Y1344427D02*
X51869Y1344389D01*
X51861Y1344352D01*
X51847Y1344318D01*
X51829Y1344288D01*
X51807Y1344263D01*
X51781Y1344245D01*
X51754Y1344234D01*
X51724Y1344230D01*
G01X51872Y1341277D02*
X51869Y1341239D01*
X51861Y1341202D01*
X51847Y1341169D01*
X51829Y1341138D01*
X51807Y1341114D01*
X51781Y1341096D01*
X51754Y1341084D01*
X51724Y1341080D01*
G01X51872Y1338128D02*
X51869Y1338089D01*
X51861Y1338053D01*
X51847Y1338019D01*
X51829Y1337989D01*
X51807Y1337964D01*
X51781Y1337946D01*
X51754Y1337935D01*
X51724Y1337931D01*
G01X51872Y1334978D02*
X51869Y1334940D01*
X51861Y1334903D01*
X51847Y1334869D01*
X51829Y1334839D01*
X51807Y1334815D01*
X51781Y1334796D01*
X51754Y1334785D01*
X51724Y1334781D01*
G01X51872Y1331828D02*
X51869Y1331790D01*
X51861Y1331754D01*
X51847Y1331720D01*
X51829Y1331689D01*
X51807Y1331665D01*
X51781Y1331647D01*
X51754Y1331635D01*
X51724Y1331631D01*
G01X51428Y1343150D02*
X51417Y1343051D01*
X51389Y1342979D01*
X51351Y1342953D01*
G01X51428Y1340000D02*
X51417Y1339902D01*
X51389Y1339830D01*
X51351Y1339803D01*
G01X51428Y1333701D02*
X51417Y1333602D01*
X51389Y1333530D01*
X51351Y1333504D01*
G01X51428Y1330551D02*
X51417Y1330453D01*
X51389Y1330381D01*
X51351Y1330354D01*
G01X51428Y1327402D02*
X51417Y1327303D01*
X51389Y1327231D01*
X51351Y1327205D01*
G01X51428Y1324252D02*
X51417Y1324154D01*
X51389Y1324081D01*
X51351Y1324055D01*
G01X51428Y1321102D02*
X51417Y1321004D01*
X51389Y1320932D01*
X51351Y1320906D01*
G01X51428Y1317953D02*
X51417Y1317854D01*
X51389Y1317782D01*
X51351Y1317756D01*
G01X51428Y1314803D02*
X51417Y1314705D01*
X51389Y1314633D01*
X51351Y1314606D01*
G01X51428Y1311654D02*
X51417Y1311555D01*
X51389Y1311483D01*
X51351Y1311457D01*
G01X51428Y1308504D02*
X51417Y1308406D01*
X51389Y1308333D01*
X51351Y1308307D01*
G01X51941Y1305748D02*
X51938Y1305786D01*
X51930Y1305823D01*
X51917Y1305857D01*
X51900Y1305887D01*
X51879Y1305911D01*
X51856Y1305930D01*
X51830Y1305941D01*
X51802Y1305945D01*
G01X51941Y1308898D02*
X51938Y1308936D01*
X51930Y1308972D01*
X51917Y1309006D01*
X51900Y1309037D01*
X51879Y1309061D01*
X51856Y1309079D01*
X51830Y1309091D01*
X51802Y1309094D01*
G01X51941Y1312047D02*
X51938Y1312085D01*
X51930Y1312122D01*
X51917Y1312156D01*
X51900Y1312186D01*
X51879Y1312211D01*
X51856Y1312229D01*
X51830Y1312240D01*
X51802Y1312244D01*
G01X51941Y1315197D02*
X51938Y1315235D01*
X51930Y1315272D01*
X51917Y1315306D01*
X51900Y1315336D01*
X51879Y1315360D01*
X51856Y1315378D01*
X51830Y1315390D01*
X51802Y1315394D01*
G01X51941Y1318346D02*
X51938Y1318385D01*
X51930Y1318421D01*
X51917Y1318455D01*
X51900Y1318485D01*
X51879Y1318510D01*
X51856Y1318528D01*
X51830Y1318539D01*
X51802Y1318543D01*
G01X51941Y1321496D02*
X51938Y1321534D01*
X51930Y1321571D01*
X51917Y1321605D01*
X51900Y1321635D01*
X51879Y1321659D01*
X51856Y1321678D01*
X51830Y1321689D01*
X51802Y1321693D01*
G01X51941Y1324646D02*
X51938Y1324684D01*
X51930Y1324720D01*
X51917Y1324754D01*
X51900Y1324785D01*
X51879Y1324809D01*
X51856Y1324827D01*
X51830Y1324839D01*
X51802Y1324843D01*
G01X51941Y1327795D02*
X51938Y1327833D01*
X51930Y1327870D01*
X51917Y1327904D01*
X51900Y1327934D01*
X51879Y1327959D01*
X51856Y1327977D01*
X51830Y1327988D01*
X51802Y1327992D01*
G01X51941Y1330945D02*
X51938Y1330983D01*
X51930Y1331020D01*
X51917Y1331054D01*
X51900Y1331084D01*
X51879Y1331108D01*
X51856Y1331126D01*
X51830Y1331138D01*
X51802Y1331142D01*
G01X51941Y1334094D02*
X51938Y1334133D01*
X51930Y1334169D01*
X51917Y1334203D01*
X51900Y1334233D01*
X51879Y1334258D01*
X51856Y1334276D01*
X51830Y1334287D01*
X51802Y1334291D01*
G01X51941Y1337244D02*
X51938Y1337282D01*
X51930Y1337319D01*
X51917Y1337353D01*
X51900Y1337383D01*
X51879Y1337407D01*
X51856Y1337426D01*
X51830Y1337437D01*
X51802Y1337441D01*
G01X51941Y1340394D02*
X51938Y1340432D01*
X51930Y1340469D01*
X51917Y1340502D01*
X51900Y1340533D01*
X51879Y1340557D01*
X51856Y1340575D01*
X51830Y1340587D01*
X51802Y1340591D01*
G01X51941Y1343543D02*
X51938Y1343581D01*
X51930Y1343618D01*
X51917Y1343652D01*
X51900Y1343682D01*
X51879Y1343707D01*
X51856Y1343725D01*
X51830Y1343736D01*
X51802Y1343740D01*
G01X69213Y1328091D02*
Y1311752D01*
G01Y1330453D02*
Y1349941D01*
G01X74409Y1330551D02*
Y1349843D01*
G01X74724D02*
Y1330551D01*
G01X74803Y1314272D02*
Y1311122D01*
G01X75170Y1340591D02*
Y1339803D01*
G01Y1343740D02*
Y1342953D01*
G01Y1337441D02*
Y1336654D01*
G01Y1331142D02*
Y1330354D01*
G01Y1334291D02*
Y1333504D01*
G01Y1327992D02*
Y1327205D01*
G01Y1321693D02*
Y1320906D01*
G01Y1324843D02*
Y1324055D01*
G01Y1318543D02*
Y1317756D01*
G01Y1312244D02*
Y1311457D01*
G01Y1315394D02*
Y1314606D01*
G01Y1309094D02*
Y1308307D01*
G01X75197Y1340591D02*
Y1339803D01*
G01Y1343740D02*
Y1342953D01*
G01Y1337441D02*
Y1336654D01*
G01Y1331142D02*
Y1330354D01*
G01Y1334291D02*
Y1333504D01*
G01Y1327992D02*
Y1327205D01*
G01Y1321693D02*
Y1320906D01*
G01Y1324843D02*
Y1324055D01*
G01Y1318543D02*
Y1317756D01*
G01Y1312244D02*
Y1311457D01*
G01Y1315394D02*
Y1314606D01*
G01Y1309094D02*
Y1308307D01*
G01X75237Y1346102D02*
Y1343740D01*
G01Y1342953D02*
Y1340591D01*
G01Y1336654D02*
Y1334291D01*
G01Y1339803D02*
Y1337441D01*
G01Y1333504D02*
Y1331142D01*
G01X75512Y1349843D02*
Y1330551D01*
G01X75573Y1340591D02*
Y1339803D01*
G01Y1343740D02*
Y1342953D01*
G01Y1337441D02*
Y1336654D01*
G01Y1331142D02*
Y1330354D01*
G01Y1334291D02*
Y1333504D01*
G01Y1327992D02*
Y1327205D01*
G01Y1321693D02*
Y1320906D01*
G01Y1324843D02*
Y1324055D01*
G01Y1318543D02*
Y1317756D01*
G01Y1312244D02*
Y1311457D01*
G01Y1315394D02*
Y1314606D01*
G01Y1309094D02*
Y1308307D01*
G01X75787Y1328484D02*
Y1326909D01*
G01Y1323484D02*
Y1321909D01*
G01Y1318484D02*
Y1316909D01*
G01Y1314272D02*
Y1311122D01*
G01Y1308484D02*
Y1306909D01*
G01X76012Y1330551D02*
Y1349843D01*
G01X76222Y1349350D02*
Y1331043D01*
G01X76772Y1329272D02*
Y1326122D01*
G01Y1324272D02*
Y1321122D01*
G01Y1319272D02*
Y1316122D01*
G01Y1313484D02*
Y1311909D01*
G01Y1309272D02*
Y1306122D01*
G01X76929Y1349843D02*
Y1330551D01*
G01X77206Y1345512D02*
Y1344331D01*
G01Y1342362D02*
Y1341181D01*
G01Y1336063D02*
Y1334882D01*
G01Y1339213D02*
Y1338031D01*
G01Y1332913D02*
Y1331732D01*
G01X77756Y1329272D02*
Y1326122D01*
G01Y1324272D02*
Y1321122D01*
G01Y1319272D02*
Y1316122D01*
G01Y1309272D02*
Y1306122D01*
G01X78740Y1328484D02*
Y1326909D01*
G01Y1323484D02*
Y1321909D01*
G01Y1318484D02*
Y1316909D01*
G01Y1308484D02*
Y1306909D01*
G01X78935Y1308307D02*
Y1309094D01*
G01Y1311457D02*
Y1312244D01*
G01Y1314606D02*
Y1315394D01*
G01Y1317756D02*
Y1318543D01*
G01Y1320906D02*
Y1321693D01*
G01Y1324055D02*
Y1324843D01*
G01Y1327205D02*
Y1327992D01*
G01Y1330354D02*
Y1331142D01*
G01Y1333504D02*
Y1334291D01*
G01Y1336654D02*
Y1337441D01*
G01Y1339803D02*
Y1340591D01*
G01Y1342953D02*
Y1343740D01*
G01X79921Y1311909D02*
Y1313484D01*
G01X80285Y1349843D02*
Y1330551D01*
G01X80337Y1334370D02*
Y1336575D01*
G01Y1343819D02*
Y1346024D01*
G01X80356Y1331732D02*
Y1332913D01*
G01Y1334882D02*
Y1336063D01*
G01Y1338031D02*
Y1339213D01*
G01Y1341181D02*
Y1342362D01*
G01Y1344331D02*
Y1345512D01*
G01X80763Y1343819D02*
Y1336575D01*
G01Y1334370D02*
Y1330551D01*
G01X80919Y1308307D02*
Y1309094D01*
G01Y1311457D02*
Y1312244D01*
G01Y1314606D02*
Y1315394D01*
G01Y1317756D02*
Y1318543D01*
G01Y1320906D02*
Y1321693D01*
G01Y1324055D02*
Y1324843D01*
G01Y1327205D02*
Y1327992D01*
G01Y1330354D02*
Y1331142D01*
G01Y1333504D02*
Y1334291D01*
G01Y1336654D02*
Y1337441D01*
G01Y1339803D02*
Y1340591D01*
G01Y1342953D02*
Y1343740D01*
G01X81890Y1306909D02*
Y1308484D01*
G01Y1316909D02*
Y1318484D01*
G01Y1321909D02*
Y1323484D01*
G01Y1326909D02*
Y1328484D01*
G01X82220Y1346024D02*
Y1343819D01*
G01Y1336575D02*
Y1334370D01*
G01X82570Y1340591D02*
Y1339803D01*
G01Y1343740D02*
Y1342953D01*
G01Y1337441D02*
Y1336654D01*
G01Y1331142D02*
Y1330354D01*
G01Y1334291D02*
Y1333504D01*
G01Y1327992D02*
Y1327205D01*
G01Y1321693D02*
Y1320906D01*
G01Y1324843D02*
Y1324055D01*
G01Y1318543D02*
Y1317756D01*
G01Y1312244D02*
Y1311457D01*
G01Y1315394D02*
Y1314606D01*
G01Y1309094D02*
Y1308307D01*
G01X84298Y1305945D02*
Y1308307D01*
G01Y1309094D02*
Y1311457D01*
G01Y1312244D02*
Y1314606D01*
G01Y1315394D02*
Y1317756D01*
G01Y1318543D02*
Y1320906D01*
G01Y1321693D02*
Y1324055D01*
G01Y1324843D02*
Y1327205D01*
G01Y1327992D02*
Y1330354D01*
G01Y1331142D02*
Y1333504D01*
G01Y1334291D02*
Y1336654D01*
G01Y1337441D02*
Y1339803D01*
G01Y1340591D02*
Y1342953D01*
G01Y1343740D02*
Y1346102D01*
G01X85237Y1340591D02*
Y1339803D01*
G01Y1343740D02*
Y1342953D01*
G01Y1337441D02*
Y1336654D01*
G01Y1331142D02*
Y1330354D01*
G01Y1334291D02*
Y1333504D01*
G01Y1327992D02*
Y1327205D01*
G01Y1321693D02*
Y1320906D01*
G01Y1324843D02*
Y1324055D01*
G01Y1318543D02*
Y1317756D01*
G01Y1312244D02*
Y1311457D01*
G01Y1315394D02*
Y1314606D01*
G01Y1309094D02*
Y1308307D01*
G01X85384Y1340591D02*
Y1339803D01*
G01Y1343740D02*
Y1342953D01*
G01Y1337441D02*
Y1336654D01*
G01Y1331142D02*
Y1330354D01*
G01Y1334291D02*
Y1333504D01*
G01Y1327992D02*
Y1327205D01*
G01Y1321693D02*
Y1320906D01*
G01Y1324843D02*
Y1324055D01*
G01Y1318543D02*
Y1317756D01*
G01Y1312244D02*
Y1311457D01*
G01Y1315394D02*
Y1314606D01*
G01Y1309094D02*
Y1308307D01*
G01X86976Y1340591D02*
Y1339803D01*
G01Y1343740D02*
Y1342953D01*
G01Y1337441D02*
Y1336654D01*
G01Y1331142D02*
Y1330354D01*
G01Y1334291D02*
Y1333504D01*
G01Y1327992D02*
Y1327205D01*
G01Y1321693D02*
Y1320906D01*
G01Y1324843D02*
Y1324055D01*
G01Y1318543D02*
Y1317756D01*
G01Y1312244D02*
Y1311457D01*
G01Y1315394D02*
Y1314606D01*
G01Y1309094D02*
Y1308307D01*
G01X87918D02*
Y1309094D01*
G01Y1311457D02*
Y1312244D01*
G01Y1314606D02*
Y1315394D01*
G01Y1317756D02*
Y1318543D01*
G01Y1320906D02*
Y1321693D01*
G01Y1324055D02*
Y1324843D01*
G01Y1327205D02*
Y1327992D01*
G01Y1330354D02*
Y1331142D01*
G01Y1333504D02*
Y1334291D01*
G01Y1336654D02*
Y1337441D01*
G01Y1339803D02*
Y1340591D01*
G01Y1342953D02*
Y1343740D01*
G01X90754Y1308307D02*
Y1309094D01*
G01Y1311457D02*
Y1312244D01*
G01Y1314606D02*
Y1315394D01*
G01Y1317756D02*
Y1318543D01*
G01Y1320906D02*
Y1321693D01*
G01Y1324055D02*
Y1324843D01*
G01Y1327205D02*
Y1327992D01*
G01Y1330354D02*
Y1331142D01*
G01Y1333504D02*
Y1334291D01*
G01Y1336654D02*
Y1337441D01*
G01Y1339803D02*
Y1340591D01*
G01Y1342953D02*
Y1343740D01*
G01X90943Y1340591D02*
Y1339803D01*
G01Y1343740D02*
Y1342953D01*
G01Y1337441D02*
Y1336654D01*
G01Y1331142D02*
Y1330354D01*
G01Y1334291D02*
Y1333504D01*
G01Y1327992D02*
Y1327205D01*
G01Y1321693D02*
Y1320906D01*
G01Y1324843D02*
Y1324055D01*
G01Y1318543D02*
Y1317756D01*
G01Y1312244D02*
Y1311457D01*
G01Y1315394D02*
Y1314606D01*
G01Y1309094D02*
Y1308307D01*
G01X92717Y1340591D02*
Y1339803D01*
G01Y1343740D02*
Y1342953D01*
G01Y1337441D02*
Y1336654D01*
G01Y1331142D02*
Y1330354D01*
G01Y1334291D02*
Y1333504D01*
G01Y1327992D02*
Y1327205D01*
G01Y1321693D02*
Y1320906D01*
G01Y1324843D02*
Y1324055D01*
G01Y1318543D02*
Y1317756D01*
G01Y1312244D02*
Y1311457D01*
G01Y1315394D02*
Y1314606D01*
G01Y1309094D02*
Y1308307D01*
G01X51839Y1308484D02*
X52112Y1307894D01*
G01X51839Y1318484D02*
X52112Y1317894D01*
G01X51839Y1323484D02*
X52112Y1322894D01*
G01X51839Y1328484D02*
X52112Y1327894D01*
G01X52529Y1308484D02*
X52956Y1307894D01*
G01X52529Y1318484D02*
X52956Y1317894D01*
G01X52529Y1323484D02*
X52956Y1322894D01*
G01X52597Y1328484D02*
X53021Y1327894D01*
G01X51351Y1305945D02*
X51389Y1305919D01*
X51417Y1305846D01*
X51428Y1305748D01*
G01X51351Y1309094D02*
X51389Y1309068D01*
X51417Y1308996D01*
X51428Y1308898D01*
G01X51351Y1312244D02*
X51389Y1312218D01*
X51417Y1312146D01*
X51428Y1312047D01*
G01X51351Y1315394D02*
X51389Y1315367D01*
X51417Y1315295D01*
X51428Y1315197D01*
G01X51351Y1318543D02*
X51389Y1318517D01*
X51417Y1318445D01*
X51428Y1318346D01*
G01X51351Y1321693D02*
X51389Y1321667D01*
X51417Y1321594D01*
X51428Y1321496D01*
G01X51351Y1324843D02*
X51389Y1324816D01*
X51417Y1324744D01*
X51428Y1324646D01*
G01X51351Y1327992D02*
X51389Y1327966D01*
X51417Y1327894D01*
X51428Y1327795D01*
G01X51351Y1331142D02*
X51389Y1331115D01*
X51417Y1331043D01*
X51428Y1330945D01*
G01X51351Y1334291D02*
X51389Y1334265D01*
X51417Y1334193D01*
X51428Y1334094D01*
G01X51351Y1337441D02*
X51389Y1337415D01*
X51417Y1337343D01*
X51428Y1337244D01*
G01X51351Y1340591D02*
X51389Y1340564D01*
X51417Y1340492D01*
X51428Y1340394D01*
G01X51351Y1343740D02*
X51389Y1343714D01*
X51417Y1343642D01*
X51428Y1343543D01*
G01X85237Y1305945D02*
X73228D01*
G01X85384D02*
X92717D01*
G01X77756Y1306122D02*
X76772D01*
G01X77756Y1306319D02*
X76772D01*
G01X77756Y1306713D02*
X76772D01*
G01X74724Y1306909D02*
X81890D01*
G01X92717Y1308307D02*
X85384D01*
G01X85237D02*
X73228D01*
G01X74724Y1308484D02*
X81890D01*
G01X77756Y1308681D02*
X76772D01*
G01X77756Y1309075D02*
X76772D01*
G01X85237Y1309094D02*
X73228D01*
G01X85384D02*
X92717D01*
G01X77756Y1309272D02*
X76772D01*
G01X74331Y1310492D02*
X73228D01*
G01X75787Y1311122D02*
X74803D01*
G01X75787Y1311319D02*
X74803D01*
G01X92717Y1311457D02*
X85384D01*
G01X85237D02*
X73228D01*
G01X75787Y1311713D02*
X74803D01*
G01X74331Y1311909D02*
X79921D01*
G01X85237Y1312244D02*
X73228D01*
G01X85384D02*
X92717D01*
G01X51724Y1333009D02*
X51753Y1333006D01*
X51781Y1332994D01*
X51806Y1332977D01*
X51829Y1332952D01*
X51847Y1332922D01*
X51861Y1332888D01*
X51869Y1332852D01*
X51872Y1332813D01*
G01X51724Y1336159D02*
X51753Y1336156D01*
X51781Y1336144D01*
X51806Y1336126D01*
X51829Y1336102D01*
X51847Y1336072D01*
X51861Y1336038D01*
X51869Y1336001D01*
X51872Y1335962D01*
G01X51724Y1339309D02*
X51753Y1339305D01*
X51781Y1339294D01*
X51806Y1339276D01*
X51829Y1339251D01*
X51847Y1339221D01*
X51861Y1339187D01*
X51869Y1339151D01*
X51872Y1339112D01*
G01X51724Y1342458D02*
X51753Y1342455D01*
X51781Y1342443D01*
X51806Y1342426D01*
X51829Y1342401D01*
X51847Y1342371D01*
X51861Y1342337D01*
X51869Y1342300D01*
X51872Y1342261D01*
G01X51802Y1308307D02*
X51829Y1308311D01*
X51855Y1308322D01*
X51879Y1308340D01*
X51900Y1308365D01*
X51917Y1308394D01*
X51930Y1308428D01*
X51938Y1308465D01*
X51941Y1308504D01*
G01X51802Y1311457D02*
X51829Y1311460D01*
X51855Y1311471D01*
X51879Y1311489D01*
X51900Y1311514D01*
X51917Y1311544D01*
X51930Y1311578D01*
X51938Y1311615D01*
X51941Y1311654D01*
G01X51802Y1314606D02*
X51829Y1314610D01*
X51855Y1314621D01*
X51879Y1314639D01*
X51900Y1314664D01*
X51917Y1314694D01*
X51930Y1314728D01*
X51938Y1314764D01*
X51941Y1314803D01*
G01X51802Y1317756D02*
X51829Y1317759D01*
X51855Y1317770D01*
X51879Y1317789D01*
X51900Y1317813D01*
X51917Y1317843D01*
X51930Y1317877D01*
X51938Y1317914D01*
X51941Y1317953D01*
G01X51802Y1320906D02*
X51829Y1320909D01*
X51855Y1320920D01*
X51879Y1320938D01*
X51900Y1320963D01*
X51917Y1320993D01*
X51930Y1321027D01*
X51938Y1321063D01*
X51941Y1321102D01*
G01X51802Y1324055D02*
X51829Y1324059D01*
X51855Y1324070D01*
X51879Y1324088D01*
X51900Y1324113D01*
X51917Y1324143D01*
X51930Y1324176D01*
X51938Y1324213D01*
X51941Y1324252D01*
G01X51802Y1327205D02*
X51829Y1327208D01*
X51855Y1327219D01*
X51879Y1327237D01*
X51900Y1327262D01*
X51917Y1327292D01*
X51930Y1327326D01*
X51938Y1327363D01*
X51941Y1327402D01*
G01X74331Y1313484D02*
X79921D01*
G01X75787Y1313681D02*
X74803D01*
G01X75787Y1314075D02*
X74803D01*
G01X75787Y1314272D02*
X74803D01*
G01X92717Y1314606D02*
X85384D01*
G01X85237D02*
X73228D01*
G01Y1314902D02*
X74331D01*
G01X85237Y1315394D02*
X73228D01*
G01X85384D02*
X92717D01*
G01X77756Y1316122D02*
X76772D01*
G01X77756Y1316319D02*
X76772D01*
G01X77756Y1316713D02*
X76772D01*
G01X74724Y1316909D02*
X81890D01*
G01X92717Y1317756D02*
X85384D01*
G01X85237D02*
X73228D01*
G01X74724Y1318484D02*
X81890D01*
G01X85237Y1318543D02*
X73228D01*
G01X85384D02*
X92717D01*
G01X77756Y1318681D02*
X76772D01*
G01X77756Y1319075D02*
X76772D01*
G01X77756Y1319272D02*
X76772D01*
G01X92717Y1320906D02*
X85384D01*
G01X85237D02*
X73228D01*
G01X77756Y1321122D02*
X76772D01*
G01X77756Y1321319D02*
X76772D01*
G01X85237Y1321693D02*
X73228D01*
G01X85384D02*
X92717D01*
G01X77756Y1321713D02*
X76772D01*
G01X74724Y1321909D02*
X81890D01*
G01X74724Y1323484D02*
X81890D01*
G01X77756Y1323681D02*
X76772D01*
G01X92717Y1324055D02*
X85384D01*
G01X85237D02*
X73228D01*
G01X77756Y1324075D02*
X76772D01*
G01X77756Y1324272D02*
X76772D01*
G01X85237Y1324843D02*
X73228D01*
G01X85384D02*
X92717D01*
G01X77756Y1326122D02*
X76772D01*
G01X77756Y1326319D02*
X76772D01*
G01X77756Y1326713D02*
X76772D01*
G01X74724Y1326909D02*
X81890D01*
G01X92717Y1327205D02*
X85384D01*
G01X85237D02*
X73228D01*
G01X85237Y1327992D02*
X73228D01*
G01X85384D02*
X92717D01*
G01X74724Y1328484D02*
X81890D01*
G01X77756Y1328681D02*
X76772D01*
G01X77756Y1329075D02*
X76772D01*
G01X77756Y1329272D02*
X76772D01*
G01X92717Y1330354D02*
X85384D01*
G01X85237D02*
X73228D01*
G01X74331Y1330433D02*
X73228D01*
G01Y1330551D02*
X80763D01*
G01X76222Y1331043D02*
X78346D01*
G01X85237Y1331142D02*
X73228D01*
G01X85384D02*
X92717D01*
G01X76222Y1331339D02*
X75237D01*
G01X76222Y1331535D02*
X75237D01*
G01X74331Y1331732D02*
X80356D01*
G01X74331Y1332913D02*
X80356D01*
G01X76222Y1333110D02*
X75237D01*
G01X76222Y1333307D02*
X75237D01*
G01X92717Y1333504D02*
X85384D01*
G01X85237D02*
X73228D01*
G01X85237Y1334291D02*
X73228D01*
G01X85384D02*
X92717D01*
G01X82220Y1334370D02*
X80337D01*
G01X76222Y1334488D02*
X75237D01*
G01X76222Y1334685D02*
X75237D01*
G01X74331Y1334882D02*
X80356D01*
G01X74331Y1336063D02*
X80356D01*
G01X76222Y1336260D02*
X75237D01*
G01X76222Y1336457D02*
X75237D01*
G01X82220Y1336575D02*
X80337D01*
G01X92717Y1336654D02*
X85384D01*
G01X85237D02*
X73228D01*
G01X85237Y1337441D02*
X73228D01*
G01X85384D02*
X92717D01*
G01X76222Y1337638D02*
X75237D01*
G01X76222Y1337835D02*
X75237D01*
G01X74331Y1338031D02*
X80356D01*
G01X74331Y1339213D02*
X80356D01*
G01X76222Y1339409D02*
X75237D01*
G01X76222Y1339606D02*
X75237D01*
G01X92717Y1339803D02*
X85384D01*
G01X85237D02*
X73228D01*
G01X85237Y1340591D02*
X73228D01*
G01X85384D02*
X92717D01*
G01X76222Y1340787D02*
X75237D01*
G01X76222Y1340984D02*
X75237D01*
G01X74331Y1341181D02*
X80356D01*
G01X74331Y1342362D02*
X80356D01*
G01X76222Y1342559D02*
X75237D01*
G01X76222Y1342756D02*
X75237D01*
G01X92717Y1342953D02*
X85384D01*
G01X85237D02*
X73228D01*
G01X85237Y1343740D02*
X73228D01*
G01X85384D02*
X92717D01*
G01X82220Y1343819D02*
X80337D01*
G01X76222Y1343937D02*
X75237D01*
G01X76222Y1344134D02*
X75237D01*
G01X74331Y1344331D02*
X80356D01*
G01X51802Y1330354D02*
X51829Y1330358D01*
X51855Y1330369D01*
X51879Y1330387D01*
X51900Y1330412D01*
X51917Y1330442D01*
X51930Y1330476D01*
X51938Y1330512D01*
X51941Y1330551D01*
G01X51802Y1333504D02*
X51829Y1333507D01*
X51855Y1333519D01*
X51879Y1333537D01*
X51900Y1333561D01*
X51917Y1333591D01*
X51930Y1333625D01*
X51938Y1333662D01*
X51941Y1333701D01*
G01X51802Y1336654D02*
X51829Y1336657D01*
X51855Y1336668D01*
X51879Y1336686D01*
X51900Y1336711D01*
X51917Y1336741D01*
X51930Y1336775D01*
X51938Y1336811D01*
X51941Y1336850D01*
G01X51802Y1339803D02*
X51829Y1339807D01*
X51855Y1339818D01*
X51879Y1339836D01*
X51900Y1339861D01*
X51917Y1339891D01*
X51930Y1339924D01*
X51938Y1339961D01*
X51941Y1340000D01*
G01X51802Y1342953D02*
X51829Y1342956D01*
X51855Y1342967D01*
X51879Y1342985D01*
X51900Y1343010D01*
X51917Y1343040D01*
X51930Y1343074D01*
X51938Y1343111D01*
X51941Y1343150D01*
G01X74331Y1328878D02*
G03X74724Y1328484I394J0D01*
G01Y1326909D02*
G03X74331Y1326516I0J-393D01*
G01Y1318878D02*
G03X74724Y1318484I394J0D01*
G01Y1316909D02*
G03X74331Y1316516I0J-393D01*
G01Y1323878D02*
G03X74724Y1323484I394J0D01*
G01Y1321909D02*
G03X74331Y1321516I0J-393D01*
G01Y1308878D02*
G03X74724Y1308484I394J0D01*
G01Y1306909D02*
G03X74331Y1306516I0J-393D01*
G01X50143Y1312500D02*
X49871Y1311909D01*
G01X46684Y1328484D02*
X46548Y1328288D01*
X46413Y1328091D01*
X46279Y1327894D01*
G01X46784Y1323484D02*
X46644Y1323288D01*
X46506Y1323091D01*
X46369Y1322894D01*
G01X46784Y1318484D02*
X46644Y1318288D01*
X46506Y1318091D01*
X46369Y1317894D01*
G01X44815Y1313484D02*
X44676Y1313288D01*
X44538Y1313091D01*
X44401Y1312894D01*
G01X46784Y1308484D02*
X46644Y1308288D01*
X46506Y1308091D01*
X46369Y1307894D01*
G01X50560Y1311909D02*
X50987Y1312500D01*
G01X42520Y1328465D02*
X44488Y1330433D01*
G01X43531Y1323996D02*
Y1329476D01*
G01X43701Y1351122D02*
Y1329272D01*
G01X44401Y1312500D02*
Y1312894D01*
G01X46279Y1327500D02*
Y1327894D01*
G01X46369Y1307500D02*
Y1307894D01*
G01Y1317500D02*
Y1317894D01*
G01Y1322500D02*
Y1322894D01*
G01X46496Y1331828D02*
Y1332813D01*
G01Y1334978D02*
Y1335962D01*
G01Y1338128D02*
Y1339112D01*
G01Y1341277D02*
Y1342261D01*
G01Y1344427D02*
Y1345411D01*
G01X46506Y1343543D02*
Y1343150D01*
G01Y1340394D02*
Y1340000D01*
G01Y1337244D02*
Y1336850D01*
G01Y1334094D02*
Y1333701D01*
G01Y1330945D02*
Y1330551D01*
G01Y1327795D02*
Y1327402D01*
G01Y1324646D02*
Y1324252D01*
G01Y1321496D02*
Y1321102D01*
G01Y1318346D02*
Y1317953D01*
G01Y1315197D02*
Y1314803D01*
G01Y1312047D02*
Y1311654D01*
G01Y1308898D02*
Y1308504D01*
G01Y1305748D02*
Y1305354D01*
G01X48989Y1329272D02*
Y1330453D01*
G01X49019Y1312500D02*
Y1312894D01*
G01X50143D02*
Y1312500D01*
G01X50720Y1345411D02*
Y1344427D01*
G01Y1342261D02*
Y1341277D01*
G01Y1335962D02*
Y1334978D01*
G01Y1339112D02*
Y1338128D01*
G01Y1332813D02*
Y1331828D01*
G01X50987Y1312894D02*
Y1312500D01*
G01Y1307500D02*
Y1307894D01*
G01Y1317500D02*
Y1317894D01*
G01Y1322500D02*
Y1322894D01*
G01Y1327500D02*
Y1327894D01*
G01X50720Y1344427D02*
Y1344389D01*
X50718Y1344352D01*
X50715Y1344318D01*
X50711Y1344288D01*
X50706Y1344263D01*
X50700Y1344245D01*
X50694Y1344234D01*
X50687Y1344230D01*
G01X50720Y1341277D02*
Y1341239D01*
X50718Y1341202D01*
X50715Y1341169D01*
X50711Y1341138D01*
X50706Y1341114D01*
X50700Y1341096D01*
X50694Y1341084D01*
X50687Y1341080D01*
G01X50720Y1338128D02*
Y1338089D01*
X50718Y1338053D01*
X50715Y1338019D01*
X50711Y1337989D01*
X50706Y1337964D01*
X50700Y1337946D01*
X50694Y1337935D01*
X50687Y1337931D01*
G01X50720Y1334978D02*
Y1334940D01*
X50718Y1334903D01*
X50715Y1334869D01*
X50711Y1334839D01*
X50706Y1334815D01*
X50700Y1334796D01*
X50694Y1334785D01*
X50687Y1334781D01*
G01X50720Y1331828D02*
Y1331790D01*
X50718Y1331754D01*
X50715Y1331720D01*
X50711Y1331689D01*
X50706Y1331665D01*
X50700Y1331647D01*
X50694Y1331635D01*
X50687Y1331631D01*
G01X50987Y1327500D02*
X50909Y1326909D01*
G01X49019Y1312500D02*
X48941Y1311909D01*
G01X50987Y1322500D02*
X50909Y1321909D01*
G01X50987Y1317500D02*
X50909Y1316909D01*
G01X50987Y1307500D02*
X50909Y1306909D01*
G01X49019Y1312894D02*
X48941Y1313484D01*
G01X50987Y1307894D02*
X50909Y1308484D01*
G01X50987Y1317894D02*
X50909Y1318484D01*
G01X50987Y1322894D02*
X50909Y1323484D01*
G01X50987Y1327894D02*
X50909Y1328484D01*
G01X46496Y1331828D02*
X46530Y1331730D01*
X46618Y1331659D01*
X46744Y1331631D01*
G01X46496Y1334978D02*
X46530Y1334879D01*
X46618Y1334808D01*
X46744Y1334781D01*
G01X46496Y1338128D02*
X46530Y1338029D01*
X46618Y1337958D01*
X46744Y1337931D01*
G01X46496Y1341277D02*
X46530Y1341178D01*
X46618Y1341107D01*
X46744Y1341080D01*
G01X46496Y1344427D02*
X46530Y1344328D01*
X46618Y1344257D01*
X46744Y1344230D01*
G01X46506Y1308504D02*
X46538Y1308407D01*
X46626Y1308335D01*
X46753Y1308307D01*
G01X46506Y1311654D02*
X46538Y1311556D01*
X46626Y1311484D01*
X46753Y1311457D01*
G01X46506Y1314803D02*
X46538Y1314706D01*
X46626Y1314634D01*
X46753Y1314606D01*
G01X46506Y1317953D02*
X46538Y1317856D01*
X46626Y1317783D01*
X46753Y1317756D01*
G01X46506Y1321102D02*
X46538Y1321005D01*
X46626Y1320933D01*
X46753Y1320906D01*
G01X46506Y1324252D02*
X46538Y1324155D01*
X46626Y1324083D01*
X46753Y1324055D01*
G01X46506Y1327402D02*
X46538Y1327304D01*
X46626Y1327232D01*
X46753Y1327205D01*
G01X46506Y1330551D02*
X46538Y1330454D01*
X46626Y1330382D01*
X46753Y1330354D01*
G01X46506Y1333701D02*
X46538Y1333604D01*
X46626Y1333531D01*
X46753Y1333504D01*
G01X46506Y1336850D02*
X46538Y1336753D01*
X46626Y1336681D01*
X46753Y1336654D01*
G01X46506Y1340000D02*
X46538Y1339903D01*
X46626Y1339831D01*
X46753Y1339803D01*
G01X46506Y1343150D02*
X46538Y1343052D01*
X46626Y1342980D01*
X46753Y1342953D01*
G01X49871Y1313484D02*
X50143Y1312894D01*
G01X50560Y1313484D02*
X50987Y1312894D01*
G01X46369Y1307500D02*
X46506Y1307302D01*
X46644Y1307106D01*
X46784Y1306909D01*
G01X44401Y1312500D02*
X44538Y1312302D01*
X44676Y1312106D01*
X44815Y1311909D01*
G01X46369Y1317500D02*
X46506Y1317302D01*
X46644Y1317106D01*
X46784Y1316909D01*
G01X46369Y1322500D02*
X46506Y1322302D01*
X46644Y1322106D01*
X46784Y1321909D01*
G01X46279Y1327500D02*
X46413Y1327302D01*
X46548Y1327106D01*
X46684Y1326909D01*
G01X50687Y1333009D02*
X50694Y1333006D01*
X50700Y1332994D01*
X50706Y1332977D01*
X50711Y1332952D01*
X50715Y1332922D01*
X50718Y1332888D01*
X50720Y1332852D01*
Y1332813D01*
G01X50687Y1336159D02*
X50694Y1336156D01*
X50700Y1336144D01*
X50706Y1336126D01*
X50711Y1336102D01*
X50715Y1336072D01*
X50718Y1336038D01*
X50720Y1336001D01*
Y1335962D01*
G01X50687Y1339309D02*
X50694Y1339305D01*
X50700Y1339294D01*
X50706Y1339276D01*
X50711Y1339251D01*
X50715Y1339221D01*
X50718Y1339187D01*
X50720Y1339151D01*
Y1339112D01*
G01X50687Y1342458D02*
X50694Y1342455D01*
X50700Y1342443D01*
X50706Y1342426D01*
X50711Y1342401D01*
X50715Y1342371D01*
X50718Y1342337D01*
X50720Y1342300D01*
Y1342261D01*
G01X53118Y1305354D02*
X46506D01*
G01Y1305748D02*
X53118D01*
G01X46753Y1305945D02*
X52838D01*
G01X46784Y1306909D02*
X52529D01*
G01X46369Y1307500D02*
X52956D01*
G01Y1307894D02*
X46369D01*
G01X46753Y1308307D02*
X52838D01*
G01X52529Y1308484D02*
X46784D01*
G01X53118Y1308504D02*
X46506D01*
G01Y1308898D02*
X53118D01*
G01X46753Y1309094D02*
X52838D01*
G01X71181Y1309390D02*
X44488D01*
G01X46753Y1311457D02*
X52838D01*
G01X53118Y1311654D02*
X46506D01*
G01X44488Y1311752D02*
X71181D01*
G01X44815Y1311909D02*
X50560D01*
G01X46506Y1312047D02*
X53118D01*
G01X46753Y1312244D02*
X52838D01*
G01X44401Y1312500D02*
X50987D01*
G01Y1312894D02*
X44401D01*
G01X50560Y1313484D02*
X44815D01*
G01X46753Y1314606D02*
X52838D01*
G01X53118Y1314803D02*
X46506D01*
G01Y1315197D02*
X53118D01*
G01X46753Y1315394D02*
X52838D01*
G01X46784Y1316909D02*
X52529D01*
G01X46369Y1317500D02*
X52956D01*
G01X46753Y1317756D02*
X52838D01*
G01X52956Y1317894D02*
X46369D01*
G01X53118Y1317953D02*
X46506D01*
G01Y1318346D02*
X53118D01*
G01X52529Y1318484D02*
X46784D01*
G01X46753Y1318543D02*
X52838D01*
G01X46753Y1320906D02*
X52838D01*
G01X53118Y1321102D02*
X46506D01*
G01Y1321496D02*
X53118D01*
G01X46753Y1321693D02*
X52838D01*
G01X46784Y1321909D02*
X52529D01*
G01X46369Y1322500D02*
X52956D01*
G01Y1322894D02*
X46369D01*
G01X52529Y1323484D02*
X46784D01*
G01X43531Y1323996D02*
X62992D01*
G01X46753Y1324055D02*
X52838D01*
G01X53118Y1324252D02*
X46506D01*
G01Y1324646D02*
X53118D01*
G01X46753Y1324843D02*
X52838D01*
G01X52597Y1326909D02*
X46684D01*
G01X46753Y1327205D02*
X52838D01*
G01X53118Y1327402D02*
X46506D01*
G01X46279Y1327500D02*
X53021D01*
G01X46506Y1327795D02*
X53118D01*
G01X53021Y1327894D02*
X46279D01*
G01X46753Y1327992D02*
X52838D01*
G01X71181Y1328091D02*
X44488D01*
G01X52597Y1328484D02*
X46684D01*
G01X48989Y1329272D02*
X42520D01*
G01X46753Y1330354D02*
X52838D01*
G01X62992Y1330433D02*
X44488D01*
G01X48989Y1330453D02*
X71181D01*
G01X53118Y1330551D02*
X46506D01*
G01Y1330945D02*
X53118D01*
G01X46753Y1331142D02*
X52838D01*
G01X52552Y1331631D02*
X46744D01*
G01X46496Y1331828D02*
X52814D01*
G01Y1332813D02*
X46496D01*
G01X52552Y1333009D02*
X46744D01*
G01X46753Y1333504D02*
X52838D01*
G01X53118Y1333701D02*
X46506D01*
G01Y1334094D02*
X53118D01*
G01X46753Y1334291D02*
X52838D01*
G01X52552Y1334781D02*
X46744D01*
G01X46496Y1334978D02*
X52814D01*
G01Y1335962D02*
X46496D01*
G01X52552Y1336159D02*
X46744D01*
G01X46753Y1336654D02*
X52838D01*
G01X53118Y1336850D02*
X46506D01*
G01Y1337244D02*
X53118D01*
G01X46753Y1337441D02*
X52838D01*
G01X52552Y1337931D02*
X46744D01*
G01X46496Y1338128D02*
X52814D01*
G01Y1339112D02*
X46496D01*
G01X52552Y1339309D02*
X46744D01*
G01X46753Y1339803D02*
X52838D01*
G01X53118Y1340000D02*
X46506D01*
G01Y1340394D02*
X53118D01*
G01X46753Y1340591D02*
X52838D01*
G01X52552Y1341080D02*
X46744D01*
G01X46496Y1341277D02*
X52814D01*
G01Y1342261D02*
X46496D01*
G01X52552Y1342458D02*
X46744D01*
G01X46753Y1342953D02*
X52838D01*
G01X53118Y1343150D02*
X46506D01*
G01Y1343543D02*
X53118D01*
G01X46753Y1343740D02*
X52838D01*
G01X52552Y1344230D02*
X46744D01*
G01X46496Y1344427D02*
X52814D01*
G01X46753Y1305945D02*
X46626Y1305917D01*
X46537Y1305844D01*
X46506Y1305748D01*
G01X46753Y1309094D02*
X46626Y1309067D01*
X46537Y1308994D01*
X46506Y1308898D01*
G01X46753Y1312244D02*
X46626Y1312216D01*
X46537Y1312143D01*
X46506Y1312047D01*
G01X46753Y1315394D02*
X46626Y1315366D01*
X46537Y1315293D01*
X46506Y1315197D01*
G01X46753Y1318543D02*
X46626Y1318515D01*
X46537Y1318443D01*
X46506Y1318346D01*
G01X46753Y1321693D02*
X46626Y1321665D01*
X46537Y1321592D01*
X46506Y1321496D01*
G01X46753Y1324843D02*
X46626Y1324815D01*
X46537Y1324742D01*
X46506Y1324646D01*
G01X46753Y1327992D02*
X46626Y1327964D01*
X46537Y1327891D01*
X46506Y1327795D01*
G01X46753Y1331142D02*
X46626Y1331114D01*
X46537Y1331041D01*
X46506Y1330945D01*
G01X46753Y1334291D02*
X46626Y1334263D01*
X46537Y1334191D01*
X46506Y1334094D01*
G01X46753Y1337441D02*
X46626Y1337413D01*
X46537Y1337340D01*
X46506Y1337244D01*
G01X46753Y1340591D02*
X46626Y1340563D01*
X46537Y1340490D01*
X46506Y1340394D01*
G01X46753Y1343740D02*
X46626Y1343712D01*
X46537Y1343639D01*
X46506Y1343543D01*
G01X46744Y1333009D02*
X46617Y1332982D01*
X46528Y1332909D01*
X46496Y1332813D01*
G01X46744Y1336159D02*
X46617Y1336132D01*
X46528Y1336059D01*
X46496Y1335962D01*
G01X46744Y1339309D02*
X46617Y1339281D01*
X46528Y1339209D01*
X46496Y1339112D01*
G01X46744Y1342458D02*
X46617Y1342431D01*
X46528Y1342358D01*
X46496Y1342261D01*
G01X52112Y1357500D02*
X51839Y1356909D01*
G01X52112Y1352500D02*
X51839Y1351909D01*
G01X52597D02*
X53021Y1352500D01*
G01X52529Y1356909D02*
X52956Y1357500D01*
G01X51351Y1355551D02*
X51389Y1355578D01*
X51417Y1355650D01*
X51428Y1355748D01*
G01X51351Y1352402D02*
X51389Y1352428D01*
X51417Y1352500D01*
X51428Y1352598D01*
G01Y1356142D02*
Y1355748D01*
G01Y1349843D02*
Y1349449D01*
G01Y1352992D02*
Y1352598D01*
G01Y1346693D02*
Y1346299D01*
G01X51872Y1348561D02*
Y1347576D01*
G01X51941Y1346299D02*
Y1346693D01*
G01Y1349449D02*
Y1349843D01*
G01Y1352598D02*
Y1352992D01*
G01Y1355748D02*
Y1356142D01*
G01X52112Y1352894D02*
Y1352500D01*
G01X52814Y1348561D02*
Y1347576D01*
G01X53021Y1352894D02*
Y1352500D01*
G01X53118Y1346299D02*
Y1346693D01*
G01Y1349449D02*
Y1349843D01*
G01Y1352598D02*
Y1352992D01*
G01Y1355748D02*
Y1356142D01*
G01X51872Y1347576D02*
X51869Y1347538D01*
X51861Y1347502D01*
X51847Y1347468D01*
X51829Y1347437D01*
X51807Y1347413D01*
X51781Y1347395D01*
X51754Y1347383D01*
X51724Y1347380D01*
G01X51428Y1349449D02*
X51417Y1349350D01*
X51389Y1349278D01*
X51351Y1349252D01*
G01X51428Y1346299D02*
X51417Y1346201D01*
X51389Y1346129D01*
X51351Y1346102D01*
G01X51941Y1346693D02*
X51938Y1346731D01*
X51930Y1346768D01*
X51917Y1346802D01*
X51900Y1346832D01*
X51879Y1346856D01*
X51856Y1346874D01*
X51830Y1346886D01*
X51802Y1346890D01*
G01X51941Y1349843D02*
X51938Y1349881D01*
X51930Y1349917D01*
X51917Y1349951D01*
X51900Y1349981D01*
X51879Y1350006D01*
X51856Y1350024D01*
X51830Y1350035D01*
X51802Y1350039D01*
G01X51941Y1352992D02*
X51938Y1353030D01*
X51930Y1353067D01*
X51917Y1353101D01*
X51900Y1353131D01*
X51879Y1353156D01*
X51856Y1353174D01*
X51830Y1353185D01*
X51802Y1353189D01*
G01X51941Y1356142D02*
X51938Y1356180D01*
X51930Y1356217D01*
X51917Y1356250D01*
X51900Y1356281D01*
X51879Y1356305D01*
X51856Y1356323D01*
X51830Y1356335D01*
X51802Y1356339D01*
G01X69213Y1352303D02*
Y1367539D01*
G01X75170Y1356339D02*
Y1355551D01*
G01Y1350039D02*
Y1349252D01*
G01Y1353189D02*
Y1352402D01*
G01Y1346890D02*
Y1346102D01*
G01X75197Y1356339D02*
Y1355551D01*
G01Y1350039D02*
Y1349252D01*
G01Y1353189D02*
Y1352402D01*
G01Y1346890D02*
Y1346102D01*
G01X75237Y1349252D02*
Y1346890D01*
G01X75573Y1356339D02*
Y1355551D01*
G01Y1350039D02*
Y1349252D01*
G01Y1353189D02*
Y1352402D01*
G01Y1346890D02*
Y1346102D01*
G01X75787Y1358484D02*
Y1356909D01*
G01Y1353484D02*
Y1351909D01*
G01X76772Y1359272D02*
Y1356122D01*
G01Y1354272D02*
Y1351122D01*
G01X77206Y1348661D02*
Y1347480D01*
G01X77756Y1359272D02*
Y1356122D01*
G01Y1354272D02*
Y1351122D01*
G01X78740Y1358484D02*
Y1356909D01*
G01Y1353484D02*
Y1351909D01*
G01X78935Y1346102D02*
Y1346890D01*
G01Y1349252D02*
Y1350039D01*
G01Y1352402D02*
Y1353189D01*
G01Y1355551D02*
Y1356339D01*
G01X80356Y1347480D02*
Y1348661D01*
G01X80763Y1349843D02*
Y1346024D01*
G01X80919Y1346102D02*
Y1346890D01*
G01Y1349252D02*
Y1350039D01*
G01Y1352402D02*
Y1353189D01*
G01Y1355551D02*
Y1356339D01*
G01X81890Y1351909D02*
Y1353484D01*
G01Y1356909D02*
Y1358484D01*
G01X82570Y1356339D02*
Y1355551D01*
G01Y1350039D02*
Y1349252D01*
G01Y1353189D02*
Y1352402D01*
G01Y1346890D02*
Y1346102D01*
G01X84298Y1346890D02*
Y1349252D01*
G01Y1350039D02*
Y1352402D01*
G01Y1353189D02*
Y1355551D01*
G01Y1356339D02*
Y1358701D01*
G01X85237Y1356339D02*
Y1355551D01*
G01Y1350039D02*
Y1349252D01*
G01Y1353189D02*
Y1352402D01*
G01Y1346890D02*
Y1346102D01*
G01X85384Y1356339D02*
Y1355551D01*
G01Y1350039D02*
Y1349252D01*
G01Y1353189D02*
Y1352402D01*
G01Y1346890D02*
Y1346102D01*
G01X86976Y1356339D02*
Y1355551D01*
G01Y1350039D02*
Y1349252D01*
G01Y1353189D02*
Y1352402D01*
G01Y1346890D02*
Y1346102D01*
G01X87918D02*
Y1346890D01*
G01Y1349252D02*
Y1350039D01*
G01Y1352402D02*
Y1353189D01*
G01Y1355551D02*
Y1356339D01*
G01X90754Y1346102D02*
Y1346890D01*
G01Y1349252D02*
Y1350039D01*
G01Y1352402D02*
Y1353189D01*
G01Y1355551D02*
Y1356339D01*
G01X90943D02*
Y1355551D01*
G01Y1350039D02*
Y1349252D01*
G01Y1353189D02*
Y1352402D01*
G01Y1346890D02*
Y1346102D01*
G01X92717Y1356339D02*
Y1355551D01*
G01Y1350039D02*
Y1349252D01*
G01Y1353189D02*
Y1352402D01*
G01Y1346890D02*
Y1346102D01*
G01X51839Y1353484D02*
X52112Y1352894D01*
G01X52597Y1353484D02*
X53021Y1352894D01*
G01X51351Y1346890D02*
X51389Y1346863D01*
X51417Y1346791D01*
X51428Y1346693D01*
G01X51351Y1350039D02*
X51389Y1350013D01*
X51417Y1349941D01*
X51428Y1349843D01*
G01X51351Y1353189D02*
X51389Y1353163D01*
X51417Y1353091D01*
X51428Y1352992D01*
G01X51351Y1356339D02*
X51389Y1356312D01*
X51417Y1356240D01*
X51428Y1356142D01*
G01X51724Y1345608D02*
X51753Y1345604D01*
X51781Y1345593D01*
X51806Y1345575D01*
X51829Y1345550D01*
X51847Y1345520D01*
X51861Y1345487D01*
X51869Y1345450D01*
X51872Y1345411D01*
G01X51724Y1348757D02*
X51753Y1348754D01*
X51781Y1348743D01*
X51806Y1348725D01*
X51829Y1348700D01*
X51847Y1348670D01*
X51861Y1348636D01*
X51869Y1348600D01*
X51872Y1348561D01*
G01X74331Y1345512D02*
X80356D01*
G01X76222Y1345709D02*
X75237D01*
G01X76222Y1345906D02*
X75237D01*
G01X82220Y1346024D02*
X80337D01*
G01X92717Y1346102D02*
X85384D01*
G01X85237D02*
X73228D01*
G01X85237Y1346890D02*
X73228D01*
G01X85384D02*
X92717D01*
G01X76222Y1347087D02*
X75237D01*
G01X76222Y1347283D02*
X75237D01*
G01X74331Y1347480D02*
X80356D01*
G01X74331Y1348661D02*
X80356D01*
G01X76222Y1348858D02*
X75237D01*
G01X76222Y1349055D02*
X75237D01*
G01X92717Y1349252D02*
X85384D01*
G01X85237D02*
X73228D01*
G01X78346Y1349350D02*
X76222D01*
G01X73228Y1349843D02*
X80763D01*
G01X74331Y1349961D02*
X73228D01*
G01X85237Y1350039D02*
X73228D01*
G01X85384D02*
X92717D01*
G01X77756Y1351122D02*
X76772D01*
G01X77756Y1351319D02*
X76772D01*
G01X77756Y1351713D02*
X76772D01*
G01X74724Y1351909D02*
X81890D01*
G01X92717Y1352402D02*
X85384D01*
G01X85237D02*
X73228D01*
G01X85237Y1353189D02*
X73228D01*
G01X85384D02*
X92717D01*
G01X74724Y1353484D02*
X81890D01*
G01X77756Y1353681D02*
X76772D01*
G01X77756Y1354075D02*
X76772D01*
G01X77756Y1354272D02*
X76772D01*
G01X92717Y1355551D02*
X85384D01*
G01X85237D02*
X73228D01*
G01X77756Y1356122D02*
X76772D01*
G01X77756Y1356319D02*
X76772D01*
G01X85237Y1356339D02*
X73228D01*
G01X85384D02*
X92717D01*
G01X77756Y1356713D02*
X76772D01*
G01X74724Y1356909D02*
X81890D01*
G01X51802Y1346102D02*
X51829Y1346106D01*
X51855Y1346117D01*
X51879Y1346135D01*
X51900Y1346160D01*
X51917Y1346190D01*
X51930Y1346224D01*
X51938Y1346260D01*
X51941Y1346299D01*
G01X51802Y1349252D02*
X51829Y1349256D01*
X51855Y1349267D01*
X51879Y1349285D01*
X51900Y1349309D01*
X51917Y1349339D01*
X51930Y1349373D01*
X51938Y1349410D01*
X51941Y1349449D01*
G01X51802Y1352402D02*
X51829Y1352405D01*
X51855Y1352416D01*
X51879Y1352434D01*
X51900Y1352459D01*
X51917Y1352489D01*
X51930Y1352523D01*
X51938Y1352559D01*
X51941Y1352598D01*
G01X51802Y1355551D02*
X51829Y1355555D01*
X51855Y1355566D01*
X51879Y1355584D01*
X51900Y1355609D01*
X51917Y1355639D01*
X51930Y1355672D01*
X51938Y1355709D01*
X51941Y1355748D01*
G01X74724Y1356909D02*
G03X74331Y1356516I0J-393D01*
G01Y1353878D02*
G03X74724Y1353484I394J0D01*
G01Y1351909D02*
G03X74331Y1351516I0J-393D01*
G01X46684Y1353484D02*
X46548Y1353288D01*
X46413Y1353091D01*
X46279Y1352894D01*
G01X43531Y1350918D02*
Y1356299D01*
G01X43701D02*
Y1387303D01*
G01X46279Y1352500D02*
Y1352894D01*
G01X46496Y1347576D02*
Y1348561D01*
G01X46506Y1356142D02*
Y1355748D01*
G01Y1349843D02*
Y1349449D01*
G01Y1352992D02*
Y1352598D01*
G01Y1346693D02*
Y1346299D01*
G01X48989Y1349941D02*
Y1351122D01*
G01X50720Y1348561D02*
Y1347576D01*
G01X50987Y1352500D02*
Y1352894D01*
G01X50720Y1347576D02*
Y1347538D01*
X50718Y1347502D01*
X50715Y1347468D01*
X50711Y1347437D01*
X50706Y1347413D01*
X50700Y1347395D01*
X50694Y1347383D01*
X50687Y1347380D01*
G01X50987Y1357500D02*
X50909Y1356909D01*
G01X50987Y1352500D02*
X50909Y1351909D01*
G01X50987Y1352894D02*
X50909Y1353484D01*
G01X46496Y1347576D02*
X46530Y1347478D01*
X46618Y1347407D01*
X46744Y1347380D01*
G01X46506Y1346299D02*
X46538Y1346202D01*
X46626Y1346130D01*
X46753Y1346102D01*
G01X46506Y1349449D02*
X46538Y1349352D01*
X46626Y1349280D01*
X46753Y1349252D01*
G01X46506Y1352598D02*
X46538Y1352501D01*
X46626Y1352429D01*
X46753Y1352402D01*
G01X46506Y1355748D02*
X46538Y1355651D01*
X46626Y1355579D01*
X46753Y1355551D01*
G01X46369Y1357500D02*
X46506Y1357302D01*
X46644Y1357106D01*
X46784Y1356909D01*
G01X46279Y1352500D02*
X46413Y1352302D01*
X46548Y1352106D01*
X46684Y1351909D01*
G01X44488Y1349961D02*
X42520Y1351929D01*
G01X50687Y1345608D02*
X50694Y1345604D01*
X50700Y1345593D01*
X50706Y1345575D01*
X50711Y1345550D01*
X50715Y1345520D01*
X50718Y1345487D01*
X50720Y1345450D01*
Y1345411D01*
G01X50687Y1348757D02*
X50694Y1348754D01*
X50700Y1348743D01*
X50706Y1348725D01*
X50711Y1348700D01*
X50715Y1348670D01*
X50718Y1348636D01*
X50720Y1348600D01*
Y1348561D01*
G01X52814Y1345411D02*
X46496D01*
G01X52552Y1345608D02*
X46744D01*
G01X46753Y1346102D02*
X52838D01*
G01X53118Y1346299D02*
X46506D01*
G01Y1346693D02*
X53118D01*
G01X46753Y1346890D02*
X52838D01*
G01X52552Y1347380D02*
X46744D01*
G01X46496Y1347576D02*
X52814D01*
G01Y1348561D02*
X46496D01*
G01X52552Y1348757D02*
X46744D01*
G01X46753Y1349252D02*
X52838D01*
G01X53118Y1349449D02*
X46506D01*
G01Y1349843D02*
X53118D01*
G01X71181Y1349941D02*
X48989D01*
G01X62992Y1349961D02*
X44488D01*
G01X46753Y1350039D02*
X52838D01*
G01X42520Y1351122D02*
X48989D01*
G01X52597Y1351909D02*
X46684D01*
G01X44488Y1352303D02*
X71181D01*
G01X46753Y1352402D02*
X52838D01*
G01X46279Y1352500D02*
X53021D01*
G01X53118Y1352598D02*
X46506D01*
G01X53021Y1352894D02*
X46279D01*
G01X46506Y1352992D02*
X53118D01*
G01X46753Y1353189D02*
X52838D01*
G01X52597Y1353484D02*
X46684D01*
G01X46753Y1355551D02*
X52838D01*
G01X53118Y1355748D02*
X46506D01*
G01Y1356142D02*
X53118D01*
G01X62992Y1356299D02*
X43531D01*
G01X46753Y1356339D02*
X52838D01*
G01X46784Y1356909D02*
X52529D01*
G01X46753Y1346890D02*
X46626Y1346862D01*
X46537Y1346789D01*
X46506Y1346693D01*
G01X46753Y1350039D02*
X46626Y1350011D01*
X46537Y1349939D01*
X46506Y1349843D01*
G01X46753Y1353189D02*
X46626Y1353161D01*
X46537Y1353088D01*
X46506Y1352992D01*
G01X46753Y1356339D02*
X46626Y1356311D01*
X46537Y1356238D01*
X46506Y1356142D01*
G01X46744Y1345608D02*
X46617Y1345581D01*
X46528Y1345508D01*
X46496Y1345411D01*
G01X46744Y1348757D02*
X46617Y1348730D01*
X46528Y1348657D01*
X46496Y1348561D01*
G01X52112Y1302500D02*
X51839Y1301909D01*
G01X52112Y1297500D02*
X51839Y1296909D01*
G01X52112Y1292500D02*
X51839Y1291909D01*
G01X52112Y1287500D02*
X51839Y1286909D01*
G01X52529Y1301909D02*
X52956Y1302500D01*
G01X52529Y1296909D02*
X52956Y1297500D01*
G01X52529Y1291909D02*
X52956Y1292500D01*
G01X52529Y1286909D02*
X52956Y1287500D01*
G01X51428Y1302598D02*
Y1302205D01*
G01Y1299449D02*
Y1299055D01*
G01Y1296299D02*
Y1295906D01*
G01Y1293150D02*
Y1292756D01*
G01Y1290000D02*
Y1289606D01*
G01Y1286850D02*
Y1286457D01*
G01X51941D02*
Y1286850D01*
G01Y1289606D02*
Y1290000D01*
G01Y1295906D02*
Y1296299D01*
G01Y1292756D02*
Y1293150D01*
G01Y1299055D02*
Y1299449D01*
G01Y1302205D02*
Y1302598D01*
G01X52112Y1302894D02*
Y1302500D01*
G01Y1297894D02*
Y1297500D01*
G01Y1292894D02*
Y1292500D01*
G01Y1287894D02*
Y1287500D01*
G01X52956Y1302894D02*
Y1302500D01*
G01Y1297894D02*
Y1297500D01*
G01Y1292894D02*
Y1292500D01*
G01Y1287894D02*
Y1287500D01*
G01X53118Y1286457D02*
Y1286850D01*
G01Y1289606D02*
Y1290000D01*
G01Y1295906D02*
Y1296299D01*
G01Y1292756D02*
Y1293150D01*
G01Y1299055D02*
Y1299449D01*
G01Y1302205D02*
Y1302598D01*
G01X51428Y1305354D02*
X51417Y1305256D01*
X51389Y1305184D01*
X51351Y1305157D01*
G01X51428Y1302205D02*
X51417Y1302106D01*
X51389Y1302034D01*
X51351Y1302008D01*
G01X51428Y1299055D02*
X51417Y1298957D01*
X51389Y1298885D01*
X51351Y1298858D01*
G01X51428Y1295906D02*
X51417Y1295807D01*
X51389Y1295735D01*
X51351Y1295709D01*
G01X51428Y1292756D02*
X51417Y1292657D01*
X51389Y1292585D01*
X51351Y1292559D01*
G01X51428Y1289606D02*
X51417Y1289508D01*
X51389Y1289436D01*
X51351Y1289409D01*
G01X51428Y1286457D02*
X51417Y1286358D01*
X51389Y1286286D01*
X51351Y1286260D01*
G01X51941Y1286850D02*
X51938Y1286889D01*
X51930Y1286925D01*
X51917Y1286959D01*
X51900Y1286989D01*
X51879Y1287014D01*
X51856Y1287032D01*
X51830Y1287043D01*
X51802Y1287047D01*
G01X51941Y1290000D02*
X51938Y1290038D01*
X51930Y1290075D01*
X51917Y1290109D01*
X51900Y1290139D01*
X51879Y1290163D01*
X51856Y1290181D01*
X51830Y1290193D01*
X51802Y1290197D01*
G01X51941Y1293150D02*
X51938Y1293188D01*
X51930Y1293224D01*
X51917Y1293258D01*
X51900Y1293289D01*
X51879Y1293313D01*
X51856Y1293331D01*
X51830Y1293343D01*
X51802Y1293346D01*
G01X51941Y1296299D02*
X51938Y1296337D01*
X51930Y1296374D01*
X51917Y1296408D01*
X51900Y1296438D01*
X51879Y1296463D01*
X51856Y1296481D01*
X51830Y1296492D01*
X51802Y1296496D01*
G01X51941Y1299449D02*
X51938Y1299487D01*
X51930Y1299524D01*
X51917Y1299557D01*
X51900Y1299588D01*
X51879Y1299612D01*
X51856Y1299630D01*
X51830Y1299642D01*
X51802Y1299646D01*
G01X51941Y1302598D02*
X51938Y1302637D01*
X51930Y1302673D01*
X51917Y1302707D01*
X51900Y1302737D01*
X51879Y1302762D01*
X51856Y1302780D01*
X51830Y1302791D01*
X51802Y1302795D01*
G01X69213Y1309390D02*
Y1292854D01*
G01X75170Y1302795D02*
Y1302008D01*
G01Y1305945D02*
Y1305157D01*
G01Y1299646D02*
Y1298858D01*
G01Y1293346D02*
Y1292559D01*
G01Y1296496D02*
Y1295709D01*
G01Y1290197D02*
Y1289409D01*
G01Y1287047D02*
Y1286260D01*
G01X75197Y1302795D02*
Y1302008D01*
G01Y1305945D02*
Y1305157D01*
G01Y1299646D02*
Y1298858D01*
G01Y1293346D02*
Y1292559D01*
G01Y1296496D02*
Y1295709D01*
G01Y1290197D02*
Y1289409D01*
G01Y1287047D02*
Y1286260D01*
G01X75573Y1302795D02*
Y1302008D01*
G01Y1305945D02*
Y1305157D01*
G01Y1299646D02*
Y1298858D01*
G01Y1293346D02*
Y1292559D01*
G01Y1296496D02*
Y1295709D01*
G01Y1290197D02*
Y1289409D01*
G01Y1287047D02*
Y1286260D01*
G01X75787Y1303484D02*
Y1301909D01*
G01Y1298484D02*
Y1296909D01*
G01Y1293484D02*
Y1291909D01*
G01Y1288484D02*
Y1286909D01*
G01X76772Y1304272D02*
Y1301122D01*
G01Y1299272D02*
Y1296122D01*
G01Y1294272D02*
Y1291122D01*
G01Y1289272D02*
Y1286122D01*
G01X77756Y1304272D02*
Y1301122D01*
G01Y1299272D02*
Y1296122D01*
G01Y1294272D02*
Y1291122D01*
G01Y1289272D02*
Y1286122D01*
G01X78740Y1303484D02*
Y1301909D01*
G01Y1298484D02*
Y1296909D01*
G01Y1293484D02*
Y1291909D01*
G01Y1288484D02*
Y1286909D01*
G01X78935Y1286260D02*
Y1287047D01*
G01Y1289409D02*
Y1290197D01*
G01Y1292559D02*
Y1293346D01*
G01Y1295709D02*
Y1296496D01*
G01Y1298858D02*
Y1299646D01*
G01Y1302008D02*
Y1302795D01*
G01Y1305157D02*
Y1305945D01*
G01X80919Y1286260D02*
Y1287047D01*
G01Y1289409D02*
Y1290197D01*
G01Y1292559D02*
Y1293346D01*
G01Y1295709D02*
Y1296496D01*
G01Y1298858D02*
Y1299646D01*
G01Y1302008D02*
Y1302795D01*
G01Y1305157D02*
Y1305945D01*
G01X81890Y1286909D02*
Y1288484D01*
G01Y1291909D02*
Y1293484D01*
G01Y1296909D02*
Y1298484D01*
G01Y1301909D02*
Y1303484D01*
G01X82570Y1302795D02*
Y1302008D01*
G01Y1305945D02*
Y1305157D01*
G01Y1299646D02*
Y1298858D01*
G01Y1293346D02*
Y1292559D01*
G01Y1296496D02*
Y1295709D01*
G01Y1290197D02*
Y1289409D01*
G01Y1287047D02*
Y1286260D01*
G01X84298Y1287047D02*
Y1289409D01*
G01Y1290197D02*
Y1292559D01*
G01Y1293346D02*
Y1295709D01*
G01Y1296496D02*
Y1298858D01*
G01Y1299646D02*
Y1302008D01*
G01Y1302795D02*
Y1305157D01*
G01X85237Y1302795D02*
Y1302008D01*
G01Y1305945D02*
Y1305157D01*
G01Y1299646D02*
Y1298858D01*
G01Y1293346D02*
Y1292559D01*
G01Y1296496D02*
Y1295709D01*
G01Y1290197D02*
Y1289409D01*
G01Y1287047D02*
Y1286260D01*
G01X85384Y1302795D02*
Y1302008D01*
G01Y1305945D02*
Y1305157D01*
G01Y1299646D02*
Y1298858D01*
G01Y1293346D02*
Y1292559D01*
G01Y1296496D02*
Y1295709D01*
G01Y1290197D02*
Y1289409D01*
G01Y1287047D02*
Y1286260D01*
G01X86976Y1302795D02*
Y1302008D01*
G01Y1305945D02*
Y1305157D01*
G01Y1299646D02*
Y1298858D01*
G01Y1293346D02*
Y1292559D01*
G01Y1296496D02*
Y1295709D01*
G01Y1290197D02*
Y1289409D01*
G01Y1287047D02*
Y1286260D01*
G01X87918D02*
Y1287047D01*
G01Y1289409D02*
Y1290197D01*
G01Y1292559D02*
Y1293346D01*
G01Y1295709D02*
Y1296496D01*
G01Y1298858D02*
Y1299646D01*
G01Y1302008D02*
Y1302795D01*
G01Y1305157D02*
Y1305945D01*
G01X90754Y1286260D02*
Y1287047D01*
G01Y1289409D02*
Y1290197D01*
G01Y1292559D02*
Y1293346D01*
G01Y1295709D02*
Y1296496D01*
G01Y1298858D02*
Y1299646D01*
G01Y1302008D02*
Y1302795D01*
G01Y1305157D02*
Y1305945D01*
G01X90943Y1302795D02*
Y1302008D01*
G01Y1305945D02*
Y1305157D01*
G01Y1299646D02*
Y1298858D01*
G01Y1293346D02*
Y1292559D01*
G01Y1296496D02*
Y1295709D01*
G01Y1290197D02*
Y1289409D01*
G01Y1287047D02*
Y1286260D01*
G01X92717Y1302795D02*
Y1302008D01*
G01Y1305945D02*
Y1305157D01*
G01Y1299646D02*
Y1298858D01*
G01Y1293346D02*
Y1292559D01*
G01Y1296496D02*
Y1295709D01*
G01Y1290197D02*
Y1289409D01*
G01Y1287047D02*
Y1286260D01*
G01X51839Y1288484D02*
X52112Y1287894D01*
G01X51839Y1293484D02*
X52112Y1292894D01*
G01X51839Y1298484D02*
X52112Y1297894D01*
G01X51839Y1303484D02*
X52112Y1302894D01*
G01X52529Y1288484D02*
X52956Y1287894D01*
G01X52529Y1293484D02*
X52956Y1292894D01*
G01X52529Y1298484D02*
X52956Y1297894D01*
G01X52529Y1303484D02*
X52956Y1302894D01*
G01X51351Y1287047D02*
X51389Y1287021D01*
X51417Y1286949D01*
X51428Y1286850D01*
G01X51351Y1290197D02*
X51389Y1290170D01*
X51417Y1290098D01*
X51428Y1290000D01*
G01X51351Y1293346D02*
X51389Y1293320D01*
X51417Y1293248D01*
X51428Y1293150D01*
G01X51351Y1296496D02*
X51389Y1296470D01*
X51417Y1296398D01*
X51428Y1296299D01*
G01X51351Y1299646D02*
X51389Y1299619D01*
X51417Y1299547D01*
X51428Y1299449D01*
G01X51351Y1302795D02*
X51389Y1302769D01*
X51417Y1302697D01*
X51428Y1302598D01*
G01X77756Y1286122D02*
X76772D01*
G01X92717Y1286260D02*
X85384D01*
G01X85237D02*
X73228D01*
G01X77756Y1286319D02*
X76772D01*
G01X77756Y1286713D02*
X76772D01*
G01X74724Y1286909D02*
X81890D01*
G01X85237Y1287047D02*
X73228D01*
G01X85384D02*
X92717D01*
G01X74724Y1288484D02*
X81890D01*
G01X77756Y1288681D02*
X76772D01*
G01X77756Y1289075D02*
X76772D01*
G01X77756Y1289272D02*
X76772D01*
G01X92717Y1289409D02*
X85384D01*
G01X85237D02*
X73228D01*
G01X85237Y1290197D02*
X73228D01*
G01X85384D02*
X92717D01*
G01X77756Y1291122D02*
X76772D01*
G01X77756Y1291319D02*
X76772D01*
G01X77756Y1291713D02*
X76772D01*
G01X74724Y1291909D02*
X81890D01*
G01X92717Y1292559D02*
X85384D01*
G01X85237D02*
X73228D01*
G01X85237Y1293346D02*
X73228D01*
G01X85384D02*
X92717D01*
G01X74724Y1293484D02*
X81890D01*
G01X77756Y1293681D02*
X76772D01*
G01X77756Y1294075D02*
X76772D01*
G01X77756Y1294272D02*
X76772D01*
G01X92717Y1295709D02*
X85384D01*
G01X85237D02*
X73228D01*
G01X77756Y1296122D02*
X76772D01*
G01X77756Y1296319D02*
X76772D01*
G01X85237Y1296496D02*
X73228D01*
G01X85384D02*
X92717D01*
G01X77756Y1296713D02*
X76772D01*
G01X74724Y1296909D02*
X81890D01*
G01X74724Y1298484D02*
X81890D01*
G01X77756Y1298681D02*
X76772D01*
G01X92717Y1298858D02*
X85384D01*
G01X85237D02*
X73228D01*
G01X77756Y1299075D02*
X76772D01*
G01X77756Y1299272D02*
X76772D01*
G01X85237Y1299646D02*
X73228D01*
G01X85384D02*
X92717D01*
G01X77756Y1301122D02*
X76772D01*
G01X77756Y1301319D02*
X76772D01*
G01X77756Y1301713D02*
X76772D01*
G01X74724Y1301909D02*
X81890D01*
G01X92717Y1302008D02*
X85384D01*
G01X85237D02*
X73228D01*
G01X85237Y1302795D02*
X73228D01*
G01X85384D02*
X92717D01*
G01X74724Y1303484D02*
X81890D01*
G01X77756Y1303681D02*
X76772D01*
G01X77756Y1304075D02*
X76772D01*
G01X77756Y1304272D02*
X76772D01*
G01X92717Y1305157D02*
X85384D01*
G01X85237D02*
X73228D01*
G01X51802Y1286260D02*
X51829Y1286263D01*
X51855Y1286274D01*
X51879Y1286293D01*
X51900Y1286317D01*
X51917Y1286347D01*
X51930Y1286381D01*
X51938Y1286418D01*
X51941Y1286457D01*
G01X51802Y1289409D02*
X51829Y1289413D01*
X51855Y1289424D01*
X51879Y1289442D01*
X51900Y1289467D01*
X51917Y1289497D01*
X51930Y1289531D01*
X51938Y1289567D01*
X51941Y1289606D01*
G01X51802Y1292559D02*
X51829Y1292563D01*
X51855Y1292574D01*
X51879Y1292592D01*
X51900Y1292617D01*
X51917Y1292646D01*
X51930Y1292680D01*
X51938Y1292717D01*
X51941Y1292756D01*
G01X51802Y1295709D02*
X51829Y1295712D01*
X51855Y1295723D01*
X51879Y1295741D01*
X51900Y1295766D01*
X51917Y1295796D01*
X51930Y1295830D01*
X51938Y1295867D01*
X51941Y1295906D01*
G01X51802Y1298858D02*
X51829Y1298862D01*
X51855Y1298873D01*
X51879Y1298891D01*
X51900Y1298916D01*
X51917Y1298946D01*
X51930Y1298980D01*
X51938Y1299016D01*
X51941Y1299055D01*
G01X51802Y1302008D02*
X51829Y1302011D01*
X51855Y1302022D01*
X51879Y1302041D01*
X51900Y1302065D01*
X51917Y1302095D01*
X51930Y1302129D01*
X51938Y1302166D01*
X51941Y1302205D01*
G01X51802Y1305157D02*
X51829Y1305161D01*
X51855Y1305172D01*
X51879Y1305190D01*
X51900Y1305215D01*
X51917Y1305245D01*
X51930Y1305279D01*
X51938Y1305315D01*
X51941Y1305354D01*
G01X74331Y1303878D02*
G03X74724Y1303484I394J0D01*
G01Y1301909D02*
G03X74331Y1301516I0J-393D01*
G01Y1288878D02*
G03X74724Y1288484I394J0D01*
G01Y1286909D02*
G03X74331Y1286516I0J-393D01*
G01Y1293878D02*
G03X74724Y1293484I394J0D01*
G01Y1291909D02*
G03X74331Y1291516I0J-393D01*
G01Y1298878D02*
G03X74724Y1298484I394J0D01*
G01Y1296909D02*
G03X74331Y1296516I0J-393D01*
G01X46506Y1299449D02*
X46539Y1299548D01*
X46628Y1299619D01*
X46753Y1299646D01*
G01X46784Y1303484D02*
X46644Y1303288D01*
X46506Y1303091D01*
X46369Y1302894D01*
G01X46784Y1298484D02*
X46644Y1298288D01*
X46506Y1298091D01*
X46369Y1297894D01*
G01X46784Y1293484D02*
X46644Y1293288D01*
X46506Y1293091D01*
X46369Y1292894D01*
G01X46784Y1288484D02*
X46644Y1288288D01*
X46506Y1288091D01*
X46369Y1287894D01*
G01Y1287500D02*
Y1287894D01*
G01Y1292500D02*
Y1292894D01*
G01Y1297500D02*
Y1297894D01*
G01Y1302500D02*
Y1302894D01*
G01X46506Y1302598D02*
Y1302205D01*
G01Y1299449D02*
Y1299055D01*
G01Y1296299D02*
Y1295906D01*
G01Y1293150D02*
Y1292756D01*
G01Y1290000D02*
Y1289606D01*
G01Y1286850D02*
Y1286457D01*
G01X50987Y1287500D02*
Y1287894D01*
G01Y1292500D02*
Y1292894D01*
G01Y1297500D02*
Y1297894D01*
G01Y1302500D02*
Y1302894D01*
G01Y1302500D02*
X50909Y1301909D01*
G01X50987Y1297500D02*
X50909Y1296909D01*
G01X50987Y1292500D02*
X50909Y1291909D01*
G01X50987Y1287500D02*
X50909Y1286909D01*
G01X50987Y1287894D02*
X50909Y1288484D01*
G01X50987Y1292894D02*
X50909Y1293484D01*
G01X50987Y1297894D02*
X50909Y1298484D01*
G01X50987Y1302894D02*
X50909Y1303484D01*
G01X46506Y1286457D02*
X46538Y1286359D01*
X46626Y1286287D01*
X46753Y1286260D01*
G01X46506Y1289606D02*
X46538Y1289509D01*
X46626Y1289437D01*
X46753Y1289409D01*
G01X46506Y1292756D02*
X46538Y1292659D01*
X46626Y1292587D01*
X46753Y1292559D01*
G01X46506Y1295906D02*
X46538Y1295808D01*
X46626Y1295736D01*
X46753Y1295709D01*
G01X46506Y1302205D02*
X46538Y1302107D01*
X46626Y1302035D01*
X46753Y1302008D01*
G01X46506Y1305354D02*
X46538Y1305257D01*
X46626Y1305185D01*
X46753Y1305157D01*
G01X46369Y1287500D02*
X46506Y1287302D01*
X46644Y1287106D01*
X46784Y1286909D01*
G01X46369Y1292500D02*
X46506Y1292302D01*
X46644Y1292106D01*
X46784Y1291909D01*
G01X46369Y1297500D02*
X46506Y1297302D01*
X46644Y1297106D01*
X46784Y1296909D01*
G01X46369Y1302500D02*
X46506Y1302302D01*
X46644Y1302106D01*
X46784Y1301909D01*
G01X46753Y1298858D02*
X46627Y1298885D01*
X46538Y1298958D01*
X46506Y1299055D01*
G01X46753Y1286260D02*
X52838D01*
G01X53118Y1286457D02*
X46506D01*
G01Y1286850D02*
X53118D01*
G01X46784Y1286909D02*
X52529D01*
G01X46753Y1287047D02*
X52838D01*
G01X46369Y1287500D02*
X52956D01*
G01Y1287894D02*
X46369D01*
G01X52529Y1288484D02*
X46784D01*
G01X46753Y1289409D02*
X52838D01*
G01X53118Y1289606D02*
X46506D01*
G01Y1290000D02*
X53118D01*
G01X46753Y1290197D02*
X52838D01*
G01X71181Y1290492D02*
X44488D01*
G01X46784Y1291909D02*
X52529D01*
G01X46369Y1292500D02*
X52956D01*
G01X46753Y1292559D02*
X52838D01*
G01X53118Y1292756D02*
X46506D01*
G01X44488Y1292854D02*
X71181D01*
G01X52956Y1292894D02*
X46369D01*
G01X46506Y1293150D02*
X53118D01*
G01X46753Y1293346D02*
X52838D01*
G01X52529Y1293484D02*
X46784D01*
G01X46753Y1295709D02*
X52838D01*
G01X53118Y1295906D02*
X46506D01*
G01Y1296299D02*
X53118D01*
G01X46753Y1296496D02*
X52838D01*
G01X46784Y1296909D02*
X52529D01*
G01X46369Y1297500D02*
X52956D01*
G01Y1297894D02*
X46369D01*
G01X52529Y1298484D02*
X46784D01*
G01X46753Y1298858D02*
X52838D01*
G01X53118Y1299055D02*
X46506D01*
G01Y1299449D02*
X53118D01*
G01X46753Y1299646D02*
X52838D01*
G01X46784Y1301909D02*
X52529D01*
G01X46753Y1302008D02*
X52838D01*
G01X53118Y1302205D02*
X46506D01*
G01X46369Y1302500D02*
X52956D01*
G01X46506Y1302598D02*
X53118D01*
G01X46753Y1302795D02*
X52838D01*
G01X52956Y1302894D02*
X46369D01*
G01X52529Y1303484D02*
X46784D01*
G01X46753Y1305157D02*
X52838D01*
G01X46753Y1287047D02*
X46626Y1287019D01*
X46537Y1286946D01*
X46506Y1286850D01*
G01X46753Y1290197D02*
X46626Y1290169D01*
X46537Y1290096D01*
X46506Y1290000D01*
G01X46753Y1293346D02*
X46626Y1293319D01*
X46537Y1293246D01*
X46506Y1293150D01*
G01X46753Y1296496D02*
X46626Y1296468D01*
X46537Y1296395D01*
X46506Y1296299D01*
G01X46753Y1302795D02*
X46626Y1302767D01*
X46537Y1302694D01*
X46506Y1302598D01*
G01X69685Y1427362D02*
Y1426772D01*
G01X75984D02*
Y1427362D01*
G01X71260Y1427067D02*
X68110D01*
G01X74409D02*
X77559D01*
G01X75984Y1427362D02*
X69685D01*
G01Y1425591D02*
G03Y1426772I0J591D01*
G01X75984D02*
G03Y1425591I0J-590D01*
G01X69602Y1423652D02*
X69696Y1423764D01*
G01Y1423636D02*
X69602Y1423525D01*
G01X70521Y1383832D02*
X70608Y1384088D01*
G01X71741Y1383320D02*
X71654Y1383064D01*
G01X52112Y1382500D02*
X51839Y1381909D01*
G01X52112Y1377500D02*
X51839Y1376909D01*
G01X52112Y1372500D02*
X51839Y1371909D01*
G01X52112Y1367500D02*
X51839Y1366909D01*
G01X70260Y1384514D02*
X70086Y1384173D01*
G01X70260Y1382552D02*
X70434Y1382894D01*
G01X68518Y1384856D02*
X68256Y1384429D01*
G01X70608Y1384088D02*
X70783Y1384344D01*
G01X69911Y1382979D02*
X69737Y1382723D01*
G01X74865Y1394769D02*
X74682Y1394504D01*
X74619Y1394206D01*
X74683Y1393909D01*
G01X76133Y1393636D02*
X76323Y1393904D01*
G01X52529Y1381909D02*
X52956Y1382500D01*
G01X52529Y1376909D02*
X52956Y1377500D01*
G01X52529Y1371909D02*
X52956Y1372500D01*
G01X52529Y1366909D02*
X52956Y1367500D01*
G01X74294Y1395294D02*
X73956Y1394833D01*
X73811Y1394314D01*
X73871Y1393796D01*
X74122Y1393313D01*
X74559Y1392918D01*
X75132Y1392694D01*
X75767Y1392676D01*
X76351Y1392862D01*
X76806Y1393215D01*
X77098Y1393687D01*
X77202Y1394207D01*
G01X71915Y1382638D02*
X72176Y1382979D01*
G01X79474Y1395306D02*
X79151Y1394887D01*
X78989Y1394404D01*
X79010Y1393899D01*
X79213Y1393422D01*
X79580Y1393019D01*
X80086Y1392751D01*
X80678Y1392657D01*
X81267Y1392754D01*
X81769Y1393023D01*
X82133Y1393427D01*
X82334Y1393905D01*
X82354Y1394410D01*
X82190Y1394891D01*
X81869Y1395306D01*
G01X84641D02*
X84319Y1394887D01*
X84156Y1394404D01*
X84178Y1393899D01*
X84381Y1393422D01*
X84748Y1393019D01*
X85254Y1392751D01*
X85845Y1392657D01*
X86434Y1392754D01*
X86936Y1393023D01*
X87300Y1393427D01*
X87502Y1393905D01*
X87521Y1394410D01*
X87357Y1394891D01*
X87037Y1395306D01*
G01X68779Y1384344D02*
X69040Y1384600D01*
G01X70608Y1384856D02*
X70260Y1384514D01*
G01X69911Y1382211D02*
X70260Y1382552D01*
G01X71654Y1383064D02*
X71480Y1382894D01*
G01X76428Y1396297D02*
X74865Y1394769D01*
G01X81869Y1395306D02*
X82321Y1395746D01*
X82591Y1396282D01*
X82661Y1396853D01*
X82520Y1397417D01*
X82173Y1397941D01*
X81646Y1398335D01*
X81003Y1398538D01*
X80324Y1398535D01*
X79684Y1398328D01*
X79161Y1397931D01*
X78820Y1397408D01*
X78681Y1396847D01*
X78753Y1396279D01*
X79024Y1395745D01*
G01X87037Y1395306D02*
X87488Y1395746D01*
X87759Y1396282D01*
X87829Y1396853D01*
X87687Y1397417D01*
X87341Y1397941D01*
X86813Y1398335D01*
X86170Y1398538D01*
X85491Y1398535D01*
X84851Y1398328D01*
X84328Y1397931D01*
X83987Y1397408D01*
X83849Y1396847D01*
X83920Y1396279D01*
X84191Y1395745D01*
G01X75922Y1396841D02*
X74294Y1395294D01*
G01X71567Y1382382D02*
X71915Y1382638D01*
G01X51351Y1380748D02*
X51389Y1380774D01*
X51417Y1380846D01*
X51428Y1380945D01*
G01X51351Y1371299D02*
X51389Y1371326D01*
X51417Y1371398D01*
X51428Y1371496D01*
G01X51351Y1368150D02*
X51389Y1368176D01*
X51417Y1368248D01*
X51428Y1368346D01*
G01X80249Y1397747D02*
X79888Y1397511D01*
X79650Y1397161D01*
X79565Y1396757D01*
X79647Y1396355D01*
X79883Y1396003D01*
X80247Y1395763D01*
X80672Y1395678D01*
G01X81094Y1395762D02*
X81455Y1395998D01*
X81693Y1396348D01*
X81779Y1396752D01*
X81696Y1397154D01*
X81460Y1397506D01*
X81096Y1397746D01*
X80672Y1397831D01*
G01X85416Y1397747D02*
X85056Y1397511D01*
X84817Y1397161D01*
X84732Y1396757D01*
X84814Y1396355D01*
X85051Y1396003D01*
X85414Y1395763D01*
X85839Y1395678D01*
G01X86262Y1395762D02*
X86622Y1395998D01*
X86861Y1396348D01*
X86946Y1396752D01*
X86864Y1397154D01*
X86627Y1397506D01*
X86264Y1397746D01*
X85839Y1397831D01*
G01X69737Y1382723D02*
X69476Y1382552D01*
G01X80323Y1394955D02*
X80040Y1394777D01*
X79853Y1394512D01*
X79786Y1394210D01*
X79850Y1393909D01*
X80036Y1393643D01*
X80321Y1393461D01*
X80672Y1393396D01*
G01X81020Y1393461D02*
X81303Y1393638D01*
X81490Y1393904D01*
X81557Y1394206D01*
X81493Y1394506D01*
X81307Y1394772D01*
X81022Y1394954D01*
X80672Y1395020D01*
G01X85490Y1394955D02*
X85207Y1394777D01*
X85020Y1394512D01*
X84953Y1394210D01*
X85018Y1393909D01*
X85203Y1393643D01*
X85489Y1393461D01*
X85839Y1393396D01*
G01X86188Y1393461D02*
X86470Y1393638D01*
X86657Y1393904D01*
X86724Y1394206D01*
X86660Y1394506D01*
X86475Y1394772D01*
X86189Y1394954D01*
X85839Y1395020D01*
G01X76133Y1393636D02*
X75846Y1393458D01*
X75492Y1393396D01*
G01X68953Y1385111D02*
X68518Y1384856D01*
G01X69563Y1382041D02*
X69911Y1382211D01*
G01X71480Y1382894D02*
X71306Y1382808D01*
G01X51428Y1378189D02*
Y1377795D01*
G01Y1381339D02*
Y1380945D01*
G01Y1375039D02*
Y1374646D01*
G01Y1371890D02*
Y1371496D01*
G01Y1368740D02*
Y1368346D01*
G01X51941Y1371496D02*
Y1371890D01*
G01Y1368346D02*
Y1368740D01*
G01Y1374646D02*
Y1375039D01*
G01Y1377795D02*
Y1378189D01*
G01Y1380945D02*
Y1381339D01*
G01X52112Y1382894D02*
Y1382500D01*
G01Y1377894D02*
Y1377500D01*
G01Y1372894D02*
Y1372500D01*
G01Y1367894D02*
Y1367500D01*
G01X52956Y1382894D02*
Y1382500D01*
G01Y1377894D02*
Y1377500D01*
G01Y1372894D02*
Y1372500D01*
G01Y1367894D02*
Y1367500D01*
G01X53118Y1371496D02*
Y1371890D01*
G01Y1368346D02*
Y1368740D01*
G01Y1374646D02*
Y1375039D01*
G01Y1377795D02*
Y1378189D01*
G01Y1380945D02*
Y1381339D01*
G01X51428Y1377795D02*
X51417Y1377697D01*
X51389Y1377625D01*
X51351Y1377598D01*
G01X51428Y1374646D02*
X51417Y1374547D01*
X51389Y1374475D01*
X51351Y1374449D01*
G01X77202Y1394207D02*
X77115Y1393731D01*
X76868Y1393289D01*
X76480Y1392937D01*
X75973Y1392717D01*
X75395Y1392661D01*
X74832Y1392783D01*
X74356Y1393065D01*
X74017Y1393470D01*
X73837Y1393926D01*
X73822Y1394407D01*
X73979Y1394877D01*
X74294Y1395294D01*
G01X68256Y1384429D02*
X68169Y1384002D01*
G01X70434Y1382894D02*
X70521Y1383320D01*
G01X72176Y1382979D02*
X72264Y1383406D01*
G01X76323Y1393903D02*
X76390Y1394207D01*
G01X68692Y1384002D02*
X68779Y1384344D01*
G01X70086Y1384173D02*
X69998Y1383832D01*
G01Y1383320D02*
X69911Y1382979D01*
G01X69040Y1384600D02*
X69302Y1384685D01*
G01X70783Y1384344D02*
X71044Y1384429D01*
G01X71306Y1382296D02*
X71567Y1382382D01*
G01X51941Y1365591D02*
X51938Y1365629D01*
X51930Y1365665D01*
X51917Y1365699D01*
X51900Y1365730D01*
X51879Y1365754D01*
X51856Y1365772D01*
X51830Y1365783D01*
X51802Y1365787D01*
G01X51941Y1368740D02*
X51938Y1368778D01*
X51930Y1368815D01*
X51917Y1368849D01*
X51900Y1368879D01*
X51879Y1368904D01*
X51856Y1368922D01*
X51830Y1368933D01*
X51802Y1368937D01*
G01X51941Y1371890D02*
X51938Y1371928D01*
X51930Y1371965D01*
X51917Y1371998D01*
X51900Y1372029D01*
X51879Y1372053D01*
X51856Y1372071D01*
X51830Y1372083D01*
X51802Y1372087D01*
G01X51941Y1375039D02*
X51938Y1375078D01*
X51930Y1375114D01*
X51917Y1375148D01*
X51900Y1375178D01*
X51879Y1375203D01*
X51856Y1375221D01*
X51830Y1375232D01*
X51802Y1375236D01*
G01X51941Y1378189D02*
X51938Y1378227D01*
X51930Y1378264D01*
X51917Y1378298D01*
X51900Y1378328D01*
X51879Y1378352D01*
X51856Y1378370D01*
X51830Y1378382D01*
X51802Y1378386D01*
G01X51941Y1381339D02*
X51938Y1381377D01*
X51930Y1381413D01*
X51917Y1381447D01*
X51900Y1381478D01*
X51879Y1381502D01*
X51856Y1381520D01*
X51830Y1381531D01*
X51802Y1381535D01*
G01X64646Y1386319D02*
Y1412717D01*
G01X64961Y1387500D02*
Y1385728D01*
G01X66929Y1399783D02*
Y1391437D01*
G01X68110Y1427067D02*
Y1425098D01*
G01Y1422539D02*
Y1424508D01*
G01X68169Y1384002D02*
Y1383320D01*
G01Y1380335D02*
Y1380846D01*
G01X68565Y1393322D02*
Y1392657D01*
G01X68692Y1383320D02*
Y1384002D01*
G01X69213Y1369902D02*
Y1386319D01*
G01X69302Y1384685D02*
Y1385197D01*
G01X69602Y1423525D02*
Y1423652D01*
G01X69685Y1425591D02*
Y1424016D01*
G01Y1422835D02*
Y1422244D01*
G01X69696Y1423016D02*
Y1423636D01*
G01X69789Y1423764D02*
Y1423016D01*
G01X69998Y1383832D02*
Y1383320D01*
G01X70044Y1407598D02*
Y1406024D01*
G01X70079D02*
Y1407598D01*
G01X70103Y1406024D02*
Y1407598D01*
G01X70521Y1383320D02*
Y1383832D01*
G01X70669Y1422244D02*
Y1427362D01*
G01X70866D02*
Y1422244D01*
G01Y1397815D02*
Y1394035D01*
G01Y1389626D02*
Y1392067D01*
G01X71260Y1424508D02*
Y1422539D01*
G01Y1425098D02*
Y1427067D01*
G01X71306Y1382808D02*
Y1382296D01*
G01X71426Y1407598D02*
Y1406024D01*
G01X71741Y1383832D02*
Y1383320D01*
G01X71796Y1406024D02*
Y1407598D01*
G01X72264Y1380846D02*
Y1380335D01*
G01Y1383406D02*
Y1383832D01*
G01X72404Y1392657D02*
Y1393396D01*
G01X73585Y1398563D02*
Y1397825D01*
G01X73873Y1407598D02*
Y1406024D01*
G01X74243D02*
Y1407598D01*
G01X74409Y1424508D02*
Y1422539D01*
G01Y1425098D02*
Y1427067D01*
G01X74783Y1383661D02*
Y1381693D01*
G01X74803Y1427362D02*
Y1422244D01*
G01X75000D02*
Y1427362D01*
G01X75170Y1378386D02*
Y1377598D01*
G01Y1381535D02*
Y1380748D01*
G01Y1375236D02*
Y1374449D01*
G01Y1368937D02*
Y1368150D01*
G01Y1372087D02*
Y1371299D01*
G01X75197Y1378386D02*
Y1377598D01*
G01Y1381535D02*
Y1380748D01*
G01Y1375236D02*
Y1374449D01*
G01Y1368937D02*
Y1368150D01*
G01Y1372087D02*
Y1371299D01*
G01X75567Y1407598D02*
Y1406024D01*
G01X75573Y1378386D02*
Y1377598D01*
G01Y1381535D02*
Y1380748D01*
G01Y1375236D02*
Y1374449D01*
G01Y1368937D02*
Y1368150D01*
G01Y1372087D02*
Y1371299D01*
G01X75591Y1407598D02*
Y1406024D01*
G01X75625D02*
Y1407598D01*
G01X75787Y1383484D02*
Y1381909D01*
G01Y1378484D02*
Y1376909D01*
G01Y1373484D02*
Y1371909D01*
G01Y1368484D02*
Y1366909D01*
G01X75984Y1422244D02*
Y1422835D01*
G01Y1424016D02*
Y1425591D01*
G01X76390Y1394355D02*
Y1394207D01*
G01X76772Y1384272D02*
Y1381122D01*
G01Y1379272D02*
Y1376122D01*
G01Y1374272D02*
Y1371122D01*
G01Y1369272D02*
Y1366122D01*
G01Y1389134D02*
Y1391437D01*
G01X77202Y1394207D02*
Y1394355D01*
G01X77497Y1398120D02*
Y1398563D01*
G01X77559Y1427067D02*
Y1425098D01*
G01Y1422539D02*
Y1424508D01*
G01X77756Y1384272D02*
Y1381122D01*
G01Y1379272D02*
Y1376122D01*
G01Y1374272D02*
Y1371122D01*
G01Y1369272D02*
Y1366122D01*
G01X78740Y1383484D02*
Y1381909D01*
G01Y1378484D02*
Y1376909D01*
G01Y1373484D02*
Y1371909D01*
G01Y1368484D02*
Y1366909D01*
G01X78935Y1368150D02*
Y1368937D01*
G01Y1371299D02*
Y1372087D01*
G01Y1374449D02*
Y1375236D01*
G01Y1377598D02*
Y1378386D01*
G01Y1380748D02*
Y1381535D01*
G01X79328Y1389075D02*
Y1389134D01*
G01X79967Y1391437D02*
Y1388681D01*
G01X80919Y1368150D02*
Y1368937D01*
G01Y1371299D02*
Y1372087D01*
G01Y1374449D02*
Y1375236D01*
G01Y1377598D02*
Y1378386D01*
G01Y1380748D02*
Y1381535D01*
G01X81024Y1412717D02*
Y1399783D01*
G01X81890Y1366909D02*
Y1368484D01*
G01Y1371909D02*
Y1373484D01*
G01Y1376909D02*
Y1378484D01*
G01Y1381909D02*
Y1383484D01*
G01X82570Y1378386D02*
Y1377598D01*
G01Y1381535D02*
Y1380748D01*
G01Y1375236D02*
Y1374449D01*
G01Y1368937D02*
Y1368150D01*
G01Y1372087D02*
Y1371299D01*
G01X82854Y1381693D02*
Y1383661D01*
G01X84298Y1365787D02*
Y1368150D01*
G01Y1368937D02*
Y1371299D01*
G01Y1372087D02*
Y1374449D01*
G01Y1375236D02*
Y1377598D01*
G01Y1378386D02*
Y1380748D01*
G01Y1381535D02*
Y1384114D01*
G01X85237Y1378386D02*
Y1377598D01*
G01Y1381535D02*
Y1380748D01*
G01Y1375236D02*
Y1374449D01*
G01Y1368937D02*
Y1368150D01*
G01Y1372087D02*
Y1371299D01*
G01X85384Y1378386D02*
Y1377598D01*
G01Y1381535D02*
Y1380748D01*
G01Y1375236D02*
Y1374449D01*
G01Y1368937D02*
Y1368150D01*
G01Y1372087D02*
Y1371299D01*
G01X86976Y1378386D02*
Y1377598D01*
G01Y1381535D02*
Y1380748D01*
G01Y1375236D02*
Y1374449D01*
G01Y1368937D02*
Y1368150D01*
G01Y1372087D02*
Y1371299D01*
G01X87841Y1391437D02*
Y1388681D01*
G01X87918Y1368150D02*
Y1368937D01*
G01Y1371299D02*
Y1372087D01*
G01Y1374449D02*
Y1375236D01*
G01Y1377598D02*
Y1378386D01*
G01Y1380748D02*
Y1381535D01*
G01X89013Y1393322D02*
Y1392657D01*
G01X90754Y1368150D02*
Y1368937D01*
G01Y1371299D02*
Y1372087D01*
G01Y1374449D02*
Y1375236D01*
G01Y1377598D02*
Y1378386D01*
G01Y1380748D02*
Y1381535D01*
G01X90943Y1378386D02*
Y1377598D01*
G01Y1381535D02*
Y1380748D01*
G01Y1375236D02*
Y1374449D01*
G01Y1368937D02*
Y1368150D01*
G01Y1372087D02*
Y1371299D01*
G01X92717Y1378386D02*
Y1377598D01*
G01Y1381535D02*
Y1380748D01*
G01Y1375236D02*
Y1374449D01*
G01Y1368937D02*
Y1368150D01*
G01Y1372087D02*
Y1371299D01*
G01X92852Y1392657D02*
Y1393396D01*
G01X93696Y1386102D02*
Y1388681D01*
G01X94170Y1386102D02*
Y1391437D01*
G01X94488Y1386102D02*
Y1399783D01*
G01X68779Y1382979D02*
X68692Y1383320D01*
G01X72264Y1383832D02*
X72176Y1384173D01*
G01X68169Y1383320D02*
X68256Y1382894D01*
G01X51839Y1368484D02*
X52112Y1367894D01*
G01X51839Y1373484D02*
X52112Y1372894D01*
G01X51839Y1378484D02*
X52112Y1377894D01*
G01X51839Y1383484D02*
X52112Y1382894D01*
G01X71654Y1384088D02*
X71741Y1383832D01*
G01X52529Y1368484D02*
X52956Y1367894D01*
G01X52529Y1373484D02*
X52956Y1372894D01*
G01X52529Y1378484D02*
X52956Y1377894D01*
G01X52529Y1383484D02*
X52956Y1382894D01*
G01X68953Y1382723D02*
X68779Y1382979D01*
G01X71480Y1384344D02*
X71654Y1384088D01*
G01X79583Y1388681D02*
X79328Y1389075D01*
G01X68256Y1382894D02*
X68430Y1382552D01*
G01X72176Y1384173D02*
X72002Y1384514D01*
G01X81869Y1395306D02*
X82192Y1394887D01*
X82355Y1394404D01*
X82333Y1393899D01*
X82130Y1393422D01*
X81763Y1393019D01*
X81257Y1392751D01*
X80666Y1392657D01*
X80077Y1392754D01*
X79574Y1393023D01*
X79210Y1393427D01*
X79009Y1393905D01*
X78989Y1394410D01*
X79154Y1394891D01*
X79474Y1395306D01*
G01X87037D02*
X87359Y1394887D01*
X87522Y1394404D01*
X87500Y1393899D01*
X87297Y1393422D01*
X86930Y1393019D01*
X86424Y1392751D01*
X85833Y1392657D01*
X85244Y1392754D01*
X84742Y1393023D01*
X84377Y1393427D01*
X84176Y1393905D01*
X84157Y1394410D01*
X84321Y1394891D01*
X84641Y1395306D01*
G01X74866Y1393645D02*
X74683Y1393910D01*
X74619Y1394209D01*
X74683Y1394506D01*
G01X79474Y1395306D02*
X79022Y1395746D01*
X78752Y1396282D01*
X78682Y1396853D01*
X78824Y1397417D01*
X79170Y1397941D01*
X79698Y1398335D01*
X80340Y1398538D01*
X81019Y1398535D01*
X81659Y1398328D01*
X82182Y1397931D01*
X82524Y1397408D01*
X82662Y1396847D01*
X82590Y1396279D01*
X82320Y1395745D01*
G01X84641Y1395306D02*
X84189Y1395746D01*
X83919Y1396282D01*
X83849Y1396853D01*
X83991Y1397417D01*
X84337Y1397941D01*
X84865Y1398335D01*
X85507Y1398538D01*
X86187Y1398535D01*
X86827Y1398328D01*
X87350Y1397931D01*
X87691Y1397408D01*
X87829Y1396847D01*
X87757Y1396279D01*
X87487Y1395745D01*
G01X68430Y1382552D02*
X68779Y1382211D01*
G01X72002Y1384514D02*
X71654Y1384856D01*
G01X69215Y1382552D02*
X68953Y1382723D01*
G01X51351Y1365787D02*
X51389Y1365761D01*
X51417Y1365689D01*
X51428Y1365591D01*
G01X51351Y1368937D02*
X51389Y1368911D01*
X51417Y1368839D01*
X51428Y1368740D01*
G01X51351Y1372087D02*
X51389Y1372060D01*
X51417Y1371988D01*
X51428Y1371890D01*
G01X51351Y1375236D02*
X51389Y1375210D01*
X51417Y1375138D01*
X51428Y1375039D01*
G01X51351Y1378386D02*
X51389Y1378359D01*
X51417Y1378287D01*
X51428Y1378189D01*
G01X51351Y1381535D02*
X51389Y1381509D01*
X51417Y1381437D01*
X51428Y1381339D01*
G01X71567Y1380846D02*
X70957Y1381358D01*
G01X71654D02*
X72264Y1380846D01*
G01X68779Y1382211D02*
X69128Y1382041D01*
G01X80323Y1393461D02*
X80040Y1393638D01*
X79853Y1393904D01*
X79786Y1394206D01*
X79850Y1394506D01*
X80036Y1394772D01*
X80321Y1394954D01*
X80672Y1395020D01*
G01X81020Y1394955D02*
X81303Y1394777D01*
X81490Y1394512D01*
X81557Y1394210D01*
X81493Y1393909D01*
X81307Y1393643D01*
X81022Y1393461D01*
X80672Y1393396D01*
G01X85490Y1393461D02*
X85207Y1393638D01*
X85020Y1393904D01*
X84953Y1394206D01*
X85018Y1394506D01*
X85203Y1394772D01*
X85489Y1394954D01*
X85839Y1395020D01*
G01X86188Y1394955D02*
X86470Y1394777D01*
X86657Y1394512D01*
X86724Y1394210D01*
X86660Y1393909D01*
X86475Y1393643D01*
X86189Y1393461D01*
X85839Y1393396D01*
G01X75145Y1393465D02*
X74865Y1393646D01*
G01X80249Y1395762D02*
X79888Y1395998D01*
X79650Y1396348D01*
X79565Y1396752D01*
X79647Y1397154D01*
X79883Y1397506D01*
X80247Y1397746D01*
X80672Y1397831D01*
G01X81094Y1397747D02*
X81455Y1397511D01*
X81693Y1397161D01*
X81779Y1396757D01*
X81696Y1396355D01*
X81460Y1396003D01*
X81096Y1395763D01*
X80672Y1395678D01*
G01X85416Y1395762D02*
X85056Y1395998D01*
X84817Y1396348D01*
X84732Y1396752D01*
X84814Y1397154D01*
X85051Y1397506D01*
X85414Y1397746D01*
X85839Y1397831D01*
G01X86262Y1397747D02*
X86622Y1397511D01*
X86861Y1397161D01*
X86946Y1396757D01*
X86864Y1396355D01*
X86627Y1396003D01*
X86264Y1395763D01*
X85839Y1395678D01*
G01X71218Y1384429D02*
X71480Y1384344D01*
G01X75492Y1393396D02*
X75144Y1393465D01*
G01X71654Y1384856D02*
X71306Y1384941D01*
G01X85237Y1365787D02*
X73228D01*
G01X85384D02*
X92717D01*
G01X77756Y1366122D02*
X76772D01*
G01X77756Y1366319D02*
X76772D01*
G01X77756Y1366713D02*
X76772D01*
G01X74724Y1366909D02*
X81890D01*
G01X92717Y1368150D02*
X85384D01*
G01X85237D02*
X73228D01*
G01X74724Y1368484D02*
X81890D01*
G01X77756Y1368681D02*
X76772D01*
G01X85237Y1368937D02*
X73228D01*
G01X85384D02*
X92717D01*
G01X77756Y1369075D02*
X76772D01*
G01X77756Y1369272D02*
X76772D01*
G01X77756Y1371122D02*
X76772D01*
G01X92717Y1371299D02*
X85384D01*
G01X85237D02*
X73228D01*
G01X77756Y1371319D02*
X76772D01*
G01X77756Y1371713D02*
X76772D01*
G01X74724Y1371909D02*
X81890D01*
G01X85237Y1372087D02*
X73228D01*
G01X85384D02*
X92717D01*
G01X74724Y1373484D02*
X81890D01*
G01X77756Y1373681D02*
X76772D01*
G01X77756Y1374075D02*
X76772D01*
G01X77756Y1374272D02*
X76772D01*
G01X92717Y1374449D02*
X85384D01*
G01X85237D02*
X73228D01*
G01X85237Y1375236D02*
X73228D01*
G01X85384D02*
X92717D01*
G01X77756Y1376122D02*
X76772D01*
G01X77756Y1376319D02*
X76772D01*
G01X77756Y1376713D02*
X76772D01*
G01X74724Y1376909D02*
X81890D01*
G01X92717Y1377598D02*
X85384D01*
G01X85237D02*
X73228D01*
G01X85237Y1378386D02*
X73228D01*
G01X85384D02*
X92717D01*
G01X74724Y1378484D02*
X81890D01*
G01X77756Y1378681D02*
X76772D01*
G01X77756Y1379075D02*
X76772D01*
G01X77756Y1379272D02*
X76772D01*
G01X72264Y1380335D02*
X68169D01*
G01X92717Y1380748D02*
X85384D01*
G01X85237D02*
X73228D01*
G01X68169Y1380846D02*
X71567D01*
G01X77756Y1381122D02*
X76772D01*
G01X77756Y1381319D02*
X76772D01*
G01X70957Y1381358D02*
X71654D01*
G01X85237Y1381535D02*
X73228D01*
G01X85384D02*
X92717D01*
G01X74783Y1381693D02*
X82854D01*
G01X77756Y1381713D02*
X76772D01*
G01X74724Y1381909D02*
X81890D01*
G01X69128Y1382041D02*
X69563D01*
G01X69476Y1382552D02*
X69215D01*
G01X74724Y1383484D02*
X81890D01*
G01X82854Y1383661D02*
X74783D01*
G01X77756Y1383681D02*
X76772D01*
G01X77756Y1384075D02*
X76772D01*
G01X78346Y1384114D02*
X87331D01*
G01X77756Y1384272D02*
X76772D01*
G01X71044Y1384429D02*
X71218D01*
G01X71306Y1384941D02*
X70957D01*
G01X74331Y1385728D02*
X64961D01*
G01X74331Y1386102D02*
X94488D01*
G01X64646Y1386319D02*
X71181D01*
G01X74331Y1387500D02*
X64961D01*
G01X93696Y1388681D02*
X73228D01*
G01X79328Y1389075D02*
X73228D01*
G01X79328Y1389134D02*
X73228D01*
G01X51802Y1368150D02*
X51829Y1368153D01*
X51855Y1368164D01*
X51879Y1368182D01*
X51900Y1368207D01*
X51917Y1368237D01*
X51930Y1368271D01*
X51938Y1368307D01*
X51941Y1368346D01*
G01X51802Y1371299D02*
X51829Y1371303D01*
X51855Y1371314D01*
X51879Y1371332D01*
X51900Y1371357D01*
X51917Y1371387D01*
X51930Y1371420D01*
X51938Y1371457D01*
X51941Y1371496D01*
G01X51802Y1374449D02*
X51829Y1374452D01*
X51855Y1374463D01*
X51879Y1374481D01*
X51900Y1374506D01*
X51917Y1374536D01*
X51930Y1374570D01*
X51938Y1374607D01*
X51941Y1374646D01*
G01X51802Y1377598D02*
X51829Y1377602D01*
X51855Y1377613D01*
X51879Y1377631D01*
X51900Y1377656D01*
X51917Y1377686D01*
X51930Y1377720D01*
X51938Y1377756D01*
X51941Y1377795D01*
G01X51802Y1380748D02*
X51829Y1380752D01*
X51855Y1380763D01*
X51879Y1380781D01*
X51900Y1380806D01*
X51917Y1380835D01*
X51930Y1380869D01*
X51938Y1380906D01*
X51941Y1380945D01*
G01X70866Y1389626D02*
X94488D01*
G01Y1392067D02*
X70866D01*
G01X68565Y1392657D02*
X72404D01*
G01X89013D02*
X92852D01*
G01Y1393396D02*
X89899D01*
G01X72404D02*
X69451D01*
G01X70866Y1394035D02*
X94488D01*
G01X77202Y1394355D02*
X76390D01*
G01X94488Y1397815D02*
X70866D01*
G01X73585Y1397825D02*
X76464D01*
G01X92113Y1398563D02*
X91228D01*
G01X77497D02*
X73585D01*
G01X71666D02*
X70780D01*
G01X81024Y1402539D02*
X64646D01*
G01X75000Y1405236D02*
X70669D01*
G01X75625Y1406024D02*
X70044D01*
G01Y1407598D02*
X75625D01*
G01X70669Y1408386D02*
X75000D01*
G01X81024Y1412717D02*
X64646D01*
G01X69685Y1422244D02*
X75984D01*
G01X71260Y1422539D02*
X68110D01*
G01X74409D02*
X77559D01*
G01X69789Y1423016D02*
X69696D01*
G01Y1423764D02*
X69789D01*
G01X77559Y1424508D02*
X74409D01*
G01X68110D02*
X71260D01*
G01X77559Y1425098D02*
X74409D01*
G01X68110D02*
X71260D01*
G01X70957Y1384941D02*
X70608Y1384856D01*
G01X69302Y1385197D02*
X68953Y1385111D01*
G01X68565Y1393322D02*
G03X70780Y1398563I-7141J6107D01*
G01X69451Y1393396D02*
G03X71666Y1398563I-6937J6032D01*
G01X76428Y1396297D02*
G03X77498Y1398120I-2809J2875D01*
G01X70669Y1408386D02*
G03Y1405236I0J-1575D01*
G01X69685Y1422835D02*
G03Y1424016I0J590D01*
G01X74331Y1378878D02*
G03X74724Y1378484I394J0D01*
G01Y1376909D02*
G03X74331Y1376516I0J-393D01*
G01Y1368878D02*
G03X74724Y1368484I394J0D01*
G01Y1366909D02*
G03X74331Y1366516I0J-393D01*
G01Y1373878D02*
G03X74724Y1373484I394J0D01*
G01Y1371909D02*
G03X74331Y1371516I0J-393D01*
G01Y1383878D02*
G03X74724Y1383484I394J0D01*
G01Y1381909D02*
G03X74331Y1381516I0J-393D01*
G01X75922Y1396841D02*
G03X76464Y1397825I-1276J1344D01*
G01X75000Y1405236D02*
G03Y1408386I0J1575D01*
G01X75984Y1424016D02*
G03Y1422835I0J-591D01*
G01X89013Y1393322D02*
G03X91228Y1398563I-7141J6107D01*
G01X89899Y1393396D02*
G03X92113Y1398563I-6938J6031D01*
G01X86614Y1395000D02*
G03I-4528J0D01*
G01X85591D02*
G03I-3505J0D01*
G01X85433D02*
G03I-3347J0D01*
G01X84252D02*
G03I-2166J0D01*
G01X52112Y1362500D02*
X51839Y1361909D01*
G01X52529D02*
X52956Y1362500D01*
G01X51351Y1365000D02*
X51389Y1365026D01*
X51417Y1365098D01*
X51428Y1365197D01*
G01Y1365591D02*
Y1365197D01*
G01Y1362441D02*
Y1362047D01*
G01Y1359291D02*
Y1358898D01*
G01X51941Y1362047D02*
Y1362441D01*
G01Y1358898D02*
Y1359291D01*
G01Y1365197D02*
Y1365591D01*
G01X52112Y1362894D02*
Y1362500D01*
G01Y1357894D02*
Y1357500D01*
G01X52956Y1362894D02*
Y1362500D01*
G01Y1357894D02*
Y1357500D01*
G01X53118Y1362047D02*
Y1362441D01*
G01Y1358898D02*
Y1359291D01*
G01Y1365197D02*
Y1365591D01*
G01X51428Y1362047D02*
X51417Y1361949D01*
X51389Y1361877D01*
X51351Y1361850D01*
G01X51428Y1358898D02*
X51417Y1358799D01*
X51389Y1358727D01*
X51351Y1358701D01*
G01X51941Y1359291D02*
X51938Y1359330D01*
X51930Y1359366D01*
X51917Y1359400D01*
X51900Y1359430D01*
X51879Y1359455D01*
X51856Y1359473D01*
X51830Y1359484D01*
X51802Y1359488D01*
G01X51941Y1362441D02*
X51938Y1362479D01*
X51930Y1362516D01*
X51917Y1362550D01*
X51900Y1362580D01*
X51879Y1362604D01*
X51856Y1362622D01*
X51830Y1362634D01*
X51802Y1362638D01*
G01X75170Y1365787D02*
Y1365000D01*
G01Y1359488D02*
Y1358701D01*
G01Y1362638D02*
Y1361850D01*
G01X75197Y1365787D02*
Y1365000D01*
G01Y1359488D02*
Y1358701D01*
G01Y1362638D02*
Y1361850D01*
G01X75573Y1365787D02*
Y1365000D01*
G01Y1359488D02*
Y1358701D01*
G01Y1362638D02*
Y1361850D01*
G01X75787Y1363484D02*
Y1361909D01*
G01X76772Y1364272D02*
Y1361122D01*
G01X77756Y1364272D02*
Y1361122D01*
G01X78740Y1363484D02*
Y1361909D01*
G01X78935Y1358701D02*
Y1359488D01*
G01Y1361850D02*
Y1362638D01*
G01Y1365000D02*
Y1365787D01*
G01X80919Y1358701D02*
Y1359488D01*
G01Y1361850D02*
Y1362638D01*
G01Y1365000D02*
Y1365787D01*
G01X81890Y1361909D02*
Y1363484D01*
G01X82570Y1365787D02*
Y1365000D01*
G01Y1359488D02*
Y1358701D01*
G01Y1362638D02*
Y1361850D01*
G01X84298Y1359488D02*
Y1361850D01*
G01Y1362638D02*
Y1365000D01*
G01X85237Y1365787D02*
Y1365000D01*
G01Y1359488D02*
Y1358701D01*
G01Y1362638D02*
Y1361850D01*
G01X85384Y1365787D02*
Y1365000D01*
G01Y1359488D02*
Y1358701D01*
G01Y1362638D02*
Y1361850D01*
G01X86976Y1365787D02*
Y1365000D01*
G01Y1359488D02*
Y1358701D01*
G01Y1362638D02*
Y1361850D01*
G01X87918Y1358701D02*
Y1359488D01*
G01Y1361850D02*
Y1362638D01*
G01Y1365000D02*
Y1365787D01*
G01X90754Y1358701D02*
Y1359488D01*
G01Y1361850D02*
Y1362638D01*
G01Y1365000D02*
Y1365787D01*
G01X90943D02*
Y1365000D01*
G01Y1359488D02*
Y1358701D01*
G01Y1362638D02*
Y1361850D01*
G01X92717Y1365787D02*
Y1365000D01*
G01Y1359488D02*
Y1358701D01*
G01Y1362638D02*
Y1361850D01*
G01X51839Y1358484D02*
X52112Y1357894D01*
G01X51839Y1363484D02*
X52112Y1362894D01*
G01X52529Y1358484D02*
X52956Y1357894D01*
G01X52529Y1363484D02*
X52956Y1362894D01*
G01X51351Y1359488D02*
X51389Y1359462D01*
X51417Y1359390D01*
X51428Y1359291D01*
G01X51351Y1362638D02*
X51389Y1362611D01*
X51417Y1362539D01*
X51428Y1362441D01*
G01X74724Y1358484D02*
X81890D01*
G01X77756Y1358681D02*
X76772D01*
G01X92717Y1358701D02*
X85384D01*
G01X85237D02*
X73228D01*
G01X77756Y1359075D02*
X76772D01*
G01X77756Y1359272D02*
X76772D01*
G01X85237Y1359488D02*
X73228D01*
G01X85384D02*
X92717D01*
G01X77756Y1361122D02*
X76772D01*
G01X77756Y1361319D02*
X76772D01*
G01X77756Y1361713D02*
X76772D01*
G01X92717Y1361850D02*
X85384D01*
G01X85237D02*
X73228D01*
G01X74724Y1361909D02*
X81890D01*
G01X85237Y1362638D02*
X73228D01*
G01X85384D02*
X92717D01*
G01X74724Y1363484D02*
X81890D01*
G01X77756Y1363681D02*
X76772D01*
G01X77756Y1364075D02*
X76772D01*
G01X77756Y1364272D02*
X76772D01*
G01X92717Y1365000D02*
X85384D01*
G01X85237D02*
X73228D01*
G01X51802Y1358701D02*
X51829Y1358704D01*
X51855Y1358715D01*
X51879Y1358733D01*
X51900Y1358758D01*
X51917Y1358788D01*
X51930Y1358822D01*
X51938Y1358859D01*
X51941Y1358898D01*
G01X51802Y1361850D02*
X51829Y1361854D01*
X51855Y1361865D01*
X51879Y1361883D01*
X51900Y1361908D01*
X51917Y1361938D01*
X51930Y1361972D01*
X51938Y1362008D01*
X51941Y1362047D01*
G01X51802Y1365000D02*
X51829Y1365004D01*
X51855Y1365015D01*
X51879Y1365033D01*
X51900Y1365057D01*
X51917Y1365087D01*
X51930Y1365121D01*
X51938Y1365158D01*
X51941Y1365197D01*
G01X74331Y1363878D02*
G03X74724Y1363484I394J0D01*
G01Y1361909D02*
G03X74331Y1361516I0J-393D01*
G01Y1358878D02*
G03X74724Y1358484I394J0D01*
G01X44488Y1391437D02*
X42520Y1389469D01*
G01X40519Y1399752D02*
X40462Y1399612D01*
X40457Y1399372D01*
G01X40519Y1399752D02*
X40463Y1399618D01*
X40456Y1399382D01*
X40493Y1399053D01*
G01X46784Y1383484D02*
X46644Y1383288D01*
X46506Y1383091D01*
X46369Y1382894D01*
G01X46784Y1378484D02*
X46644Y1378288D01*
X46506Y1378091D01*
X46369Y1377894D01*
G01X46784Y1373484D02*
X46644Y1373288D01*
X46506Y1373091D01*
X46369Y1372894D01*
G01X46784Y1368484D02*
X46644Y1368288D01*
X46506Y1368091D01*
X46369Y1367894D01*
G01X40551Y1398602D02*
Y1391437D01*
G01X46369Y1367500D02*
Y1367894D01*
G01Y1372500D02*
Y1372894D01*
G01Y1377500D02*
Y1377894D01*
G01Y1382500D02*
Y1382894D01*
G01X46506Y1378189D02*
Y1377795D01*
G01Y1381339D02*
Y1380945D01*
G01Y1375039D02*
Y1374646D01*
G01Y1371890D02*
Y1371496D01*
G01Y1368740D02*
Y1368346D01*
G01X50987Y1367500D02*
Y1367894D01*
G01Y1372500D02*
Y1372894D01*
G01Y1377500D02*
Y1377894D01*
G01Y1382500D02*
Y1382894D01*
G01Y1382500D02*
X50909Y1381909D01*
G01X50987Y1377500D02*
X50909Y1376909D01*
G01X50987Y1372500D02*
X50909Y1371909D01*
G01X50987Y1367500D02*
X50909Y1366909D01*
G01X40492Y1399061D02*
X40547Y1398676D01*
G01X50987Y1367894D02*
X50909Y1368484D01*
G01X50987Y1372894D02*
X50909Y1373484D01*
G01X50987Y1377894D02*
X50909Y1378484D01*
G01X50987Y1382894D02*
X50909Y1383484D01*
G01X46506Y1368346D02*
X46538Y1368249D01*
X46626Y1368177D01*
X46753Y1368150D01*
G01X46506Y1371496D02*
X46538Y1371399D01*
X46626Y1371327D01*
X46753Y1371299D01*
G01X46506Y1374646D02*
X46538Y1374548D01*
X46626Y1374476D01*
X46753Y1374449D01*
G01X46506Y1377795D02*
X46538Y1377698D01*
X46626Y1377626D01*
X46753Y1377598D01*
G01X46506Y1380945D02*
X46538Y1380848D01*
X46626Y1380776D01*
X46753Y1380748D01*
G01X46369Y1367500D02*
X46506Y1367302D01*
X46644Y1367106D01*
X46784Y1366909D01*
G01X46369Y1372500D02*
X46506Y1372302D01*
X46644Y1372106D01*
X46784Y1371909D01*
G01X46369Y1377500D02*
X46506Y1377302D01*
X46644Y1377106D01*
X46784Y1376909D01*
G01X46369Y1382500D02*
X46506Y1382302D01*
X46644Y1382106D01*
X46784Y1381909D01*
G01X42520Y1388484D02*
X44488Y1386516D01*
G01X46506Y1365591D02*
X53118D01*
G01X46753Y1365787D02*
X52838D01*
G01X46784Y1366909D02*
X52529D01*
G01X46369Y1367500D02*
X52956D01*
G01X71181Y1367539D02*
X44488D01*
G01X52956Y1367894D02*
X46369D01*
G01X46753Y1368150D02*
X52838D01*
G01X53118Y1368346D02*
X46506D01*
G01X52529Y1368484D02*
X46784D01*
G01X46506Y1368740D02*
X53118D01*
G01X46753Y1368937D02*
X52838D01*
G01X44488Y1369902D02*
X71181D01*
G01X46753Y1371299D02*
X52838D01*
G01X53118Y1371496D02*
X46506D01*
G01Y1371890D02*
X53118D01*
G01X46784Y1371909D02*
X52529D01*
G01X46753Y1372087D02*
X52838D01*
G01X46369Y1372500D02*
X52956D01*
G01Y1372894D02*
X46369D01*
G01X52529Y1373484D02*
X46784D01*
G01X46753Y1374449D02*
X52838D01*
G01X53118Y1374646D02*
X46506D01*
G01Y1375039D02*
X53118D01*
G01X46753Y1375236D02*
X52838D01*
G01X46784Y1376909D02*
X52529D01*
G01X46369Y1377500D02*
X52956D01*
G01X46753Y1377598D02*
X52838D01*
G01X53118Y1377795D02*
X46506D01*
G01X52956Y1377894D02*
X46369D01*
G01X46506Y1378189D02*
X53118D01*
G01X46753Y1378386D02*
X52838D01*
G01X52529Y1378484D02*
X46784D01*
G01X46753Y1380748D02*
X52838D01*
G01X53118Y1380945D02*
X46506D01*
G01Y1381339D02*
X53118D01*
G01X46753Y1381535D02*
X52838D01*
G01X46784Y1381909D02*
X52529D01*
G01X46369Y1382500D02*
X52956D01*
G01Y1382894D02*
X46369D01*
G01X52529Y1383484D02*
X46784D01*
G01X62992Y1386516D02*
X44488D01*
G01X73228Y1386909D02*
X42520D01*
G01X46753Y1365787D02*
X46626Y1365759D01*
X46537Y1365687D01*
X46506Y1365591D01*
G01X46753Y1368937D02*
X46626Y1368909D01*
X46537Y1368836D01*
X46506Y1368740D01*
G01X46753Y1372087D02*
X46626Y1372059D01*
X46537Y1371986D01*
X46506Y1371890D01*
G01X46753Y1375236D02*
X46626Y1375208D01*
X46537Y1375135D01*
X46506Y1375039D01*
G01X42520Y1391437D02*
X39236D01*
G01X44488D02*
X94488D01*
G01X66929Y1398602D02*
X40551D01*
G01Y1399783D02*
X94488D01*
G01X46753Y1378386D02*
X46626Y1378358D01*
X46537Y1378285D01*
X46506Y1378189D01*
G01X46753Y1381535D02*
X46626Y1381507D01*
X46537Y1381435D01*
X46506Y1381339D01*
G01X46784Y1363484D02*
X46644Y1363288D01*
X46506Y1363091D01*
X46369Y1362894D01*
G01X46784Y1358484D02*
X46644Y1358288D01*
X46506Y1358091D01*
X46369Y1357894D01*
G01Y1357500D02*
Y1357894D01*
G01Y1362500D02*
Y1362894D01*
G01X46506Y1365591D02*
Y1365197D01*
G01Y1362441D02*
Y1362047D01*
G01Y1359291D02*
Y1358898D01*
G01X50987Y1357500D02*
Y1357894D01*
G01Y1362500D02*
Y1362894D01*
G01Y1362500D02*
X50909Y1361909D01*
G01X50987Y1357894D02*
X50909Y1358484D01*
G01X50987Y1362894D02*
X50909Y1363484D01*
G01X46506Y1358898D02*
X46538Y1358800D01*
X46626Y1358728D01*
X46753Y1358701D01*
G01X46506Y1362047D02*
X46538Y1361950D01*
X46626Y1361878D01*
X46753Y1361850D01*
G01X46506Y1365197D02*
X46538Y1365100D01*
X46626Y1365028D01*
X46753Y1365000D01*
G01X46369Y1362500D02*
X46506Y1362302D01*
X46644Y1362106D01*
X46784Y1361909D01*
G01X46369Y1357500D02*
X52956D01*
G01Y1357894D02*
X46369D01*
G01X52529Y1358484D02*
X46784D01*
G01X46753Y1358701D02*
X52838D01*
G01X53118Y1358898D02*
X46506D01*
G01Y1359291D02*
X53118D01*
G01X46753Y1359488D02*
X52838D01*
G01X46753Y1361850D02*
X52838D01*
G01X46784Y1361909D02*
X52529D01*
G01X53118Y1362047D02*
X46506D01*
G01Y1362441D02*
X53118D01*
G01X46369Y1362500D02*
X52956D01*
G01X46753Y1362638D02*
X52838D01*
G01X52956Y1362894D02*
X46369D01*
G01X52529Y1363484D02*
X46784D01*
G01X46753Y1365000D02*
X52838D01*
G01X53118Y1365197D02*
X46506D01*
G01X46753Y1359488D02*
X46626Y1359460D01*
X46537Y1359387D01*
X46506Y1359291D01*
G01X46753Y1362638D02*
X46626Y1362610D01*
X46537Y1362537D01*
X46506Y1362441D01*
G01X135335Y1502165D02*
X108760D01*
G01D02*
Y1482087D01*
G01D02*
X135335D01*
G01X90453Y1648801D02*
X89662Y1647524D01*
G01X89697Y1649670D02*
X88254Y1647524D01*
G01X79783Y1647008D02*
X79886Y1647377D01*
X79982Y1647706D01*
X80063Y1647969D01*
X80115Y1648134D01*
X80132Y1648189D01*
G01X64646Y1659587D02*
Y1633189D01*
G01X66929Y1646122D02*
Y1654469D01*
G01X68670Y1651531D02*
Y1647524D01*
G01X70044Y1639882D02*
Y1638307D01*
G01X70079D02*
Y1639882D01*
G01X70103Y1638307D02*
Y1639882D01*
G01X70110Y1650048D02*
Y1647524D01*
G01X70866Y1651870D02*
Y1648091D01*
G01X71426Y1639882D02*
Y1638307D01*
G01X71541Y1647524D02*
Y1650048D01*
G01X71796Y1638307D02*
Y1639882D01*
G01X73000Y1650048D02*
Y1647524D01*
G01X73873Y1639882D02*
Y1638307D01*
G01X74243D02*
Y1639882D01*
G01X74430Y1647524D02*
Y1650048D01*
G01X75567Y1639882D02*
Y1638307D01*
G01X75591Y1639882D02*
Y1638307D01*
G01X75625D02*
Y1639882D01*
G01X75823Y1650453D02*
Y1647524D01*
G01X81024Y1646122D02*
Y1633189D01*
G01X81622Y1647524D02*
Y1653278D01*
G01X83082D02*
Y1647524D01*
G01X94488Y1646122D02*
Y1660000D01*
G01X84041Y1648189D02*
X84059Y1648133D01*
X84111Y1647967D01*
X84190Y1647709D01*
X84285Y1647381D01*
X84390Y1647008D01*
G01X91426Y1649679D02*
X92747Y1647524D01*
G01X90453Y1648801D02*
X91198Y1647524D01*
G01X64646Y1633189D02*
X81024D01*
G01X75000Y1637520D02*
X70669D01*
G01X75625Y1638307D02*
X70044D01*
G01Y1639882D02*
X75625D01*
G01X70669Y1640669D02*
X75000D01*
G01X81024Y1643366D02*
X64646D01*
G01X79783Y1647008D02*
X84390D01*
G01X89662Y1647524D02*
X88254D01*
G01X92747D02*
X91198D01*
G01X83082D02*
X81622D01*
G01X75823D02*
X74430D01*
G01X73000D02*
X71541D01*
G01X70110D02*
X68670D01*
G01X94488Y1648091D02*
X70866D01*
G01X84041Y1648189D02*
X80132D01*
G01X70669Y1640669D02*
G03Y1637520I0J-1574D01*
G01X77278Y1647733D02*
G03X80324Y1647734I1522J2362D01*
G01X75000Y1637520D02*
G03Y1640669I0J1574D01*
G01X76757Y1648298D02*
G03X77278Y1647733I1351J723D01*
G01X78029Y1648633D02*
G03X79502I737J277D01*
G01X80324Y1647734D02*
G03X80845Y1648300I-831J1288D01*
G01X84390Y1647008D02*
G03Y1654803I-2304J3897D01*
G01X79783D02*
G03Y1647008I2304J-3898D01*
G01X85591Y1650905D02*
G03I-3505J0D01*
G01X80132Y1653622D02*
G03Y1648189I1954J-2717D01*
G01X84041D02*
G03Y1653622I-1954J2717D01*
G01X83934Y1648341D02*
G03X85672Y1647324I1806J1094D01*
G01X87254Y1647611D02*
G03X88098Y1648680I-703J1423D01*
G01X85669Y1647324D02*
G03X87254Y1647611I262J3073D01*
G01X40493Y1646854D02*
X40457Y1646530D01*
X40463Y1646289D01*
X40519Y1646153D01*
G01X40493Y1646852D02*
X40547Y1647230D01*
G01X40551Y1654469D02*
Y1647303D01*
G01X40519Y1646153D02*
X40462Y1646293D01*
X40457Y1646533D01*
G01X94488Y1646122D02*
X40551D01*
G01Y1647303D02*
X66929D01*
G01X52529Y1702421D02*
X52956Y1703012D01*
G01X52529Y1697421D02*
X52956Y1698012D01*
G01X52529Y1692421D02*
X52956Y1693012D01*
G01X52529Y1687421D02*
X52956Y1688012D01*
G01X52529Y1682421D02*
X52956Y1683012D01*
G01X52529Y1672421D02*
X52956Y1673012D01*
G01X52529Y1667421D02*
X52956Y1668012D01*
G01X52112Y1703012D02*
X51839Y1702421D01*
G01X52112Y1698012D02*
X51839Y1697421D01*
G01X52112Y1693012D02*
X51839Y1692421D01*
G01X52112Y1688012D02*
X51839Y1687421D01*
G01X52112Y1683012D02*
X51839Y1682421D01*
G01X52112Y1673012D02*
X51839Y1672421D01*
G01X52112Y1668012D02*
X51839Y1667421D01*
G01X51428Y1704567D02*
X51417Y1704469D01*
X51389Y1704396D01*
X51351Y1704370D01*
G01X51428Y1701417D02*
X51417Y1701319D01*
X51389Y1701247D01*
X51351Y1701220D01*
G01X51428Y1698268D02*
X51417Y1698169D01*
X51389Y1698097D01*
X51351Y1698071D01*
G01X51428Y1695118D02*
X51417Y1695020D01*
X51389Y1694948D01*
X51351Y1694921D01*
G01X51428Y1691969D02*
X51417Y1691870D01*
X51389Y1691798D01*
X51351Y1691772D01*
G01X51428Y1688819D02*
X51417Y1688720D01*
X51389Y1688648D01*
X51351Y1688622D01*
G01X51428Y1685669D02*
X51417Y1685571D01*
X51389Y1685499D01*
X51351Y1685472D01*
G01X51428Y1682520D02*
X51417Y1682421D01*
X51389Y1682349D01*
X51351Y1682323D01*
G01X51428Y1679370D02*
X51417Y1679272D01*
X51389Y1679200D01*
X51351Y1679173D01*
G01X51428Y1676220D02*
X51417Y1676122D01*
X51389Y1676050D01*
X51351Y1676024D01*
G01X51428Y1673071D02*
X51417Y1672972D01*
X51389Y1672900D01*
X51351Y1672874D01*
G01X51428Y1669921D02*
X51417Y1669823D01*
X51389Y1669751D01*
X51351Y1669724D01*
G01X51428Y1701811D02*
Y1701417D01*
G01Y1704961D02*
Y1704567D01*
G01Y1698661D02*
Y1698268D01*
G01Y1695512D02*
Y1695118D01*
G01Y1692362D02*
Y1691969D01*
G01Y1689213D02*
Y1688819D01*
G01Y1686063D02*
Y1685669D01*
G01Y1682913D02*
Y1682520D01*
G01Y1679764D02*
Y1679370D01*
G01Y1676614D02*
Y1676220D01*
G01Y1673465D02*
Y1673071D01*
G01Y1670315D02*
Y1669921D01*
G01Y1667165D02*
Y1666772D01*
G01X51941D02*
Y1667165D01*
G01Y1669921D02*
Y1670315D01*
G01Y1676220D02*
Y1676614D01*
G01Y1673071D02*
Y1673465D01*
G01Y1679370D02*
Y1679764D01*
G01Y1685669D02*
Y1686063D01*
G01Y1682520D02*
Y1682913D01*
G01Y1688819D02*
Y1689213D01*
G01Y1695118D02*
Y1695512D01*
G01Y1691969D02*
Y1692362D01*
G01Y1698268D02*
Y1698661D01*
G01Y1701417D02*
Y1701811D01*
G01Y1704567D02*
Y1704961D01*
G01X52112Y1703406D02*
Y1703012D01*
G01Y1698406D02*
Y1698012D01*
G01Y1693406D02*
Y1693012D01*
G01Y1688406D02*
Y1688012D01*
G01Y1683406D02*
Y1683012D01*
G01Y1673406D02*
Y1673012D01*
G01Y1668406D02*
Y1668012D01*
G01X52956Y1703406D02*
Y1703012D01*
G01Y1698406D02*
Y1698012D01*
G01Y1693406D02*
Y1693012D01*
G01Y1688406D02*
Y1688012D01*
G01Y1683406D02*
Y1683012D01*
G01Y1673406D02*
Y1673012D01*
G01Y1668406D02*
Y1668012D01*
G01X53118Y1666772D02*
Y1667165D01*
G01Y1669921D02*
Y1670315D01*
G01Y1676220D02*
Y1676614D01*
G01Y1673071D02*
Y1673465D01*
G01Y1679370D02*
Y1679764D01*
G01Y1685669D02*
Y1686063D01*
G01Y1682520D02*
Y1682913D01*
G01Y1688819D02*
Y1689213D01*
G01Y1695118D02*
Y1695512D01*
G01Y1691969D02*
Y1692362D01*
G01Y1698268D02*
Y1698661D01*
G01Y1701417D02*
Y1701811D01*
G01Y1704567D02*
Y1704961D01*
G01X51428Y1666772D02*
X51417Y1666673D01*
X51389Y1666601D01*
X51351Y1666575D01*
G01X51941Y1667165D02*
X51938Y1667204D01*
X51930Y1667240D01*
X51917Y1667274D01*
X51900Y1667304D01*
X51879Y1667329D01*
X51856Y1667347D01*
X51830Y1667358D01*
X51802Y1667362D01*
G01X51941Y1670315D02*
X51938Y1670353D01*
X51930Y1670390D01*
X51917Y1670424D01*
X51900Y1670454D01*
X51879Y1670478D01*
X51856Y1670496D01*
X51830Y1670508D01*
X51802Y1670512D01*
G01X51941Y1673465D02*
X51938Y1673503D01*
X51930Y1673539D01*
X51917Y1673573D01*
X51900Y1673604D01*
X51879Y1673628D01*
X51856Y1673646D01*
X51830Y1673657D01*
X51802Y1673661D01*
G01X51941Y1676614D02*
X51938Y1676652D01*
X51930Y1676689D01*
X51917Y1676723D01*
X51900Y1676753D01*
X51879Y1676778D01*
X51856Y1676796D01*
X51830Y1676807D01*
X51802Y1676811D01*
G01X51941Y1679764D02*
X51938Y1679802D01*
X51930Y1679839D01*
X51917Y1679872D01*
X51900Y1679903D01*
X51879Y1679927D01*
X51856Y1679945D01*
X51830Y1679957D01*
X51802Y1679961D01*
G01X51941Y1682913D02*
X51938Y1682952D01*
X51930Y1682988D01*
X51917Y1683022D01*
X51900Y1683052D01*
X51879Y1683077D01*
X51856Y1683095D01*
X51830Y1683106D01*
X51802Y1683110D01*
G01X51941Y1686063D02*
X51938Y1686101D01*
X51930Y1686138D01*
X51917Y1686172D01*
X51900Y1686202D01*
X51879Y1686226D01*
X51856Y1686244D01*
X51830Y1686256D01*
X51802Y1686260D01*
G01X51941Y1689213D02*
X51938Y1689251D01*
X51930Y1689287D01*
X51917Y1689321D01*
X51900Y1689352D01*
X51879Y1689376D01*
X51856Y1689394D01*
X51830Y1689406D01*
X51802Y1689409D01*
G01X51941Y1692362D02*
X51938Y1692400D01*
X51930Y1692437D01*
X51917Y1692471D01*
X51900Y1692501D01*
X51879Y1692526D01*
X51856Y1692544D01*
X51830Y1692555D01*
X51802Y1692559D01*
G01X51941Y1695512D02*
X51938Y1695550D01*
X51930Y1695587D01*
X51917Y1695620D01*
X51900Y1695651D01*
X51879Y1695675D01*
X51856Y1695693D01*
X51830Y1695705D01*
X51802Y1695709D01*
G01X51941Y1698661D02*
X51938Y1698700D01*
X51930Y1698736D01*
X51917Y1698770D01*
X51900Y1698800D01*
X51879Y1698825D01*
X51856Y1698843D01*
X51830Y1698854D01*
X51802Y1698858D01*
G01X51941Y1701811D02*
X51938Y1701849D01*
X51930Y1701886D01*
X51917Y1701920D01*
X51900Y1701950D01*
X51879Y1701974D01*
X51856Y1701993D01*
X51830Y1702004D01*
X51802Y1702008D01*
G01X51941Y1704961D02*
X51938Y1704999D01*
X51930Y1705035D01*
X51917Y1705069D01*
X51900Y1705100D01*
X51879Y1705124D01*
X51856Y1705142D01*
X51830Y1705154D01*
X51802Y1705157D01*
G01X69213Y1714902D02*
Y1698366D01*
G01Y1696004D02*
Y1679469D01*
G01X74803Y1679783D02*
Y1676634D01*
G01X75170Y1705157D02*
Y1704370D01*
G01Y1702008D02*
Y1701220D01*
G01Y1695709D02*
Y1694921D01*
G01Y1698858D02*
Y1698071D01*
G01Y1692559D02*
Y1691772D01*
G01Y1686260D02*
Y1685472D01*
G01Y1689409D02*
Y1688622D01*
G01Y1683110D02*
Y1682323D01*
G01Y1679961D02*
Y1679173D01*
G01Y1673661D02*
Y1672874D01*
G01Y1676811D02*
Y1676024D01*
G01Y1670512D02*
Y1669724D01*
G01Y1667362D02*
Y1666575D01*
G01X75197Y1705157D02*
Y1704370D01*
G01Y1702008D02*
Y1701220D01*
G01Y1695709D02*
Y1694921D01*
G01Y1698858D02*
Y1698071D01*
G01Y1692559D02*
Y1691772D01*
G01Y1686260D02*
Y1685472D01*
G01Y1689409D02*
Y1688622D01*
G01Y1683110D02*
Y1682323D01*
G01Y1679961D02*
Y1679173D01*
G01Y1673661D02*
Y1672874D01*
G01Y1676811D02*
Y1676024D01*
G01Y1670512D02*
Y1669724D01*
G01Y1667362D02*
Y1666575D01*
G01X75573Y1705157D02*
Y1704370D01*
G01Y1702008D02*
Y1701220D01*
G01Y1695709D02*
Y1694921D01*
G01Y1698858D02*
Y1698071D01*
G01Y1692559D02*
Y1691772D01*
G01Y1686260D02*
Y1685472D01*
G01Y1689409D02*
Y1688622D01*
G01Y1683110D02*
Y1682323D01*
G01Y1679961D02*
Y1679173D01*
G01Y1673661D02*
Y1672874D01*
G01Y1676811D02*
Y1676024D01*
G01Y1670512D02*
Y1669724D01*
G01Y1667362D02*
Y1666575D01*
G01X75787Y1703996D02*
Y1702421D01*
G01Y1698996D02*
Y1697421D01*
G01Y1693996D02*
Y1692421D01*
G01Y1688996D02*
Y1687421D01*
G01Y1683996D02*
Y1682421D01*
G01Y1679783D02*
Y1676634D01*
G01Y1673996D02*
Y1672421D01*
G01Y1668996D02*
Y1667421D01*
G01X76772Y1704783D02*
Y1701634D01*
G01Y1699783D02*
Y1696634D01*
G01Y1694783D02*
Y1691634D01*
G01Y1689783D02*
Y1686634D01*
G01Y1684783D02*
Y1681634D01*
G01Y1678996D02*
Y1677421D01*
G01Y1674783D02*
Y1671634D01*
G01Y1669783D02*
Y1666634D01*
G01X77756Y1704783D02*
Y1701634D01*
G01Y1699783D02*
Y1696634D01*
G01Y1694783D02*
Y1691634D01*
G01Y1689783D02*
Y1686634D01*
G01Y1684783D02*
Y1681634D01*
G01Y1674783D02*
Y1671634D01*
G01Y1669783D02*
Y1666634D01*
G01X78740Y1703996D02*
Y1702421D01*
G01Y1698996D02*
Y1697421D01*
G01Y1693996D02*
Y1692421D01*
G01Y1688996D02*
Y1687421D01*
G01Y1683996D02*
Y1682421D01*
G01Y1673996D02*
Y1672421D01*
G01Y1668996D02*
Y1667421D01*
G01X78935Y1666575D02*
Y1667362D01*
G01Y1669724D02*
Y1670512D01*
G01Y1672874D02*
Y1673661D01*
G01Y1676024D02*
Y1676811D01*
G01Y1679173D02*
Y1679961D01*
G01Y1682323D02*
Y1683110D01*
G01Y1685472D02*
Y1686260D01*
G01Y1688622D02*
Y1689409D01*
G01Y1691772D02*
Y1692559D01*
G01Y1694921D02*
Y1695709D01*
G01Y1698071D02*
Y1698858D01*
G01Y1701220D02*
Y1702008D01*
G01Y1704370D02*
Y1705157D01*
G01X79921Y1677421D02*
Y1678996D01*
G01X80919Y1666575D02*
Y1667362D01*
G01Y1669724D02*
Y1670512D01*
G01Y1672874D02*
Y1673661D01*
G01Y1676024D02*
Y1676811D01*
G01Y1679173D02*
Y1679961D01*
G01Y1682323D02*
Y1683110D01*
G01Y1685472D02*
Y1686260D01*
G01Y1688622D02*
Y1689409D01*
G01Y1691772D02*
Y1692559D01*
G01Y1694921D02*
Y1695709D01*
G01Y1698071D02*
Y1698858D01*
G01Y1701220D02*
Y1702008D01*
G01Y1704370D02*
Y1705157D01*
G01X81890Y1667421D02*
Y1668996D01*
G01Y1672421D02*
Y1673996D01*
G01Y1682421D02*
Y1683996D01*
G01Y1687421D02*
Y1688996D01*
G01Y1692421D02*
Y1693996D01*
G01Y1697421D02*
Y1698996D01*
G01Y1702421D02*
Y1703996D01*
G01X82570Y1705157D02*
Y1704370D01*
G01Y1702008D02*
Y1701220D01*
G01Y1695709D02*
Y1694921D01*
G01Y1698858D02*
Y1698071D01*
G01Y1692559D02*
Y1691772D01*
G01Y1686260D02*
Y1685472D01*
G01Y1689409D02*
Y1688622D01*
G01Y1683110D02*
Y1682323D01*
G01Y1679961D02*
Y1679173D01*
G01Y1673661D02*
Y1672874D01*
G01Y1676811D02*
Y1676024D01*
G01Y1670512D02*
Y1669724D01*
G01Y1667362D02*
Y1666575D01*
G01X84298Y1667362D02*
Y1669724D01*
G01Y1670512D02*
Y1672874D01*
G01Y1673661D02*
Y1676024D01*
G01Y1676811D02*
Y1679173D01*
G01Y1679961D02*
Y1682323D01*
G01Y1683110D02*
Y1685472D01*
G01Y1686260D02*
Y1688622D01*
G01Y1689409D02*
Y1691772D01*
G01Y1692559D02*
Y1694921D01*
G01Y1695709D02*
Y1698071D01*
G01Y1698858D02*
Y1701220D01*
G01Y1702008D02*
Y1704370D01*
G01Y1705157D02*
Y1707520D01*
G01X85237Y1705157D02*
Y1704370D01*
G01Y1702008D02*
Y1701220D01*
G01Y1695709D02*
Y1694921D01*
G01Y1698858D02*
Y1698071D01*
G01Y1692559D02*
Y1691772D01*
G01Y1686260D02*
Y1685472D01*
G01Y1689409D02*
Y1688622D01*
G01Y1683110D02*
Y1682323D01*
G01Y1679961D02*
Y1679173D01*
G01Y1673661D02*
Y1672874D01*
G01Y1676811D02*
Y1676024D01*
G01Y1670512D02*
Y1669724D01*
G01Y1667362D02*
Y1666575D01*
G01X85384Y1705157D02*
Y1704370D01*
G01Y1702008D02*
Y1701220D01*
G01Y1695709D02*
Y1694921D01*
G01Y1698858D02*
Y1698071D01*
G01Y1692559D02*
Y1691772D01*
G01Y1686260D02*
Y1685472D01*
G01Y1689409D02*
Y1688622D01*
G01Y1683110D02*
Y1682323D01*
G01Y1679961D02*
Y1679173D01*
G01Y1673661D02*
Y1672874D01*
G01Y1676811D02*
Y1676024D01*
G01Y1670512D02*
Y1669724D01*
G01Y1667362D02*
Y1666575D01*
G01X86976Y1705157D02*
Y1704370D01*
G01Y1702008D02*
Y1701220D01*
G01Y1695709D02*
Y1694921D01*
G01Y1698858D02*
Y1698071D01*
G01Y1692559D02*
Y1691772D01*
G01Y1686260D02*
Y1685472D01*
G01Y1689409D02*
Y1688622D01*
G01Y1683110D02*
Y1682323D01*
G01Y1679961D02*
Y1679173D01*
G01Y1673661D02*
Y1672874D01*
G01Y1676811D02*
Y1676024D01*
G01Y1670512D02*
Y1669724D01*
G01Y1667362D02*
Y1666575D01*
G01X87918D02*
Y1667362D01*
G01Y1669724D02*
Y1670512D01*
G01Y1672874D02*
Y1673661D01*
G01Y1676024D02*
Y1676811D01*
G01Y1679173D02*
Y1679961D01*
G01Y1682323D02*
Y1683110D01*
G01Y1685472D02*
Y1686260D01*
G01Y1688622D02*
Y1689409D01*
G01Y1691772D02*
Y1692559D01*
G01Y1694921D02*
Y1695709D01*
G01Y1698071D02*
Y1698858D01*
G01Y1701220D02*
Y1702008D01*
G01Y1704370D02*
Y1705157D01*
G01X90754Y1666575D02*
Y1667362D01*
G01Y1669724D02*
Y1670512D01*
G01Y1672874D02*
Y1673661D01*
G01Y1676024D02*
Y1676811D01*
G01Y1679173D02*
Y1679961D01*
G01Y1682323D02*
Y1683110D01*
G01Y1685472D02*
Y1686260D01*
G01Y1688622D02*
Y1689409D01*
G01Y1691772D02*
Y1692559D01*
G01Y1694921D02*
Y1695709D01*
G01Y1698071D02*
Y1698858D01*
G01Y1701220D02*
Y1702008D01*
G01Y1704370D02*
Y1705157D01*
G01X90943D02*
Y1704370D01*
G01Y1702008D02*
Y1701220D01*
G01Y1695709D02*
Y1694921D01*
G01Y1698858D02*
Y1698071D01*
G01Y1692559D02*
Y1691772D01*
G01Y1686260D02*
Y1685472D01*
G01Y1689409D02*
Y1688622D01*
G01Y1683110D02*
Y1682323D01*
G01Y1679961D02*
Y1679173D01*
G01Y1673661D02*
Y1672874D01*
G01Y1676811D02*
Y1676024D01*
G01Y1670512D02*
Y1669724D01*
G01Y1667362D02*
Y1666575D01*
G01X92717Y1705157D02*
Y1704370D01*
G01Y1702008D02*
Y1701220D01*
G01Y1695709D02*
Y1694921D01*
G01Y1698858D02*
Y1698071D01*
G01Y1692559D02*
Y1691772D01*
G01Y1686260D02*
Y1685472D01*
G01Y1689409D02*
Y1688622D01*
G01Y1683110D02*
Y1682323D01*
G01Y1679961D02*
Y1679173D01*
G01Y1673661D02*
Y1672874D01*
G01Y1676811D02*
Y1676024D01*
G01Y1670512D02*
Y1669724D01*
G01Y1667362D02*
Y1666575D01*
G01X51839Y1668996D02*
X52112Y1668406D01*
G01X51839Y1673996D02*
X52112Y1673406D01*
G01X51839Y1683996D02*
X52112Y1683406D01*
G01X51839Y1688996D02*
X52112Y1688406D01*
G01X51839Y1693996D02*
X52112Y1693406D01*
G01X51839Y1698996D02*
X52112Y1698406D01*
G01X51839Y1703996D02*
X52112Y1703406D01*
G01X52529Y1668996D02*
X52956Y1668406D01*
G01X52529Y1673996D02*
X52956Y1673406D01*
G01X52529Y1683996D02*
X52956Y1683406D01*
G01X52529Y1688996D02*
X52956Y1688406D01*
G01X52529Y1693996D02*
X52956Y1693406D01*
G01X52529Y1698996D02*
X52956Y1698406D01*
G01X52529Y1703996D02*
X52956Y1703406D01*
G01X51351Y1667362D02*
X51389Y1667336D01*
X51417Y1667264D01*
X51428Y1667165D01*
G01X51351Y1670512D02*
X51389Y1670485D01*
X51417Y1670413D01*
X51428Y1670315D01*
G01X51351Y1673661D02*
X51389Y1673635D01*
X51417Y1673563D01*
X51428Y1673465D01*
G01X51351Y1676811D02*
X51389Y1676785D01*
X51417Y1676713D01*
X51428Y1676614D01*
G01X51351Y1679961D02*
X51389Y1679934D01*
X51417Y1679862D01*
X51428Y1679764D01*
G01X51351Y1683110D02*
X51389Y1683084D01*
X51417Y1683012D01*
X51428Y1682913D01*
G01X51351Y1686260D02*
X51389Y1686233D01*
X51417Y1686161D01*
X51428Y1686063D01*
G01X51351Y1689409D02*
X51389Y1689383D01*
X51417Y1689311D01*
X51428Y1689213D01*
G01X51351Y1692559D02*
X51389Y1692533D01*
X51417Y1692461D01*
X51428Y1692362D01*
G01X51351Y1695709D02*
X51389Y1695682D01*
X51417Y1695610D01*
X51428Y1695512D01*
G01X51351Y1698858D02*
X51389Y1698832D01*
X51417Y1698760D01*
X51428Y1698661D01*
G01X51351Y1702008D02*
X51389Y1701981D01*
X51417Y1701909D01*
X51428Y1701811D01*
G01X51351Y1705157D02*
X51389Y1705131D01*
X51417Y1705059D01*
X51428Y1704961D01*
G01X92717Y1666575D02*
X85384D01*
G01X85237D02*
X73228D01*
G01X77756Y1666634D02*
X76772D01*
G01X77756Y1666831D02*
X76772D01*
G01X77756Y1667224D02*
X76772D01*
G01X85237Y1667362D02*
X73228D01*
G01X85384D02*
X92717D01*
G01X81890Y1667421D02*
X74724D01*
G01X81890Y1668996D02*
X74724D01*
G01X77756Y1669193D02*
X76772D01*
G01X77756Y1669587D02*
X76772D01*
G01X92717Y1669724D02*
X85384D01*
G01X85237D02*
X73228D01*
G01X77756Y1669783D02*
X76772D01*
G01X85237Y1670512D02*
X73228D01*
G01X85384D02*
X92717D01*
G01X77756Y1671634D02*
X76772D01*
G01X77756Y1671831D02*
X76772D01*
G01X77756Y1672224D02*
X76772D01*
G01X74724Y1672421D02*
X81890D01*
G01X92717Y1672874D02*
X85384D01*
G01X85237D02*
X73228D01*
G01X85237Y1673661D02*
X73228D01*
G01X85384D02*
X92717D01*
G01X74724Y1673996D02*
X81890D01*
G01X77756Y1674193D02*
X76772D01*
G01X77756Y1674587D02*
X76772D01*
G01X77756Y1674783D02*
X76772D01*
G01X73228Y1676004D02*
X74331D01*
G01X92717Y1676024D02*
X85384D01*
G01X85237D02*
X73228D01*
G01X75787Y1676634D02*
X74803D01*
G01X85237Y1676811D02*
X73228D01*
G01X85384D02*
X92717D01*
G01X75787Y1676831D02*
X74803D01*
G01X75787Y1677224D02*
X74803D01*
G01X74331Y1677421D02*
X79921D01*
G01X74331Y1678996D02*
X79921D01*
G01X92717Y1679173D02*
X85384D01*
G01X85237D02*
X73228D01*
G01X75787Y1679193D02*
X74803D01*
G01X75787Y1679587D02*
X74803D01*
G01X75787Y1679783D02*
X74803D01*
G01X85237Y1679961D02*
X73228D01*
G01X85384D02*
X92717D01*
G01X73228Y1680413D02*
X74331D01*
G01X77756Y1681634D02*
X76772D01*
G01X77756Y1681831D02*
X76772D01*
G01X77756Y1682224D02*
X76772D01*
G01X92717Y1682323D02*
X85384D01*
G01X85237D02*
X73228D01*
G01X74724Y1682421D02*
X81890D01*
G01X85237Y1683110D02*
X73228D01*
G01X85384D02*
X92717D01*
G01X74724Y1683996D02*
X81890D01*
G01X77756Y1684193D02*
X76772D01*
G01X77756Y1684587D02*
X76772D01*
G01X77756Y1684783D02*
X76772D01*
G01X92717Y1685472D02*
X85384D01*
G01X85237D02*
X73228D01*
G01X85237Y1686260D02*
X73228D01*
G01X85384D02*
X92717D01*
G01X77756Y1686634D02*
X76772D01*
G01X77756Y1686831D02*
X76772D01*
G01X77756Y1687224D02*
X76772D01*
G01X74724Y1687421D02*
X81890D01*
G01X92717Y1688622D02*
X85384D01*
G01X85237D02*
X73228D01*
G01X74724Y1688996D02*
X81890D01*
G01X77756Y1689193D02*
X76772D01*
G01X85237Y1689409D02*
X73228D01*
G01X85384D02*
X92717D01*
G01X77756Y1689587D02*
X76772D01*
G01X77756Y1689783D02*
X76772D01*
G01X77756Y1691634D02*
X76772D01*
G01X92717Y1691772D02*
X85384D01*
G01X85237D02*
X73228D01*
G01X77756Y1691831D02*
X76772D01*
G01X77756Y1692224D02*
X76772D01*
G01X74724Y1692421D02*
X81890D01*
G01X85237Y1692559D02*
X73228D01*
G01X85384D02*
X92717D01*
G01X74724Y1693996D02*
X81890D01*
G01X77756Y1694193D02*
X76772D01*
G01X77756Y1694587D02*
X76772D01*
G01X77756Y1694783D02*
X76772D01*
G01X92717Y1694921D02*
X85384D01*
G01X85237D02*
X73228D01*
G01X85237Y1695709D02*
X73228D01*
G01X85384D02*
X92717D01*
G01X51802Y1666575D02*
X51829Y1666578D01*
X51855Y1666589D01*
X51879Y1666607D01*
X51900Y1666632D01*
X51917Y1666662D01*
X51930Y1666696D01*
X51938Y1666733D01*
X51941Y1666772D01*
G01X51802Y1669724D02*
X51829Y1669728D01*
X51855Y1669739D01*
X51879Y1669757D01*
X51900Y1669782D01*
X51917Y1669812D01*
X51930Y1669846D01*
X51938Y1669882D01*
X51941Y1669921D01*
G01X51802Y1672874D02*
X51829Y1672878D01*
X51855Y1672889D01*
X51879Y1672907D01*
X51900Y1672931D01*
X51917Y1672961D01*
X51930Y1672995D01*
X51938Y1673032D01*
X51941Y1673071D01*
G01X51802Y1676024D02*
X51829Y1676027D01*
X51855Y1676038D01*
X51879Y1676056D01*
X51900Y1676081D01*
X51917Y1676111D01*
X51930Y1676145D01*
X51938Y1676181D01*
X51941Y1676220D01*
G01X51802Y1679173D02*
X51829Y1679177D01*
X51855Y1679188D01*
X51879Y1679206D01*
X51900Y1679231D01*
X51917Y1679261D01*
X51930Y1679294D01*
X51938Y1679331D01*
X51941Y1679370D01*
G01X51802Y1682323D02*
X51829Y1682326D01*
X51855Y1682337D01*
X51879Y1682356D01*
X51900Y1682380D01*
X51917Y1682410D01*
X51930Y1682444D01*
X51938Y1682481D01*
X51941Y1682520D01*
G01X51802Y1685472D02*
X51829Y1685476D01*
X51855Y1685487D01*
X51879Y1685505D01*
X51900Y1685530D01*
X51917Y1685560D01*
X51930Y1685594D01*
X51938Y1685630D01*
X51941Y1685669D01*
G01X51802Y1688622D02*
X51829Y1688626D01*
X51855Y1688637D01*
X51879Y1688655D01*
X51900Y1688680D01*
X51917Y1688709D01*
X51930Y1688743D01*
X51938Y1688780D01*
X51941Y1688819D01*
G01X51802Y1691772D02*
X51829Y1691775D01*
X51855Y1691786D01*
X51879Y1691804D01*
X51900Y1691829D01*
X51917Y1691859D01*
X51930Y1691893D01*
X51938Y1691930D01*
X51941Y1691969D01*
G01X51802Y1694921D02*
X51829Y1694925D01*
X51855Y1694936D01*
X51879Y1694954D01*
X51900Y1694979D01*
X51917Y1695009D01*
X51930Y1695043D01*
X51938Y1695079D01*
X51941Y1695118D01*
G01X51802Y1698071D02*
X51829Y1698074D01*
X51855Y1698085D01*
X51879Y1698104D01*
X51900Y1698128D01*
X51917Y1698158D01*
X51930Y1698192D01*
X51938Y1698229D01*
X51941Y1698268D01*
G01X51802Y1701220D02*
X51829Y1701224D01*
X51855Y1701235D01*
X51879Y1701253D01*
X51900Y1701278D01*
X51917Y1701308D01*
X51930Y1701342D01*
X51938Y1701378D01*
X51941Y1701417D01*
G01X51802Y1704370D02*
X51829Y1704374D01*
X51855Y1704385D01*
X51879Y1704403D01*
X51900Y1704428D01*
X51917Y1704457D01*
X51930Y1704491D01*
X51938Y1704528D01*
X51941Y1704567D01*
G01X77756Y1696634D02*
X76772D01*
G01X77756Y1696831D02*
X76772D01*
G01X77756Y1697224D02*
X76772D01*
G01X74724Y1697421D02*
X81890D01*
G01X92717Y1698071D02*
X85384D01*
G01X85237D02*
X73228D01*
G01X85237Y1698858D02*
X73228D01*
G01X85384D02*
X92717D01*
G01X74724Y1698996D02*
X81890D01*
G01X77756Y1699193D02*
X76772D01*
G01X77756Y1699587D02*
X76772D01*
G01X77756Y1699783D02*
X76772D01*
G01X92717Y1701220D02*
X85384D01*
G01X85237D02*
X73228D01*
G01X77756Y1701634D02*
X76772D01*
G01X77756Y1701831D02*
X76772D01*
G01X85237Y1702008D02*
X73228D01*
G01X85384D02*
X92717D01*
G01X77756Y1702224D02*
X76772D01*
G01X74724Y1702421D02*
X81890D01*
G01X74724Y1703996D02*
X81890D01*
G01X77756Y1704193D02*
X76772D01*
G01X92717Y1704370D02*
X85384D01*
G01X85237D02*
X73228D01*
G01X77756Y1704587D02*
X76772D01*
G01X77756Y1704783D02*
X76772D01*
G01X85237Y1705157D02*
X73228D01*
G01X85384D02*
X92717D01*
G01X74331Y1669390D02*
G03X74724Y1668996I394J0D01*
G01Y1667421D02*
G03X74331Y1667028I1J-394D01*
G01Y1674390D02*
G03X74724Y1673996I394J0D01*
G01Y1672421D02*
G03X74331Y1672028I1J-394D01*
G01Y1684390D02*
G03X74724Y1683996I394J0D01*
G01Y1682421D02*
G03X74331Y1682028I1J-394D01*
G01Y1694390D02*
G03X74724Y1693996I394J0D01*
G01Y1692421D02*
G03X74331Y1692028I1J-394D01*
G01Y1689390D02*
G03X74724Y1688996I394J0D01*
G01Y1687421D02*
G03X74331Y1687028I1J-394D01*
G01Y1699390D02*
G03X74724Y1698996I394J0D01*
G01Y1697421D02*
G03X74331Y1697028I1J-394D01*
G01Y1704390D02*
G03X74724Y1703996I394J0D01*
G01Y1702421D02*
G03X74331Y1702028I1J-394D01*
G01X46784Y1703996D02*
X46644Y1703800D01*
X46506Y1703603D01*
X46369Y1703406D01*
G01X46784Y1698996D02*
X46644Y1698800D01*
X46506Y1698603D01*
X46369Y1698406D01*
G01X46784Y1693996D02*
X46644Y1693800D01*
X46506Y1693603D01*
X46369Y1693406D01*
G01X46784Y1688996D02*
X46644Y1688800D01*
X46506Y1688603D01*
X46369Y1688406D01*
G01X46784Y1683996D02*
X46644Y1683800D01*
X46506Y1683603D01*
X46369Y1683406D01*
G01X44815Y1678996D02*
X44676Y1678800D01*
X44538Y1678603D01*
X44401Y1678406D01*
G01X46784Y1673996D02*
X46644Y1673800D01*
X46506Y1673603D01*
X46369Y1673406D01*
G01X46784Y1668996D02*
X46644Y1668800D01*
X46506Y1668603D01*
X46369Y1668406D01*
G01X50560Y1677421D02*
X50987Y1678012D01*
G01X50143D02*
X49871Y1677421D01*
G01X46506Y1704961D02*
X46539Y1705059D01*
X46628Y1705130D01*
X46753Y1705157D01*
G01X46506Y1676614D02*
X46539Y1676713D01*
X46628Y1676784D01*
X46753Y1676811D01*
G01X50987Y1703012D02*
X50909Y1702421D01*
G01X50987Y1698012D02*
X50909Y1697421D01*
G01X50987Y1693012D02*
X50909Y1692421D01*
G01X49019Y1678012D02*
X48941Y1677421D01*
G01X50987Y1688012D02*
X50909Y1687421D01*
G01X50987Y1683012D02*
X50909Y1682421D01*
G01X50987Y1673012D02*
X50909Y1672421D01*
G01Y1667421D02*
X50987Y1668012D01*
G01X44401Y1678012D02*
Y1678406D01*
G01X46369Y1668012D02*
Y1668406D01*
G01Y1673012D02*
Y1673406D01*
G01Y1683012D02*
Y1683406D01*
G01Y1688012D02*
Y1688406D01*
G01Y1693012D02*
Y1693406D01*
G01Y1698012D02*
Y1698406D01*
G01Y1703012D02*
Y1703406D01*
G01X46506Y1701811D02*
Y1701417D01*
G01Y1704961D02*
Y1704567D01*
G01Y1698661D02*
Y1698268D01*
G01Y1695512D02*
Y1695118D01*
G01Y1692362D02*
Y1691969D01*
G01Y1689213D02*
Y1688819D01*
G01Y1686063D02*
Y1685669D01*
G01Y1682913D02*
Y1682520D01*
G01Y1679764D02*
Y1679370D01*
G01Y1676614D02*
Y1676220D01*
G01Y1673465D02*
Y1673071D01*
G01Y1670315D02*
Y1669921D01*
G01Y1667165D02*
Y1666772D01*
G01X49019Y1678012D02*
Y1678406D01*
G01X50143D02*
Y1678012D01*
G01X50987Y1678406D02*
Y1678012D01*
G01Y1668406D02*
Y1668012D01*
G01Y1673012D02*
Y1673406D01*
G01Y1683012D02*
Y1683406D01*
G01Y1688012D02*
Y1688406D01*
G01Y1693012D02*
Y1693406D01*
G01Y1698012D02*
Y1698406D01*
G01Y1703012D02*
Y1703406D01*
G01X49019Y1678406D02*
X48941Y1678996D01*
G01X50909Y1668996D02*
X50987Y1668406D01*
G01Y1673406D02*
X50909Y1673996D01*
G01X50987Y1683406D02*
X50909Y1683996D01*
G01X50987Y1688406D02*
X50909Y1688996D01*
G01X50987Y1693406D02*
X50909Y1693996D01*
G01X50987Y1698406D02*
X50909Y1698996D01*
G01X50987Y1703406D02*
X50909Y1703996D01*
G01X46506Y1666772D02*
X46538Y1666674D01*
X46626Y1666602D01*
X46753Y1666575D01*
G01X46506Y1669921D02*
X46538Y1669824D01*
X46626Y1669752D01*
X46753Y1669724D01*
G01X46506Y1673071D02*
X46538Y1672974D01*
X46626Y1672902D01*
X46753Y1672874D01*
G01X46506Y1679370D02*
X46538Y1679273D01*
X46626Y1679201D01*
X46753Y1679173D01*
G01X46506Y1682520D02*
X46538Y1682422D01*
X46626Y1682350D01*
X46753Y1682323D01*
G01X46506Y1685669D02*
X46538Y1685572D01*
X46626Y1685500D01*
X46753Y1685472D01*
G01X46506Y1688819D02*
X46538Y1688722D01*
X46626Y1688650D01*
X46753Y1688622D01*
G01X46506Y1691969D02*
X46538Y1691871D01*
X46626Y1691799D01*
X46753Y1691772D01*
G01X46506Y1695118D02*
X46538Y1695021D01*
X46626Y1694949D01*
X46753Y1694921D01*
G01X46506Y1698268D02*
X46538Y1698170D01*
X46626Y1698098D01*
X46753Y1698071D01*
G01X46506Y1701417D02*
X46538Y1701320D01*
X46626Y1701248D01*
X46753Y1701220D01*
G01X49871Y1678996D02*
X50143Y1678406D01*
G01X46369Y1668012D02*
X46506Y1667814D01*
X46644Y1667617D01*
X46784Y1667421D01*
G01X46369Y1673012D02*
X46506Y1672814D01*
X46644Y1672617D01*
X46784Y1672421D01*
G01X44401Y1678012D02*
X44538Y1677814D01*
X44676Y1677617D01*
X44815Y1677421D01*
G01X46369Y1683012D02*
X46506Y1682814D01*
X46644Y1682617D01*
X46784Y1682421D01*
G01X50560Y1678996D02*
X50987Y1678406D01*
G01X46369Y1688012D02*
X46506Y1687814D01*
X46644Y1687617D01*
X46784Y1687421D01*
G01X46369Y1693012D02*
X46506Y1692814D01*
X46644Y1692617D01*
X46784Y1692421D01*
G01X46369Y1698012D02*
X46506Y1697814D01*
X46644Y1697617D01*
X46784Y1697421D01*
G01X46369Y1703012D02*
X46506Y1702814D01*
X46644Y1702617D01*
X46784Y1702421D01*
G01X46753Y1676024D02*
X46627Y1676051D01*
X46538Y1676124D01*
X46506Y1676220D01*
G01X46753Y1704370D02*
X46627Y1704397D01*
X46538Y1704470D01*
X46506Y1704567D01*
G01X46753Y1666575D02*
X52838D01*
G01X53118Y1666772D02*
X46506D01*
G01Y1667165D02*
X53118D01*
G01X46753Y1667362D02*
X52838D01*
G01X46784Y1667421D02*
X52529D01*
G01X46369Y1668012D02*
X52956D01*
G01Y1668406D02*
X46369D01*
G01X52529Y1668996D02*
X46784D01*
G01X46753Y1669724D02*
X52838D01*
G01X53118Y1669921D02*
X46506D01*
G01Y1670315D02*
X53118D01*
G01X46753Y1670512D02*
X52838D01*
G01X46784Y1672421D02*
X52529D01*
G01X46753Y1672874D02*
X52838D01*
G01X46369Y1673012D02*
X52956D01*
G01X53118Y1673071D02*
X46506D01*
G01X52956Y1673406D02*
X46369D01*
G01X46506Y1673465D02*
X53118D01*
G01X46753Y1673661D02*
X52838D01*
G01X52529Y1673996D02*
X46784D01*
G01X46753Y1676024D02*
X52838D01*
G01X53118Y1676220D02*
X46506D01*
G01Y1676614D02*
X53118D01*
G01X46753Y1676811D02*
X52838D01*
G01X71181Y1677106D02*
X44488D01*
G01X44815Y1677421D02*
X50560D01*
G01X44401Y1678012D02*
X50987D01*
G01Y1678406D02*
X44401D01*
G01X50560Y1678996D02*
X44815D01*
G01X46753Y1679173D02*
X52838D01*
G01X53118Y1679370D02*
X46506D01*
G01X44488Y1679469D02*
X71181D01*
G01X46506Y1679764D02*
X53118D01*
G01X46753Y1679961D02*
X52838D01*
G01X46753Y1682323D02*
X52838D01*
G01X46784Y1682421D02*
X52529D01*
G01X53118Y1682520D02*
X46506D01*
G01Y1682913D02*
X53118D01*
G01X46369Y1683012D02*
X52956D01*
G01X46753Y1683110D02*
X52838D01*
G01X52956Y1683406D02*
X46369D01*
G01X52529Y1683996D02*
X46784D01*
G01X46753Y1685472D02*
X52838D01*
G01X53118Y1685669D02*
X46506D01*
G01Y1686063D02*
X53118D01*
G01X46753Y1686260D02*
X52838D01*
G01X46784Y1687421D02*
X52529D01*
G01X46369Y1688012D02*
X52956D01*
G01Y1688406D02*
X46369D01*
G01X46753Y1688622D02*
X52838D01*
G01X53118Y1688819D02*
X46506D01*
G01X52529Y1688996D02*
X46784D01*
G01X46506Y1689213D02*
X53118D01*
G01X46753Y1689409D02*
X52838D01*
G01X46753Y1691772D02*
X52838D01*
G01X53118Y1691969D02*
X46506D01*
G01Y1692362D02*
X53118D01*
G01X46784Y1692421D02*
X52529D01*
G01X46753Y1692559D02*
X52838D01*
G01X46369Y1693012D02*
X52956D01*
G01Y1693406D02*
X46369D01*
G01X52529Y1693996D02*
X46784D01*
G01X46753Y1694921D02*
X52838D01*
G01X53118Y1695118D02*
X46506D01*
G01Y1695512D02*
X53118D01*
G01X46753Y1695709D02*
X52838D01*
G01X46753Y1667362D02*
X46626Y1667334D01*
X46537Y1667261D01*
X46506Y1667165D01*
G01X46753Y1670512D02*
X46626Y1670484D01*
X46537Y1670411D01*
X46506Y1670315D01*
G01X46753Y1673661D02*
X46626Y1673633D01*
X46537Y1673561D01*
X46506Y1673465D01*
G01X46753Y1679961D02*
X46626Y1679933D01*
X46537Y1679860D01*
X46506Y1679764D01*
G01X46753Y1683110D02*
X46626Y1683082D01*
X46537Y1683009D01*
X46506Y1682913D01*
G01X46753Y1686260D02*
X46626Y1686232D01*
X46537Y1686159D01*
X46506Y1686063D01*
G01X46753Y1689409D02*
X46626Y1689381D01*
X46537Y1689309D01*
X46506Y1689213D01*
G01X71181Y1696004D02*
X44488D01*
G01X46784Y1697421D02*
X52529D01*
G01X46369Y1698012D02*
X52956D01*
G01X46753Y1698071D02*
X52838D01*
G01X53118Y1698268D02*
X46506D01*
G01X44488Y1698366D02*
X71181D01*
G01X52956Y1698406D02*
X46369D01*
G01X46506Y1698661D02*
X53118D01*
G01X46753Y1698858D02*
X52838D01*
G01X52529Y1698996D02*
X46784D01*
G01X46753Y1701220D02*
X52838D01*
G01X53118Y1701417D02*
X46506D01*
G01Y1701811D02*
X53118D01*
G01X46753Y1702008D02*
X52838D01*
G01X46784Y1702421D02*
X52529D01*
G01X46369Y1703012D02*
X52956D01*
G01Y1703406D02*
X46369D01*
G01X52529Y1703996D02*
X46784D01*
G01X46753Y1704370D02*
X52838D01*
G01X53118Y1704567D02*
X46506D01*
G01Y1704961D02*
X53118D01*
G01X46753Y1705157D02*
X52838D01*
G01X46753Y1692559D02*
X46626Y1692531D01*
X46537Y1692458D01*
X46506Y1692362D01*
G01X46753Y1695709D02*
X46626Y1695681D01*
X46537Y1695608D01*
X46506Y1695512D01*
G01X46753Y1698858D02*
X46626Y1698830D01*
X46537Y1698757D01*
X46506Y1698661D01*
G01X46753Y1702008D02*
X46626Y1701980D01*
X46537Y1701907D01*
X46506Y1701811D01*
G01X52529Y1712421D02*
X52956Y1713012D01*
G01X52529Y1707421D02*
X52956Y1708012D01*
G01X52112Y1713012D02*
X51839Y1712421D01*
G01X52112Y1708012D02*
X51839Y1707421D01*
G01X51428Y1720315D02*
X51417Y1720217D01*
X51389Y1720144D01*
X51351Y1720118D01*
G01X51428Y1717165D02*
X51417Y1717067D01*
X51389Y1716995D01*
X51351Y1716969D01*
G01X51428Y1714016D02*
X51417Y1713917D01*
X51389Y1713845D01*
X51351Y1713819D01*
G01X51428Y1710866D02*
X51417Y1710768D01*
X51389Y1710696D01*
X51351Y1710669D01*
G01X51428Y1707717D02*
X51417Y1707618D01*
X51389Y1707546D01*
X51351Y1707520D01*
G01X51428Y1720709D02*
Y1720315D01*
G01Y1717559D02*
Y1717165D01*
G01Y1714409D02*
Y1714016D01*
G01Y1711260D02*
Y1710866D01*
G01Y1708110D02*
Y1707717D01*
G01X51941D02*
Y1708110D01*
G01Y1710866D02*
Y1711260D01*
G01Y1717165D02*
Y1717559D01*
G01Y1714016D02*
Y1714409D01*
G01Y1720315D02*
Y1720709D01*
G01X52112Y1713406D02*
Y1713012D01*
G01Y1708406D02*
Y1708012D01*
G01X52956Y1713406D02*
Y1713012D01*
G01Y1708406D02*
Y1708012D01*
G01X53118Y1707717D02*
Y1708110D01*
G01Y1710866D02*
Y1711260D01*
G01Y1717165D02*
Y1717559D01*
G01Y1714016D02*
Y1714409D01*
G01Y1720315D02*
Y1720709D01*
G01X51941Y1708110D02*
X51938Y1708148D01*
X51930Y1708185D01*
X51917Y1708219D01*
X51900Y1708249D01*
X51879Y1708274D01*
X51856Y1708292D01*
X51830Y1708303D01*
X51802Y1708307D01*
G01X51941Y1711260D02*
X51938Y1711298D01*
X51930Y1711335D01*
X51917Y1711369D01*
X51900Y1711399D01*
X51879Y1711423D01*
X51856Y1711441D01*
X51830Y1711453D01*
X51802Y1711457D01*
G01X51941Y1714409D02*
X51938Y1714448D01*
X51930Y1714484D01*
X51917Y1714518D01*
X51900Y1714548D01*
X51879Y1714573D01*
X51856Y1714591D01*
X51830Y1714602D01*
X51802Y1714606D01*
G01X51941Y1717559D02*
X51938Y1717597D01*
X51930Y1717634D01*
X51917Y1717668D01*
X51900Y1717698D01*
X51879Y1717722D01*
X51856Y1717741D01*
X51830Y1717752D01*
X51802Y1717756D01*
G01X51941Y1720709D02*
X51938Y1720747D01*
X51930Y1720783D01*
X51917Y1720817D01*
X51900Y1720848D01*
X51879Y1720872D01*
X51856Y1720890D01*
X51830Y1720902D01*
X51802Y1720906D01*
G01X69213Y1733602D02*
Y1717264D01*
G01X74803Y1719783D02*
Y1716634D01*
G01X75170Y1720906D02*
Y1720118D01*
G01Y1714606D02*
Y1713819D01*
G01Y1717756D02*
Y1716969D01*
G01Y1711457D02*
Y1710669D01*
G01Y1708307D02*
Y1707520D01*
G01X75197Y1720906D02*
Y1720118D01*
G01Y1714606D02*
Y1713819D01*
G01Y1717756D02*
Y1716969D01*
G01Y1711457D02*
Y1710669D01*
G01Y1708307D02*
Y1707520D01*
G01X75573Y1720906D02*
Y1720118D01*
G01Y1714606D02*
Y1713819D01*
G01Y1717756D02*
Y1716969D01*
G01Y1711457D02*
Y1710669D01*
G01Y1708307D02*
Y1707520D01*
G01X75787Y1719783D02*
Y1716634D01*
G01Y1713996D02*
Y1712421D01*
G01Y1708996D02*
Y1707421D01*
G01X76772Y1714783D02*
Y1711634D01*
G01Y1718996D02*
Y1717421D01*
G01Y1709783D02*
Y1706634D01*
G01X77756Y1714783D02*
Y1711634D01*
G01Y1709783D02*
Y1706634D01*
G01X78740Y1713996D02*
Y1712421D01*
G01Y1708996D02*
Y1707421D01*
G01X78935Y1707520D02*
Y1708307D01*
G01Y1710669D02*
Y1711457D01*
G01Y1713819D02*
Y1714606D01*
G01Y1716969D02*
Y1717756D01*
G01Y1720118D02*
Y1720906D01*
G01X79921Y1717421D02*
Y1718996D01*
G01X80919Y1707520D02*
Y1708307D01*
G01Y1710669D02*
Y1711457D01*
G01Y1713819D02*
Y1714606D01*
G01Y1716969D02*
Y1717756D01*
G01Y1720118D02*
Y1720906D01*
G01X81890Y1707421D02*
Y1708996D01*
G01Y1712421D02*
Y1713996D01*
G01X82570Y1720906D02*
Y1720118D01*
G01Y1714606D02*
Y1713819D01*
G01Y1717756D02*
Y1716969D01*
G01Y1711457D02*
Y1710669D01*
G01Y1708307D02*
Y1707520D01*
G01X84298Y1708307D02*
Y1710669D01*
G01Y1711457D02*
Y1713819D01*
G01Y1714606D02*
Y1716969D01*
G01Y1717756D02*
Y1720118D01*
G01Y1720906D02*
Y1723268D01*
G01X85237Y1720906D02*
Y1720118D01*
G01Y1714606D02*
Y1713819D01*
G01Y1717756D02*
Y1716969D01*
G01Y1711457D02*
Y1710669D01*
G01Y1708307D02*
Y1707520D01*
G01X85384Y1720906D02*
Y1720118D01*
G01Y1714606D02*
Y1713819D01*
G01Y1717756D02*
Y1716969D01*
G01Y1711457D02*
Y1710669D01*
G01Y1708307D02*
Y1707520D01*
G01X86976Y1720906D02*
Y1720118D01*
G01Y1714606D02*
Y1713819D01*
G01Y1717756D02*
Y1716969D01*
G01Y1711457D02*
Y1710669D01*
G01Y1708307D02*
Y1707520D01*
G01X87918D02*
Y1708307D01*
G01Y1710669D02*
Y1711457D01*
G01Y1713819D02*
Y1714606D01*
G01Y1716969D02*
Y1717756D01*
G01Y1720118D02*
Y1720906D01*
G01X90754Y1707520D02*
Y1708307D01*
G01Y1710669D02*
Y1711457D01*
G01Y1713819D02*
Y1714606D01*
G01Y1716969D02*
Y1717756D01*
G01Y1720118D02*
Y1720906D01*
G01X90943D02*
Y1720118D01*
G01Y1714606D02*
Y1713819D01*
G01Y1717756D02*
Y1716969D01*
G01Y1711457D02*
Y1710669D01*
G01Y1708307D02*
Y1707520D01*
G01X92717Y1720906D02*
Y1720118D01*
G01Y1714606D02*
Y1713819D01*
G01Y1717756D02*
Y1716969D01*
G01Y1711457D02*
Y1710669D01*
G01Y1708307D02*
Y1707520D01*
G01X51839Y1708996D02*
X52112Y1708406D01*
G01X51839Y1713996D02*
X52112Y1713406D01*
G01X52529Y1708996D02*
X52956Y1708406D01*
G01X52529Y1713996D02*
X52956Y1713406D01*
G01X51351Y1708307D02*
X51389Y1708281D01*
X51417Y1708209D01*
X51428Y1708110D01*
G01X51351Y1711457D02*
X51389Y1711430D01*
X51417Y1711358D01*
X51428Y1711260D01*
G01X51351Y1714606D02*
X51389Y1714580D01*
X51417Y1714508D01*
X51428Y1714409D01*
G01X51351Y1717756D02*
X51389Y1717730D01*
X51417Y1717657D01*
X51428Y1717559D01*
G01X51351Y1720906D02*
X51389Y1720879D01*
X51417Y1720807D01*
X51428Y1720709D01*
G01X51802Y1707520D02*
X51829Y1707523D01*
X51855Y1707534D01*
X51879Y1707552D01*
X51900Y1707577D01*
X51917Y1707607D01*
X51930Y1707641D01*
X51938Y1707678D01*
X51941Y1707717D01*
G01X51802Y1710669D02*
X51829Y1710673D01*
X51855Y1710684D01*
X51879Y1710702D01*
X51900Y1710727D01*
X51917Y1710757D01*
X51930Y1710791D01*
X51938Y1710827D01*
X51941Y1710866D01*
G01X51802Y1713819D02*
X51829Y1713822D01*
X51855Y1713833D01*
X51879Y1713852D01*
X51900Y1713876D01*
X51917Y1713906D01*
X51930Y1713940D01*
X51938Y1713977D01*
X51941Y1714016D01*
G01X77756Y1706634D02*
X76772D01*
G01X77756Y1706831D02*
X76772D01*
G01X77756Y1707224D02*
X76772D01*
G01X74724Y1707421D02*
X81890D01*
G01X92717Y1707520D02*
X85384D01*
G01X85237D02*
X73228D01*
G01X85237Y1708307D02*
X73228D01*
G01X85384D02*
X92717D01*
G01X74724Y1708996D02*
X81890D01*
G01X77756Y1709193D02*
X76772D01*
G01X77756Y1709587D02*
X76772D01*
G01X77756Y1709783D02*
X76772D01*
G01X92717Y1710669D02*
X85384D01*
G01X85237D02*
X73228D01*
G01X85237Y1711457D02*
X73228D01*
G01X85384D02*
X92717D01*
G01X77756Y1711634D02*
X76772D01*
G01X77756Y1711831D02*
X76772D01*
G01X77756Y1712224D02*
X76772D01*
G01X74724Y1712421D02*
X81890D01*
G01X92717Y1713819D02*
X85384D01*
G01X85237D02*
X73228D01*
G01X74724Y1713996D02*
X81890D01*
G01X77756Y1714193D02*
X76772D01*
G01X77756Y1714587D02*
X76772D01*
G01X85237Y1714606D02*
X73228D01*
G01X85384D02*
X92717D01*
G01X77756Y1714783D02*
X76772D01*
G01X74331Y1716004D02*
X73228D01*
G01X75787Y1716634D02*
X74803D01*
G01X75787Y1716831D02*
X74803D01*
G01X92717Y1716969D02*
X85384D01*
G01X85237D02*
X73228D01*
G01X75787Y1717224D02*
X74803D01*
G01X74331Y1717421D02*
X79921D01*
G01X85237Y1717756D02*
X73228D01*
G01X85384D02*
X92717D01*
G01X74331Y1718996D02*
X79921D01*
G01X75787Y1719193D02*
X74803D01*
G01X75787Y1719587D02*
X74803D01*
G01X75787Y1719783D02*
X74803D01*
G01X92717Y1720118D02*
X85384D01*
G01X85237D02*
X73228D01*
G01Y1720413D02*
X74331D01*
G01X85237Y1720906D02*
X73228D01*
G01X85384D02*
X92717D01*
G01X51802Y1716969D02*
X51829Y1716972D01*
X51855Y1716983D01*
X51879Y1717001D01*
X51900Y1717026D01*
X51917Y1717056D01*
X51930Y1717090D01*
X51938Y1717126D01*
X51941Y1717165D01*
G01X51802Y1720118D02*
X51829Y1720122D01*
X51855Y1720133D01*
X51879Y1720151D01*
X51900Y1720176D01*
X51917Y1720206D01*
X51930Y1720239D01*
X51938Y1720276D01*
X51941Y1720315D01*
G01X74331Y1709390D02*
G03X74724Y1708996I394J0D01*
G01Y1707421D02*
G03X74331Y1707028I1J-394D01*
G01Y1714390D02*
G03X74724Y1713996I394J0D01*
G01Y1712421D02*
G03X74331Y1712028I1J-394D01*
G01X44815Y1718996D02*
X44676Y1718800D01*
X44538Y1718603D01*
X44401Y1718406D01*
G01X46784Y1713996D02*
X46644Y1713800D01*
X46506Y1713603D01*
X46369Y1713406D01*
G01X46784Y1708996D02*
X46644Y1708800D01*
X46506Y1708603D01*
X46369Y1708406D01*
G01X50560Y1717421D02*
X50987Y1718012D01*
G01X50143D02*
X49871Y1717421D01*
G01X49019Y1718012D02*
X48941Y1717421D01*
G01X50987Y1713012D02*
X50909Y1712421D01*
G01X50987Y1708012D02*
X50909Y1707421D01*
G01X44401Y1718012D02*
Y1718406D01*
G01X46369Y1708012D02*
Y1708406D01*
G01Y1713012D02*
Y1713406D01*
G01X46506Y1720709D02*
Y1720315D01*
G01Y1717559D02*
Y1717165D01*
G01Y1714409D02*
Y1714016D01*
G01Y1711260D02*
Y1710866D01*
G01Y1708110D02*
Y1707717D01*
G01X49019Y1718012D02*
Y1718406D01*
G01X50143D02*
Y1718012D01*
G01X50987Y1718406D02*
Y1718012D01*
G01Y1708012D02*
Y1708406D01*
G01Y1713012D02*
Y1713406D01*
G01X49019Y1718406D02*
X48941Y1718996D01*
G01X50987Y1708406D02*
X50909Y1708996D01*
G01X50987Y1713406D02*
X50909Y1713996D01*
G01X46506Y1707717D02*
X46538Y1707619D01*
X46626Y1707547D01*
X46753Y1707520D01*
G01X46506Y1710866D02*
X46538Y1710769D01*
X46626Y1710697D01*
X46753Y1710669D01*
G01X46506Y1714016D02*
X46538Y1713919D01*
X46626Y1713846D01*
X46753Y1713819D01*
G01X46506Y1717165D02*
X46538Y1717068D01*
X46626Y1716996D01*
X46753Y1716969D01*
G01X46506Y1720315D02*
X46538Y1720218D01*
X46626Y1720146D01*
X46753Y1720118D01*
G01X49871Y1718996D02*
X50143Y1718406D01*
G01X50560Y1718996D02*
X50987Y1718406D01*
G01X46369Y1708012D02*
X46506Y1707814D01*
X46644Y1707617D01*
X46784Y1707421D01*
G01X46369Y1713012D02*
X46506Y1712814D01*
X46644Y1712617D01*
X46784Y1712421D01*
G01X44401Y1718012D02*
X44538Y1717814D01*
X44676Y1717617D01*
X44815Y1717421D01*
G01X46784Y1707421D02*
X52529D01*
G01X46753Y1707520D02*
X52838D01*
G01X53118Y1707717D02*
X46506D01*
G01X46369Y1708012D02*
X52956D01*
G01X46506Y1708110D02*
X53118D01*
G01X46753Y1708307D02*
X52838D01*
G01X52956Y1708406D02*
X46369D01*
G01X52529Y1708996D02*
X46784D01*
G01X46753Y1710669D02*
X52838D01*
G01X53118Y1710866D02*
X46506D01*
G01Y1711260D02*
X53118D01*
G01X46753Y1711457D02*
X52838D01*
G01X46784Y1712421D02*
X52529D01*
G01X46369Y1713012D02*
X52956D01*
G01Y1713406D02*
X46369D01*
G01X46753Y1713819D02*
X52838D01*
G01X52529Y1713996D02*
X46784D01*
G01X53118Y1714016D02*
X46506D01*
G01Y1714409D02*
X53118D01*
G01X46753Y1714606D02*
X52838D01*
G01X71181Y1714902D02*
X44488D01*
G01X46753Y1716969D02*
X52838D01*
G01X53118Y1717165D02*
X46506D01*
G01X44488Y1717264D02*
X71181D01*
G01X44815Y1717421D02*
X50560D01*
G01X46506Y1717559D02*
X53118D01*
G01X46753Y1717756D02*
X52838D01*
G01X44401Y1718012D02*
X50987D01*
G01Y1718406D02*
X44401D01*
G01X50560Y1718996D02*
X44815D01*
G01X46753Y1720118D02*
X52838D01*
G01X53118Y1720315D02*
X46506D01*
G01Y1720709D02*
X53118D01*
G01X46753Y1720906D02*
X52838D01*
G01X46753Y1708307D02*
X46626Y1708279D01*
X46537Y1708206D01*
X46506Y1708110D01*
G01X46753Y1711457D02*
X46626Y1711429D01*
X46537Y1711356D01*
X46506Y1711260D01*
G01X46753Y1714606D02*
X46626Y1714578D01*
X46537Y1714506D01*
X46506Y1714409D01*
G01X46753Y1717756D02*
X46626Y1717728D01*
X46537Y1717655D01*
X46506Y1717559D01*
G01X46753Y1720906D02*
X46626Y1720878D01*
X46537Y1720805D01*
X46506Y1720709D01*
G01X52529Y1662421D02*
X52956Y1663012D01*
G01X52112D02*
X51839Y1662421D01*
G01X79328Y1656831D02*
X79583Y1657224D01*
G01X91339Y1651531D02*
X90650Y1650544D01*
G01X92721Y1651531D02*
X91426Y1649679D01*
G01X84041Y1653622D02*
X84059Y1653678D01*
X84111Y1653843D01*
X84190Y1654101D01*
X84285Y1654429D01*
X84390Y1654803D01*
G01X51428Y1664016D02*
Y1663622D01*
G01X51941D02*
Y1664016D01*
G01X52112Y1663406D02*
Y1663012D01*
G01X52956Y1663406D02*
Y1663012D01*
G01X53118Y1663622D02*
Y1664016D01*
G01X51428Y1663622D02*
X51417Y1663524D01*
X51389Y1663452D01*
X51351Y1663425D01*
G01X51941Y1664016D02*
X51938Y1664054D01*
X51930Y1664091D01*
X51917Y1664124D01*
X51900Y1664155D01*
X51879Y1664179D01*
X51856Y1664197D01*
X51830Y1664209D01*
X51802Y1664213D01*
G01X62992Y1659390D02*
Y1792028D01*
G01X64961Y1660177D02*
Y1658406D01*
G01X69213Y1677106D02*
Y1659587D01*
G01X70113Y1651531D02*
Y1650974D01*
G01X70866Y1656240D02*
Y1653839D01*
G01X71181Y1791831D02*
Y1659587D01*
G01X73228Y1656772D02*
Y1794646D01*
G01X74331Y1794193D02*
Y1657224D01*
G01X75170Y1664213D02*
Y1663425D01*
G01X75197Y1664213D02*
Y1663425D01*
G01X75573Y1664213D02*
Y1663425D01*
G01X75787Y1663996D02*
Y1662421D01*
G01X76772Y1664783D02*
Y1661634D01*
G01Y1654469D02*
Y1656772D01*
G01X77756Y1664783D02*
Y1661634D01*
G01X78346Y1794193D02*
Y1657224D01*
G01X78740Y1663996D02*
Y1662421D01*
G01X78801Y1791614D02*
Y1660000D01*
G01X78935Y1663425D02*
Y1664213D01*
G01X79328Y1656772D02*
Y1656831D01*
G01X79967Y1657224D02*
Y1654469D01*
G01X80919Y1663425D02*
Y1664213D01*
G01X81890Y1662421D02*
Y1663996D01*
G01X82570Y1664213D02*
Y1663425D01*
G01X84298Y1661752D02*
Y1663425D01*
G01Y1664213D02*
Y1666575D01*
G01X85237Y1664213D02*
Y1663425D01*
G01X85384Y1664213D02*
Y1663425D01*
G01X86976Y1664213D02*
Y1663425D01*
G01X87331Y1657224D02*
Y1794193D01*
G01X87841Y1657224D02*
Y1654469D01*
G01X87918Y1663425D02*
Y1664213D01*
G01X90754Y1663425D02*
Y1664213D01*
G01X90943D02*
Y1663425D01*
G01X92717Y1664213D02*
Y1663425D01*
G01X93696Y1657224D02*
Y1660000D01*
G01X94170Y1654469D02*
Y1660000D01*
G01X80132Y1653622D02*
X80114Y1653678D01*
X80062Y1653843D01*
X79983Y1654102D01*
X79887Y1654429D01*
X79783Y1654803D01*
G01X51839Y1663996D02*
X52112Y1663406D01*
G01X90044Y1651531D02*
X90650Y1650544D01*
G01X52529Y1663996D02*
X52956Y1663406D01*
G01X88428Y1651531D02*
X89697Y1649670D01*
G01X51351Y1664213D02*
X51389Y1664186D01*
X51417Y1664114D01*
X51428Y1664016D01*
G01X88097Y1648680D02*
X86594D01*
G01X88228Y1649123D02*
X85228D01*
G01X86655Y1649949D02*
X85229D01*
G01X90044Y1651531D02*
X88428D01*
G01X92721D02*
X91339D01*
G01X70113D02*
X68670D01*
G01X94488Y1651870D02*
X70866D01*
G01X83082Y1653278D02*
X81622D01*
G01X80132Y1653622D02*
X84041D01*
G01X94488Y1653839D02*
X70866D01*
G01X84390Y1654803D02*
X79783D01*
G01X94488Y1656240D02*
X70866D01*
G01X79328Y1656772D02*
X73228D01*
G01X79328Y1656831D02*
X73228D01*
G01X93696Y1657224D02*
X73228D01*
G01X74331Y1658406D02*
X64961D01*
G01X64646Y1659587D02*
X71181D01*
G01X94488Y1660000D02*
X74331D01*
G01Y1660177D02*
X64961D01*
G01X77756Y1661634D02*
X76772D01*
G01X87331Y1661752D02*
X78346D01*
G01X77756Y1661831D02*
X76772D01*
G01X77756Y1662224D02*
X76772D01*
G01X74724Y1662421D02*
X81890D01*
G01X92717Y1663425D02*
X85384D01*
G01X85237D02*
X73228D01*
G01X74724Y1663996D02*
X81890D01*
G01X77756Y1664193D02*
X76772D01*
G01X85237Y1664213D02*
X73228D01*
G01X85384D02*
X92717D01*
G01X77756Y1664587D02*
X76772D01*
G01X77756Y1664783D02*
X76772D01*
G01X51802Y1663425D02*
X51829Y1663429D01*
X51855Y1663440D01*
X51879Y1663458D01*
X51900Y1663483D01*
X51917Y1663513D01*
X51930Y1663546D01*
X51938Y1663583D01*
X51941Y1663622D01*
G01X72893Y1650979D02*
G03X70113Y1650974I-1388J-1207D01*
G01X75529Y1651124D02*
G03X72893Y1650979I-1248J-1352D01*
G01X74430Y1650048D02*
G03X73000I-715J1D01*
G01X71541D02*
G03X70110I-716J0D01*
G01X74331Y1664390D02*
G03X74724Y1663996I394J0D01*
G01Y1662421D02*
G03X74331Y1662028I1J-394D01*
G01X80324Y1651177D02*
G03X77277I-1523J-2362D01*
G01X80845Y1648300D02*
G03X80844Y1650612I-2163J1155D01*
G01X76756Y1650611D02*
G03X76757Y1648298I2163J-1156D01*
G01X79502Y1648633D02*
G03Y1650317I-2236J842D01*
G01X77277Y1651177D02*
G03X76756Y1650611I831J-1288D01*
G01X75823Y1650453D02*
G03X75529Y1651124I-913J0D01*
G01X79502Y1650317D02*
G03X78029I-736J-277D01*
G01X78030D02*
G03Y1648633I2236J-842D01*
G01X80844Y1650612D02*
G03X80323Y1651177I-1351J-723D01*
G01X84252Y1650905D02*
G03I-2166J0D01*
G01X83847Y1650357D02*
G03X83673Y1649696I4018J-1411D01*
G01D02*
G03Y1649200I3525J-248D01*
G01X88228Y1649123D02*
G03X87889Y1650566I-3015J53D01*
G01X83673Y1649201D02*
G03X83935Y1648339I2971J432D01*
G01X86655Y1651539D02*
G03X85012Y1651496I-757J-2475D01*
G01D02*
G03X83847Y1650357I729J-1911D01*
G01X87889Y1650566D02*
G03X86655Y1651539I-1735J-931D01*
G01X85229Y1649123D02*
G03X86003Y1648315I792J-16D01*
G01D02*
G03X86594Y1648680I9J646D01*
G01X86654Y1649949D02*
G03X85229I-713J82D01*
G01X46784Y1663996D02*
X46644Y1663800D01*
X46506Y1663603D01*
X46369Y1663406D01*
G01X44488Y1659390D02*
X42520Y1657421D01*
G01X50987Y1663012D02*
X50909Y1662421D01*
G01X42520Y1796949D02*
Y1654469D01*
G01X43642Y1658996D02*
Y1792421D01*
G01X43701Y1658602D02*
Y1729508D01*
G01X44488Y1792028D02*
Y1659390D01*
G01X46369Y1663012D02*
Y1663406D01*
G01X46506Y1664016D02*
Y1663622D01*
G01X50987Y1663012D02*
Y1663406D01*
G01D02*
X50909Y1663996D01*
G01X46506Y1663622D02*
X46538Y1663525D01*
X46626Y1663453D01*
X46753Y1663425D01*
G01X46369Y1663012D02*
X46506Y1662814D01*
X46644Y1662617D01*
X46784Y1662421D01*
G01X42520Y1656437D02*
X44488Y1654469D01*
G01X42520D02*
X39236D01*
G01X44488D02*
X94488D01*
G01X42520Y1658996D02*
X73228D01*
G01X44488Y1659390D02*
X62992D01*
G01X46784Y1662421D02*
X52529D01*
G01X46369Y1663012D02*
X52956D01*
G01Y1663406D02*
X46369D01*
G01X46753Y1663425D02*
X52838D01*
G01X53118Y1663622D02*
X46506D01*
G01X52529Y1663996D02*
X46784D01*
G01X46506Y1664016D02*
X53118D01*
G01X46753Y1664213D02*
X52838D01*
G01X46753D02*
X46626Y1664185D01*
X46537Y1664112D01*
X46506Y1664016D01*
G01X51351Y1786260D02*
X51389Y1786286D01*
X51417Y1786358D01*
X51428Y1786457D01*
G01X52529Y1787421D02*
X52956Y1788012D01*
G01X68779Y1789856D02*
X69040Y1790111D01*
G01X70608Y1790367D02*
X70260Y1790026D01*
G01X69911Y1787723D02*
X70260Y1788064D01*
G01X71654Y1788576D02*
X71480Y1788406D01*
G01X71567Y1787894D02*
X71915Y1788150D01*
G01X69737Y1788235D02*
X69476Y1788064D01*
G01X68953Y1790623D02*
X68518Y1790367D01*
G01X69563Y1787552D02*
X69911Y1787723D01*
G01X71480Y1788406D02*
X71306Y1788320D01*
G01X69040Y1790111D02*
X69302Y1790197D01*
G01X70783Y1789856D02*
X71044Y1789941D01*
G01X71306Y1787808D02*
X71567Y1787894D01*
G01X68518Y1790367D02*
X68256Y1789941D01*
G01X70608Y1789600D02*
X70783Y1789856D01*
G01X69911Y1788491D02*
X69737Y1788235D01*
G01X71915Y1788150D02*
X72176Y1788491D01*
G01X52112Y1788012D02*
X51839Y1787421D01*
G01X70260Y1790026D02*
X70086Y1789685D01*
G01X70260Y1788064D02*
X70434Y1788406D01*
G01X68692Y1789514D02*
X68779Y1789856D01*
G01X70086Y1789685D02*
X69998Y1789344D01*
G01Y1788832D02*
X69911Y1788491D01*
G01X70521Y1789344D02*
X70608Y1789600D01*
G01X71741Y1788832D02*
X71654Y1788576D01*
G01X68256Y1789941D02*
X68169Y1789514D01*
G01X70434Y1788406D02*
X70521Y1788832D01*
G01X72176Y1788491D02*
X72264Y1788917D01*
G01X51428Y1786850D02*
Y1786457D01*
G01X51941D02*
Y1786850D01*
G01X52112Y1788406D02*
Y1788012D01*
G01X52956Y1788406D02*
Y1788012D01*
G01X53118Y1786457D02*
Y1786850D01*
G01X51941D02*
X51938Y1786889D01*
X51930Y1786925D01*
X51917Y1786959D01*
X51900Y1786989D01*
X51879Y1787014D01*
X51856Y1787032D01*
X51830Y1787043D01*
X51802Y1787047D01*
G01X64646Y1791831D02*
Y1818228D01*
G01X64961Y1793012D02*
Y1791240D01*
G01X68169Y1789514D02*
Y1788832D01*
G01Y1785846D02*
Y1786358D01*
G01X68692Y1788832D02*
Y1789514D01*
G01X69302Y1790197D02*
Y1790709D01*
G01X69998Y1789344D02*
Y1788832D01*
G01X70521D02*
Y1789344D01*
G01X71306Y1788320D02*
Y1787808D01*
G01X71741Y1789344D02*
Y1788832D01*
G01X72264Y1786358D02*
Y1785846D01*
G01Y1788917D02*
Y1789344D01*
G01X74783Y1789173D02*
Y1787205D01*
G01X75170Y1787047D02*
Y1786260D01*
G01X75197Y1787047D02*
Y1786260D01*
G01X75573Y1787047D02*
Y1786260D01*
G01X75787Y1788996D02*
Y1787421D01*
G01X76772Y1789783D02*
Y1786634D01*
G01X77756Y1789783D02*
Y1786634D01*
G01X78740Y1788996D02*
Y1787421D01*
G01X78935Y1786260D02*
Y1787047D01*
G01X80919Y1786260D02*
Y1787047D01*
G01X81890Y1787421D02*
Y1788996D01*
G01X82570Y1787047D02*
Y1786260D01*
G01X82854Y1787205D02*
Y1789173D01*
G01X84298Y1787047D02*
Y1789626D01*
G01X85237Y1787047D02*
Y1786260D01*
G01X85384Y1787047D02*
Y1786260D01*
G01X86976Y1787047D02*
Y1786260D01*
G01X87918D02*
Y1787047D01*
G01X90754Y1786260D02*
Y1787047D01*
G01X90943D02*
Y1786260D01*
G01X92717Y1787047D02*
Y1786260D01*
G01X93696Y1791614D02*
Y1794193D01*
G01X94170Y1791614D02*
Y1796949D01*
G01X94488Y1791614D02*
Y1805295D01*
G01X68779Y1788491D02*
X68692Y1788832D01*
G01X72264Y1789344D02*
X72176Y1789685D01*
G01X68169Y1788832D02*
X68256Y1788406D01*
G01X71654Y1789600D02*
X71741Y1789344D01*
G01X51839Y1788996D02*
X52112Y1788406D01*
G01X68256D02*
X68430Y1788064D01*
G01X72176Y1789685D02*
X72002Y1790026D01*
G01X68953Y1788235D02*
X68779Y1788491D01*
G01X71480Y1789856D02*
X71654Y1789600D01*
G01X52529Y1788996D02*
X52956Y1788406D01*
G01X68430Y1788064D02*
X68779Y1787723D01*
G01X72002Y1790026D02*
X71654Y1790367D01*
G01X51351Y1787047D02*
X51389Y1787021D01*
X51417Y1786949D01*
X51428Y1786850D01*
G01X71567Y1786358D02*
X70957Y1786870D01*
G01X71654D02*
X72264Y1786358D01*
G01X69215Y1788064D02*
X68953Y1788235D01*
G01X68779Y1787723D02*
X69128Y1787552D01*
G01X71218Y1789941D02*
X71480Y1789856D01*
G01X71654Y1790367D02*
X71306Y1790453D01*
G01X51802Y1786260D02*
X51829Y1786263D01*
X51855Y1786274D01*
X51879Y1786293D01*
X51900Y1786317D01*
X51917Y1786347D01*
X51930Y1786381D01*
X51938Y1786418D01*
X51941Y1786457D01*
G01X72264Y1785846D02*
X68169D01*
G01X92717Y1786260D02*
X85384D01*
G01X85237D02*
X73228D01*
G01X68169Y1786358D02*
X71567D01*
G01X77756Y1786634D02*
X76772D01*
G01X77756Y1786831D02*
X76772D01*
G01X70957Y1786870D02*
X71654D01*
G01X85237Y1787047D02*
X73228D01*
G01X85384D02*
X92717D01*
G01X74783Y1787205D02*
X82854D01*
G01X77756Y1787224D02*
X76772D01*
G01X74724Y1787421D02*
X81890D01*
G01X69128Y1787552D02*
X69563D01*
G01X69476Y1788064D02*
X69215D01*
G01X74724Y1788996D02*
X81890D01*
G01X82854Y1789173D02*
X74783D01*
G01X77756Y1789193D02*
X76772D01*
G01X77756Y1789587D02*
X76772D01*
G01X78346Y1789626D02*
X87331D01*
G01X77756Y1789783D02*
X76772D01*
G01X71044Y1789941D02*
X71218D01*
G01X71306Y1790453D02*
X70957D01*
G01X74331Y1791240D02*
X64961D01*
G01X74331Y1791614D02*
X94488D01*
G01X64646Y1791831D02*
X71181D01*
G01X74331Y1793012D02*
X64961D01*
G01X70957Y1790453D02*
X70608Y1790367D01*
G01X69302Y1790709D02*
X68953Y1790623D01*
G01X74331Y1789390D02*
G03X74724Y1788996I394J0D01*
G01Y1787421D02*
G03X74331Y1787028I1J-394D01*
G01X46784Y1788996D02*
X46644Y1788800D01*
X46506Y1788603D01*
X46369Y1788406D01*
G01X50987Y1788012D02*
X50909Y1787421D01*
G01X46369Y1788012D02*
Y1788406D01*
G01X46506Y1786850D02*
Y1786457D01*
G01X50987Y1788012D02*
Y1788406D01*
G01D02*
X50909Y1788996D01*
G01X46506Y1786457D02*
X46538Y1786359D01*
X46626Y1786287D01*
X46753Y1786260D01*
G01X46369Y1788012D02*
X46506Y1787814D01*
X46644Y1787617D01*
X46784Y1787421D01*
G01X42520Y1793996D02*
X44488Y1792028D01*
G01X46753Y1786260D02*
X52838D01*
G01X53118Y1786457D02*
X46506D01*
G01Y1786850D02*
X53118D01*
G01X46753Y1787047D02*
X52838D01*
G01X46784Y1787421D02*
X52529D01*
G01X46369Y1788012D02*
X52956D01*
G01Y1788406D02*
X46369D01*
G01X52529Y1788996D02*
X46784D01*
G01X62992Y1792028D02*
X44488D01*
G01X73228Y1792421D02*
X42520D01*
G01X46753Y1787047D02*
X46626Y1787019D01*
X46537Y1786946D01*
X46506Y1786850D01*
G01X51351Y1776811D02*
X51389Y1776837D01*
X51417Y1776909D01*
X51428Y1777008D01*
G01X51351Y1773661D02*
X51389Y1773688D01*
X51417Y1773760D01*
X51428Y1773858D01*
G01X51351Y1770512D02*
X51389Y1770538D01*
X51417Y1770610D01*
X51428Y1770709D01*
G01X51351Y1761063D02*
X51389Y1761089D01*
X51417Y1761161D01*
X51428Y1761260D01*
G01X51351Y1757913D02*
X51389Y1757940D01*
X51417Y1758012D01*
X51428Y1758110D01*
G01X51351Y1742165D02*
X51389Y1742192D01*
X51417Y1742264D01*
X51428Y1742362D01*
G01X52597Y1757421D02*
X53021Y1758012D01*
G01X52597Y1732421D02*
X53021Y1733012D01*
G01X52529Y1782421D02*
X52956Y1783012D01*
G01X52529Y1777421D02*
X52956Y1778012D01*
G01X52529Y1772421D02*
X52956Y1773012D01*
G01X52529Y1767421D02*
X52956Y1768012D01*
G01X52529Y1762421D02*
X52956Y1763012D01*
G01X52529Y1727421D02*
X52956Y1728012D01*
G01X52112Y1783012D02*
X51839Y1782421D01*
G01X52112Y1778012D02*
X51839Y1777421D01*
G01X52112Y1773012D02*
X51839Y1772421D01*
G01X52112Y1768012D02*
X51839Y1767421D01*
G01X52112Y1763012D02*
X51839Y1762421D01*
G01X52112Y1758012D02*
X51839Y1757421D01*
G01X52112Y1733012D02*
X51839Y1732421D01*
G01X52112Y1728012D02*
X51839Y1727421D01*
G01X51428Y1783307D02*
X51417Y1783209D01*
X51389Y1783137D01*
X51351Y1783110D01*
G01X51428Y1780157D02*
X51417Y1780059D01*
X51389Y1779987D01*
X51351Y1779961D01*
G01X51428Y1767559D02*
X51417Y1767461D01*
X51389Y1767389D01*
X51351Y1767362D01*
G01X51428Y1764409D02*
X51417Y1764311D01*
X51389Y1764239D01*
X51351Y1764213D01*
G01X51428Y1754961D02*
X51417Y1754862D01*
X51389Y1754790D01*
X51351Y1754764D01*
G01X51428Y1751811D02*
X51417Y1751713D01*
X51389Y1751641D01*
X51351Y1751614D01*
G01X51428Y1748661D02*
X51417Y1748563D01*
X51389Y1748491D01*
X51351Y1748465D01*
G01X51428Y1745512D02*
X51417Y1745413D01*
X51389Y1745341D01*
X51351Y1745315D01*
G01X51428Y1739213D02*
X51417Y1739114D01*
X51389Y1739042D01*
X51351Y1739016D01*
G01X51428Y1736063D02*
X51417Y1735965D01*
X51389Y1735893D01*
X51351Y1735866D01*
G01X51428Y1732913D02*
X51417Y1732815D01*
X51389Y1732743D01*
X51351Y1732717D01*
G01X51428Y1729764D02*
X51417Y1729665D01*
X51389Y1729593D01*
X51351Y1729567D01*
G01X51428Y1726614D02*
X51417Y1726516D01*
X51389Y1726444D01*
X51351Y1726417D01*
G01X51428Y1780551D02*
Y1780157D01*
G01Y1783701D02*
Y1783307D01*
G01Y1777402D02*
Y1777008D01*
G01Y1771102D02*
Y1770709D01*
G01Y1774252D02*
Y1773858D01*
G01Y1767953D02*
Y1767559D01*
G01Y1761654D02*
Y1761260D01*
G01Y1764803D02*
Y1764409D01*
G01Y1758504D02*
Y1758110D01*
G01Y1755354D02*
Y1754961D01*
G01Y1752205D02*
Y1751811D01*
G01Y1749055D02*
Y1748661D01*
G01Y1745906D02*
Y1745512D01*
G01Y1742756D02*
Y1742362D01*
G01Y1739606D02*
Y1739213D01*
G01Y1733307D02*
Y1732913D01*
G01Y1736457D02*
Y1736063D01*
G01Y1730157D02*
Y1729764D01*
G01Y1727008D02*
Y1726614D01*
G01X51872Y1754072D02*
Y1753088D01*
G01Y1750923D02*
Y1749939D01*
G01Y1747773D02*
Y1746789D01*
G01Y1744624D02*
Y1743639D01*
G01Y1738324D02*
Y1737340D01*
G01Y1741474D02*
Y1740490D01*
G01X51941Y1726614D02*
Y1727008D01*
G01Y1729764D02*
Y1730157D01*
G01Y1732913D02*
Y1733307D01*
G01Y1736063D02*
Y1736457D01*
G01Y1739213D02*
Y1739606D01*
G01Y1745512D02*
Y1745906D01*
G01Y1742362D02*
Y1742756D01*
G01Y1748661D02*
Y1749055D01*
G01Y1754961D02*
Y1755354D01*
G01Y1751811D02*
Y1752205D01*
G01Y1758110D02*
Y1758504D01*
G01Y1761260D02*
Y1761654D01*
G01Y1764409D02*
Y1764803D01*
G01Y1767559D02*
Y1767953D01*
G01Y1770709D02*
Y1771102D01*
G01Y1773858D02*
Y1774252D01*
G01Y1777008D02*
Y1777402D01*
G01Y1780157D02*
Y1780551D01*
G01Y1783307D02*
Y1783701D01*
G01X52112Y1783406D02*
Y1783012D01*
G01Y1778406D02*
Y1778012D01*
G01Y1773406D02*
Y1773012D01*
G01Y1768406D02*
Y1768012D01*
G01Y1763406D02*
Y1763012D01*
G01Y1758406D02*
Y1758012D01*
G01Y1733406D02*
Y1733012D01*
G01Y1728406D02*
Y1728012D01*
G01X52814Y1754072D02*
Y1753088D01*
G01Y1750923D02*
Y1749939D01*
G01Y1747773D02*
Y1746789D01*
G01Y1744624D02*
Y1743639D01*
G01Y1738324D02*
Y1737340D01*
G01Y1741474D02*
Y1740490D01*
G01X52956Y1783406D02*
Y1783012D01*
G01Y1778406D02*
Y1778012D01*
G01Y1773406D02*
Y1773012D01*
G01Y1768406D02*
Y1768012D01*
G01Y1763406D02*
Y1763012D01*
G01Y1728406D02*
Y1728012D01*
G01X53021Y1758406D02*
Y1758012D01*
G01Y1733406D02*
Y1733012D01*
G01X53118Y1726614D02*
Y1727008D01*
G01Y1729764D02*
Y1730157D01*
G01Y1732913D02*
Y1733307D01*
G01Y1736063D02*
Y1736457D01*
G01Y1739213D02*
Y1739606D01*
G01Y1745512D02*
Y1745906D01*
G01Y1742362D02*
Y1742756D01*
G01Y1748661D02*
Y1749055D01*
G01Y1754961D02*
Y1755354D01*
G01Y1751811D02*
Y1752205D01*
G01Y1758110D02*
Y1758504D01*
G01Y1761260D02*
Y1761654D01*
G01Y1764409D02*
Y1764803D01*
G01Y1767559D02*
Y1767953D01*
G01Y1770709D02*
Y1771102D01*
G01Y1773858D02*
Y1774252D01*
G01Y1777008D02*
Y1777402D01*
G01Y1780157D02*
Y1780551D01*
G01Y1783307D02*
Y1783701D01*
G01X51872Y1753088D02*
X51869Y1753050D01*
X51861Y1753013D01*
X51847Y1752980D01*
X51829Y1752949D01*
X51807Y1752925D01*
X51781Y1752907D01*
X51754Y1752895D01*
X51724Y1752891D01*
G01X51872Y1749939D02*
X51869Y1749900D01*
X51861Y1749864D01*
X51847Y1749830D01*
X51829Y1749800D01*
X51807Y1749775D01*
X51781Y1749757D01*
X51754Y1749746D01*
X51724Y1749742D01*
G01X51872Y1746789D02*
X51869Y1746751D01*
X51861Y1746714D01*
X51847Y1746680D01*
X51829Y1746650D01*
X51807Y1746626D01*
X51781Y1746607D01*
X51754Y1746596D01*
X51724Y1746592D01*
G01X51872Y1743639D02*
X51869Y1743601D01*
X51861Y1743565D01*
X51847Y1743531D01*
X51829Y1743500D01*
X51807Y1743476D01*
X51781Y1743458D01*
X51754Y1743446D01*
X51724Y1743443D01*
G01X51872Y1740490D02*
X51869Y1740452D01*
X51861Y1740415D01*
X51847Y1740381D01*
X51829Y1740351D01*
X51807Y1740326D01*
X51781Y1740308D01*
X51754Y1740297D01*
X51724Y1740293D01*
G01X51872Y1737340D02*
X51869Y1737302D01*
X51861Y1737265D01*
X51847Y1737231D01*
X51829Y1737201D01*
X51807Y1737177D01*
X51781Y1737159D01*
X51754Y1737147D01*
X51724Y1737143D01*
G01X51941Y1727008D02*
X51938Y1727046D01*
X51930Y1727083D01*
X51917Y1727117D01*
X51900Y1727147D01*
X51879Y1727171D01*
X51856Y1727189D01*
X51830Y1727201D01*
X51802Y1727205D01*
G01X51941Y1730157D02*
X51938Y1730196D01*
X51930Y1730232D01*
X51917Y1730266D01*
X51900Y1730296D01*
X51879Y1730321D01*
X51856Y1730339D01*
X51830Y1730350D01*
X51802Y1730354D01*
G01X51941Y1733307D02*
X51938Y1733345D01*
X51930Y1733382D01*
X51917Y1733416D01*
X51900Y1733446D01*
X51879Y1733470D01*
X51856Y1733489D01*
X51830Y1733500D01*
X51802Y1733504D01*
G01X51941Y1736457D02*
X51938Y1736495D01*
X51930Y1736531D01*
X51917Y1736565D01*
X51900Y1736596D01*
X51879Y1736620D01*
X51856Y1736638D01*
X51830Y1736650D01*
X51802Y1736654D01*
G01X51941Y1739606D02*
X51938Y1739644D01*
X51930Y1739681D01*
X51917Y1739715D01*
X51900Y1739745D01*
X51879Y1739770D01*
X51856Y1739788D01*
X51830Y1739799D01*
X51802Y1739803D01*
G01X51941Y1742756D02*
X51938Y1742794D01*
X51930Y1742831D01*
X51917Y1742865D01*
X51900Y1742895D01*
X51879Y1742919D01*
X51856Y1742937D01*
X51830Y1742949D01*
X51802Y1742953D01*
G01X51941Y1745906D02*
X51938Y1745944D01*
X51930Y1745980D01*
X51917Y1746014D01*
X51900Y1746044D01*
X51879Y1746069D01*
X51856Y1746087D01*
X51830Y1746098D01*
X51802Y1746102D01*
G01X51941Y1749055D02*
X51938Y1749093D01*
X51930Y1749130D01*
X51917Y1749164D01*
X51900Y1749194D01*
X51879Y1749219D01*
X51856Y1749237D01*
X51830Y1749248D01*
X51802Y1749252D01*
G01X51941Y1752205D02*
X51938Y1752243D01*
X51930Y1752280D01*
X51917Y1752313D01*
X51900Y1752344D01*
X51879Y1752368D01*
X51856Y1752386D01*
X51830Y1752398D01*
X51802Y1752402D01*
G01X51941Y1755354D02*
X51938Y1755393D01*
X51930Y1755429D01*
X51917Y1755463D01*
X51900Y1755493D01*
X51879Y1755518D01*
X51856Y1755536D01*
X51830Y1755547D01*
X51802Y1755551D01*
G01X51941Y1758504D02*
X51938Y1758542D01*
X51930Y1758579D01*
X51917Y1758613D01*
X51900Y1758643D01*
X51879Y1758667D01*
X51856Y1758685D01*
X51830Y1758697D01*
X51802Y1758701D01*
G01X51941Y1761654D02*
X51938Y1761692D01*
X51930Y1761728D01*
X51917Y1761762D01*
X51900Y1761793D01*
X51879Y1761817D01*
X51856Y1761835D01*
X51830Y1761846D01*
X51802Y1761850D01*
G01X51941Y1764803D02*
X51938Y1764841D01*
X51930Y1764878D01*
X51917Y1764912D01*
X51900Y1764942D01*
X51879Y1764967D01*
X51856Y1764985D01*
X51830Y1764996D01*
X51802Y1765000D01*
G01X51941Y1767953D02*
X51938Y1767991D01*
X51930Y1768028D01*
X51917Y1768061D01*
X51900Y1768092D01*
X51879Y1768116D01*
X51856Y1768134D01*
X51830Y1768146D01*
X51802Y1768150D01*
G01X51941Y1771102D02*
X51938Y1771141D01*
X51930Y1771177D01*
X51917Y1771211D01*
X51900Y1771241D01*
X51879Y1771266D01*
X51856Y1771284D01*
X51830Y1771295D01*
X51802Y1771299D01*
G01X51941Y1774252D02*
X51938Y1774290D01*
X51930Y1774327D01*
X51917Y1774361D01*
X51900Y1774391D01*
X51879Y1774415D01*
X51856Y1774433D01*
X51830Y1774445D01*
X51802Y1774449D01*
G01X51941Y1777402D02*
X51938Y1777440D01*
X51930Y1777476D01*
X51917Y1777510D01*
X51900Y1777541D01*
X51879Y1777565D01*
X51856Y1777583D01*
X51830Y1777594D01*
X51802Y1777598D01*
G01X51941Y1780551D02*
X51938Y1780589D01*
X51930Y1780626D01*
X51917Y1780660D01*
X51900Y1780690D01*
X51879Y1780715D01*
X51856Y1780733D01*
X51830Y1780744D01*
X51802Y1780748D01*
G01X51941Y1783701D02*
X51938Y1783739D01*
X51930Y1783776D01*
X51917Y1783809D01*
X51900Y1783840D01*
X51879Y1783864D01*
X51856Y1783882D01*
X51830Y1783894D01*
X51802Y1783898D01*
G01X69213Y1735965D02*
Y1755453D01*
G01Y1757815D02*
Y1773051D01*
G01Y1775413D02*
Y1791831D01*
G01X74409Y1736063D02*
Y1755354D01*
G01X74724D02*
Y1736063D01*
G01X75170Y1780748D02*
Y1779961D01*
G01Y1783898D02*
Y1783110D01*
G01Y1777598D02*
Y1776811D01*
G01Y1771299D02*
Y1770512D01*
G01Y1774449D02*
Y1773661D01*
G01Y1768150D02*
Y1767362D01*
G01Y1761850D02*
Y1761063D01*
G01Y1765000D02*
Y1764213D01*
G01Y1758701D02*
Y1757913D01*
G01Y1752402D02*
Y1751614D01*
G01Y1755551D02*
Y1754764D01*
G01Y1749252D02*
Y1748465D01*
G01Y1742953D02*
Y1742165D01*
G01Y1746102D02*
Y1745315D01*
G01Y1739803D02*
Y1739016D01*
G01Y1733504D02*
Y1732717D01*
G01Y1736654D02*
Y1735866D01*
G01Y1730354D02*
Y1729567D01*
G01Y1727205D02*
Y1726417D01*
G01X75197Y1780748D02*
Y1779961D01*
G01Y1783898D02*
Y1783110D01*
G01Y1777598D02*
Y1776811D01*
G01Y1771299D02*
Y1770512D01*
G01Y1774449D02*
Y1773661D01*
G01Y1768150D02*
Y1767362D01*
G01Y1761850D02*
Y1761063D01*
G01Y1765000D02*
Y1764213D01*
G01Y1758701D02*
Y1757913D01*
G01Y1752402D02*
Y1751614D01*
G01Y1755551D02*
Y1754764D01*
G01Y1749252D02*
Y1748465D01*
G01Y1742953D02*
Y1742165D01*
G01Y1746102D02*
Y1745315D01*
G01Y1739803D02*
Y1739016D01*
G01Y1733504D02*
Y1732717D01*
G01Y1736654D02*
Y1735866D01*
G01Y1730354D02*
Y1729567D01*
G01Y1727205D02*
Y1726417D01*
G01X75237Y1754764D02*
Y1752402D01*
G01Y1748465D02*
Y1746102D01*
G01Y1751614D02*
Y1749252D01*
G01Y1745315D02*
Y1742953D01*
G01Y1742165D02*
Y1739803D01*
G01Y1739016D02*
Y1736654D01*
G01X75512Y1755354D02*
Y1736063D01*
G01X75573Y1780748D02*
Y1779961D01*
G01Y1783898D02*
Y1783110D01*
G01Y1777598D02*
Y1776811D01*
G01Y1771299D02*
Y1770512D01*
G01Y1774449D02*
Y1773661D01*
G01Y1768150D02*
Y1767362D01*
G01Y1761850D02*
Y1761063D01*
G01Y1765000D02*
Y1764213D01*
G01Y1758701D02*
Y1757913D01*
G01Y1752402D02*
Y1751614D01*
G01Y1755551D02*
Y1754764D01*
G01Y1749252D02*
Y1748465D01*
G01Y1742953D02*
Y1742165D01*
G01Y1746102D02*
Y1745315D01*
G01Y1739803D02*
Y1739016D01*
G01Y1733504D02*
Y1732717D01*
G01Y1736654D02*
Y1735866D01*
G01Y1730354D02*
Y1729567D01*
G01Y1727205D02*
Y1726417D01*
G01X75787Y1783996D02*
Y1782421D01*
G01Y1778996D02*
Y1777421D01*
G01Y1773996D02*
Y1772421D01*
G01Y1768996D02*
Y1767421D01*
G01Y1763996D02*
Y1762421D01*
G01Y1758996D02*
Y1757421D01*
G01Y1733996D02*
Y1732421D01*
G01Y1728996D02*
Y1727421D01*
G01X76012Y1736063D02*
Y1755354D01*
G01X76222Y1754862D02*
Y1736555D01*
G01X76772Y1784783D02*
Y1781634D01*
G01Y1779783D02*
Y1776634D01*
G01Y1774783D02*
Y1771634D01*
G01Y1769783D02*
Y1766634D01*
G01Y1764783D02*
Y1761634D01*
G01Y1759783D02*
Y1756634D01*
G01Y1734783D02*
Y1731634D01*
G01Y1729783D02*
Y1726634D01*
G01X76929Y1755354D02*
Y1736063D01*
G01X77206Y1754173D02*
Y1752992D01*
G01Y1747874D02*
Y1746693D01*
G01Y1751024D02*
Y1749843D01*
G01Y1744724D02*
Y1743543D01*
G01Y1741575D02*
Y1740394D01*
G01Y1738425D02*
Y1737244D01*
G01X77756Y1784783D02*
Y1781634D01*
G01Y1779783D02*
Y1776634D01*
G01Y1774783D02*
Y1771634D01*
G01Y1769783D02*
Y1766634D01*
G01Y1764783D02*
Y1761634D01*
G01Y1759783D02*
Y1756634D01*
G01Y1734783D02*
Y1731634D01*
G01Y1729783D02*
Y1726634D01*
G01X78740Y1783996D02*
Y1782421D01*
G01Y1778996D02*
Y1777421D01*
G01Y1773996D02*
Y1772421D01*
G01Y1768996D02*
Y1767421D01*
G01Y1763996D02*
Y1762421D01*
G01Y1758996D02*
Y1757421D01*
G01Y1733996D02*
Y1732421D01*
G01Y1728996D02*
Y1727421D01*
G01X78935Y1726417D02*
Y1727205D01*
G01Y1729567D02*
Y1730354D01*
G01Y1732717D02*
Y1733504D01*
G01Y1735866D02*
Y1736654D01*
G01Y1739016D02*
Y1739803D01*
G01Y1742165D02*
Y1742953D01*
G01Y1745315D02*
Y1746102D01*
G01Y1748465D02*
Y1749252D01*
G01Y1751614D02*
Y1752402D01*
G01Y1754764D02*
Y1755551D01*
G01Y1757913D02*
Y1758701D01*
G01Y1761063D02*
Y1761850D01*
G01Y1764213D02*
Y1765000D01*
G01Y1767362D02*
Y1768150D01*
G01Y1770512D02*
Y1771299D01*
G01Y1773661D02*
Y1774449D01*
G01Y1776811D02*
Y1777598D01*
G01Y1779961D02*
Y1780748D01*
G01Y1783110D02*
Y1783898D01*
G01X80285Y1755354D02*
Y1736063D01*
G01X80337Y1739882D02*
Y1742087D01*
G01Y1749331D02*
Y1751535D01*
G01X80356Y1740394D02*
Y1741575D01*
G01Y1737244D02*
Y1738425D01*
G01Y1743543D02*
Y1744724D01*
G01Y1746693D02*
Y1747874D01*
G01Y1749843D02*
Y1751024D01*
G01Y1752992D02*
Y1754173D01*
G01X80763Y1755354D02*
Y1751535D01*
G01Y1749331D02*
Y1742087D01*
G01Y1739882D02*
Y1736063D01*
G01X80919Y1726417D02*
Y1727205D01*
G01Y1729567D02*
Y1730354D01*
G01Y1732717D02*
Y1733504D01*
G01Y1735866D02*
Y1736654D01*
G01Y1739016D02*
Y1739803D01*
G01Y1742165D02*
Y1742953D01*
G01Y1745315D02*
Y1746102D01*
G01Y1748465D02*
Y1749252D01*
G01Y1751614D02*
Y1752402D01*
G01Y1754764D02*
Y1755551D01*
G01Y1757913D02*
Y1758701D01*
G01Y1761063D02*
Y1761850D01*
G01Y1764213D02*
Y1765000D01*
G01Y1767362D02*
Y1768150D01*
G01Y1770512D02*
Y1771299D01*
G01Y1773661D02*
Y1774449D01*
G01Y1776811D02*
Y1777598D01*
G01Y1779961D02*
Y1780748D01*
G01Y1783110D02*
Y1783898D01*
G01X81890Y1727421D02*
Y1728996D01*
G01Y1732421D02*
Y1733996D01*
G01Y1757421D02*
Y1758996D01*
G01Y1762421D02*
Y1763996D01*
G01Y1767421D02*
Y1768996D01*
G01Y1772421D02*
Y1773996D01*
G01Y1777421D02*
Y1778996D01*
G01Y1782421D02*
Y1783996D01*
G01X82220Y1751535D02*
Y1749331D01*
G01Y1742087D02*
Y1739882D01*
G01X82570Y1780748D02*
Y1779961D01*
G01Y1783898D02*
Y1783110D01*
G01Y1777598D02*
Y1776811D01*
G01Y1771299D02*
Y1770512D01*
G01Y1774449D02*
Y1773661D01*
G01Y1768150D02*
Y1767362D01*
G01Y1761850D02*
Y1761063D01*
G01Y1765000D02*
Y1764213D01*
G01Y1758701D02*
Y1757913D01*
G01Y1752402D02*
Y1751614D01*
G01Y1755551D02*
Y1754764D01*
G01Y1749252D02*
Y1748465D01*
G01Y1742953D02*
Y1742165D01*
G01Y1746102D02*
Y1745315D01*
G01Y1739803D02*
Y1739016D01*
G01Y1733504D02*
Y1732717D01*
G01Y1736654D02*
Y1735866D01*
G01Y1730354D02*
Y1729567D01*
G01Y1727205D02*
Y1726417D01*
G01X84298Y1727205D02*
Y1729567D01*
G01Y1730354D02*
Y1732717D01*
G01Y1733504D02*
Y1735866D01*
G01Y1736654D02*
Y1739016D01*
G01Y1739803D02*
Y1742165D01*
G01Y1742953D02*
Y1745315D01*
G01Y1746102D02*
Y1748465D01*
G01Y1749252D02*
Y1751614D01*
G01Y1752402D02*
Y1754764D01*
G01Y1755551D02*
Y1757913D01*
G01Y1758701D02*
Y1761063D01*
G01Y1761850D02*
Y1764213D01*
G01Y1765000D02*
Y1767362D01*
G01Y1768150D02*
Y1770512D01*
G01Y1771299D02*
Y1773661D01*
G01Y1774449D02*
Y1776811D01*
G01Y1777598D02*
Y1779961D01*
G01Y1780748D02*
Y1783110D01*
G01Y1783898D02*
Y1786260D01*
G01X85237Y1780748D02*
Y1779961D01*
G01Y1783898D02*
Y1783110D01*
G01Y1777598D02*
Y1776811D01*
G01Y1771299D02*
Y1770512D01*
G01Y1774449D02*
Y1773661D01*
G01Y1768150D02*
Y1767362D01*
G01Y1761850D02*
Y1761063D01*
G01Y1765000D02*
Y1764213D01*
G01Y1758701D02*
Y1757913D01*
G01Y1752402D02*
Y1751614D01*
G01Y1755551D02*
Y1754764D01*
G01Y1749252D02*
Y1748465D01*
G01Y1742953D02*
Y1742165D01*
G01Y1746102D02*
Y1745315D01*
G01Y1739803D02*
Y1739016D01*
G01Y1733504D02*
Y1732717D01*
G01Y1736654D02*
Y1735866D01*
G01Y1730354D02*
Y1729567D01*
G01Y1727205D02*
Y1726417D01*
G01X85384Y1780748D02*
Y1779961D01*
G01Y1783898D02*
Y1783110D01*
G01Y1777598D02*
Y1776811D01*
G01Y1771299D02*
Y1770512D01*
G01Y1774449D02*
Y1773661D01*
G01Y1768150D02*
Y1767362D01*
G01Y1761850D02*
Y1761063D01*
G01Y1765000D02*
Y1764213D01*
G01Y1758701D02*
Y1757913D01*
G01Y1752402D02*
Y1751614D01*
G01Y1755551D02*
Y1754764D01*
G01Y1749252D02*
Y1748465D01*
G01Y1742953D02*
Y1742165D01*
G01Y1746102D02*
Y1745315D01*
G01Y1739803D02*
Y1739016D01*
G01Y1733504D02*
Y1732717D01*
G01Y1736654D02*
Y1735866D01*
G01Y1730354D02*
Y1729567D01*
G01Y1727205D02*
Y1726417D01*
G01X86976Y1780748D02*
Y1779961D01*
G01Y1783898D02*
Y1783110D01*
G01Y1777598D02*
Y1776811D01*
G01Y1771299D02*
Y1770512D01*
G01Y1774449D02*
Y1773661D01*
G01Y1768150D02*
Y1767362D01*
G01Y1761850D02*
Y1761063D01*
G01Y1765000D02*
Y1764213D01*
G01Y1758701D02*
Y1757913D01*
G01Y1752402D02*
Y1751614D01*
G01Y1755551D02*
Y1754764D01*
G01Y1749252D02*
Y1748465D01*
G01Y1742953D02*
Y1742165D01*
G01Y1746102D02*
Y1745315D01*
G01Y1739803D02*
Y1739016D01*
G01Y1733504D02*
Y1732717D01*
G01Y1736654D02*
Y1735866D01*
G01Y1730354D02*
Y1729567D01*
G01Y1727205D02*
Y1726417D01*
G01X87918D02*
Y1727205D01*
G01Y1729567D02*
Y1730354D01*
G01Y1732717D02*
Y1733504D01*
G01Y1735866D02*
Y1736654D01*
G01Y1739016D02*
Y1739803D01*
G01Y1742165D02*
Y1742953D01*
G01Y1745315D02*
Y1746102D01*
G01Y1748465D02*
Y1749252D01*
G01Y1751614D02*
Y1752402D01*
G01Y1754764D02*
Y1755551D01*
G01Y1757913D02*
Y1758701D01*
G01Y1761063D02*
Y1761850D01*
G01Y1764213D02*
Y1765000D01*
G01Y1767362D02*
Y1768150D01*
G01Y1770512D02*
Y1771299D01*
G01Y1773661D02*
Y1774449D01*
G01Y1776811D02*
Y1777598D01*
G01Y1779961D02*
Y1780748D01*
G01Y1783110D02*
Y1783898D01*
G01X90754Y1726417D02*
Y1727205D01*
G01Y1729567D02*
Y1730354D01*
G01Y1732717D02*
Y1733504D01*
G01Y1735866D02*
Y1736654D01*
G01Y1739016D02*
Y1739803D01*
G01Y1742165D02*
Y1742953D01*
G01Y1745315D02*
Y1746102D01*
G01Y1748465D02*
Y1749252D01*
G01Y1751614D02*
Y1752402D01*
G01Y1754764D02*
Y1755551D01*
G01Y1757913D02*
Y1758701D01*
G01Y1761063D02*
Y1761850D01*
G01Y1764213D02*
Y1765000D01*
G01Y1767362D02*
Y1768150D01*
G01Y1770512D02*
Y1771299D01*
G01Y1773661D02*
Y1774449D01*
G01Y1776811D02*
Y1777598D01*
G01Y1779961D02*
Y1780748D01*
G01Y1783110D02*
Y1783898D01*
G01X90943Y1780748D02*
Y1779961D01*
G01Y1783898D02*
Y1783110D01*
G01Y1777598D02*
Y1776811D01*
G01Y1771299D02*
Y1770512D01*
G01Y1774449D02*
Y1773661D01*
G01Y1768150D02*
Y1767362D01*
G01Y1761850D02*
Y1761063D01*
G01Y1765000D02*
Y1764213D01*
G01Y1758701D02*
Y1757913D01*
G01Y1752402D02*
Y1751614D01*
G01Y1755551D02*
Y1754764D01*
G01Y1749252D02*
Y1748465D01*
G01Y1742953D02*
Y1742165D01*
G01Y1746102D02*
Y1745315D01*
G01Y1739803D02*
Y1739016D01*
G01Y1733504D02*
Y1732717D01*
G01Y1736654D02*
Y1735866D01*
G01Y1730354D02*
Y1729567D01*
G01Y1727205D02*
Y1726417D01*
G01X92717Y1780748D02*
Y1779961D01*
G01Y1783898D02*
Y1783110D01*
G01Y1777598D02*
Y1776811D01*
G01Y1771299D02*
Y1770512D01*
G01Y1774449D02*
Y1773661D01*
G01Y1768150D02*
Y1767362D01*
G01Y1761850D02*
Y1761063D01*
G01Y1765000D02*
Y1764213D01*
G01Y1758701D02*
Y1757913D01*
G01Y1752402D02*
Y1751614D01*
G01Y1755551D02*
Y1754764D01*
G01Y1749252D02*
Y1748465D01*
G01Y1742953D02*
Y1742165D01*
G01Y1746102D02*
Y1745315D01*
G01Y1739803D02*
Y1739016D01*
G01Y1733504D02*
Y1732717D01*
G01Y1736654D02*
Y1735866D01*
G01Y1730354D02*
Y1729567D01*
G01Y1727205D02*
Y1726417D01*
G01X51839Y1728996D02*
X52112Y1728406D01*
G01X51839Y1733996D02*
X52112Y1733406D01*
G01X51839Y1758996D02*
X52112Y1758406D01*
G01X51839Y1763996D02*
X52112Y1763406D01*
G01X51839Y1768996D02*
X52112Y1768406D01*
G01X51839Y1773996D02*
X52112Y1773406D01*
G01X51839Y1778996D02*
X52112Y1778406D01*
G01X51839Y1783996D02*
X52112Y1783406D01*
G01X52529Y1728996D02*
X52956Y1728406D01*
G01X52529Y1763996D02*
X52956Y1763406D01*
G01X52529Y1768996D02*
X52956Y1768406D01*
G01X52529Y1773996D02*
X52956Y1773406D01*
G01X52597Y1733996D02*
X53021Y1733406D01*
G01X52597Y1758996D02*
X53021Y1758406D01*
G01X52529Y1778996D02*
X52956Y1778406D01*
G01X52529Y1783996D02*
X52956Y1783406D01*
G01X51351Y1727205D02*
X51389Y1727178D01*
X51417Y1727106D01*
X51428Y1727008D01*
G01X51351Y1730354D02*
X51389Y1730328D01*
X51417Y1730256D01*
X51428Y1730157D01*
G01X51351Y1733504D02*
X51389Y1733478D01*
X51417Y1733406D01*
X51428Y1733307D01*
G01X51351Y1736654D02*
X51389Y1736627D01*
X51417Y1736555D01*
X51428Y1736457D01*
G01X51351Y1739803D02*
X51389Y1739777D01*
X51417Y1739705D01*
X51428Y1739606D01*
G01X51351Y1742953D02*
X51389Y1742926D01*
X51417Y1742854D01*
X51428Y1742756D01*
G01X51351Y1746102D02*
X51389Y1746076D01*
X51417Y1746004D01*
X51428Y1745906D01*
G01X51351Y1749252D02*
X51389Y1749226D01*
X51417Y1749154D01*
X51428Y1749055D01*
G01X51351Y1752402D02*
X51389Y1752375D01*
X51417Y1752303D01*
X51428Y1752205D01*
G01X51351Y1755551D02*
X51389Y1755525D01*
X51417Y1755453D01*
X51428Y1755354D01*
G01X51351Y1758701D02*
X51389Y1758674D01*
X51417Y1758602D01*
X51428Y1758504D01*
G01X51351Y1761850D02*
X51389Y1761824D01*
X51417Y1761752D01*
X51428Y1761654D01*
G01X51351Y1765000D02*
X51389Y1764974D01*
X51417Y1764902D01*
X51428Y1764803D01*
G01X51351Y1768150D02*
X51389Y1768123D01*
X51417Y1768051D01*
X51428Y1767953D01*
G01X51351Y1771299D02*
X51389Y1771273D01*
X51417Y1771201D01*
X51428Y1771102D01*
G01X51351Y1774449D02*
X51389Y1774422D01*
X51417Y1774350D01*
X51428Y1774252D01*
G01X51351Y1777598D02*
X51389Y1777572D01*
X51417Y1777500D01*
X51428Y1777402D01*
G01X51351Y1780748D02*
X51389Y1780722D01*
X51417Y1780650D01*
X51428Y1780551D01*
G01X51351Y1783898D02*
X51389Y1783871D01*
X51417Y1783799D01*
X51428Y1783701D01*
G01X51724Y1738521D02*
X51753Y1738518D01*
X51781Y1738506D01*
X51806Y1738489D01*
X51829Y1738464D01*
X51847Y1738434D01*
X51861Y1738400D01*
X51869Y1738363D01*
X51872Y1738324D01*
G01X51724Y1741671D02*
X51753Y1741667D01*
X51781Y1741656D01*
X51806Y1741638D01*
X51829Y1741613D01*
X51847Y1741583D01*
X51861Y1741550D01*
X51869Y1741513D01*
X51872Y1741474D01*
G01X51724Y1744820D02*
X51753Y1744817D01*
X51781Y1744806D01*
X51806Y1744788D01*
X51829Y1744763D01*
X51847Y1744733D01*
X51861Y1744699D01*
X51869Y1744663D01*
X51872Y1744624D01*
G01X51724Y1747970D02*
X51753Y1747967D01*
X51781Y1747955D01*
X51806Y1747937D01*
X51829Y1747913D01*
X51847Y1747883D01*
X51861Y1747849D01*
X51869Y1747812D01*
X51872Y1747773D01*
G01X51724Y1751120D02*
X51753Y1751116D01*
X51781Y1751105D01*
X51806Y1751087D01*
X51829Y1751062D01*
X51847Y1751032D01*
X51861Y1750998D01*
X51869Y1750962D01*
X51872Y1750923D01*
G01X51724Y1754269D02*
X51753Y1754266D01*
X51781Y1754254D01*
X51806Y1754237D01*
X51829Y1754212D01*
X51847Y1754182D01*
X51861Y1754148D01*
X51869Y1754111D01*
X51872Y1754072D01*
G01X92717Y1726417D02*
X85384D01*
G01X85237D02*
X73228D01*
G01X77756Y1726634D02*
X76772D01*
G01X77756Y1726831D02*
X76772D01*
G01X85237Y1727205D02*
X73228D01*
G01X85384D02*
X92717D01*
G01X77756Y1727224D02*
X76772D01*
G01X74724Y1727421D02*
X81890D01*
G01X74724Y1728996D02*
X81890D01*
G01X77756Y1729193D02*
X76772D01*
G01X92717Y1729567D02*
X85384D01*
G01X85237D02*
X73228D01*
G01X77756Y1729587D02*
X76772D01*
G01X77756Y1729783D02*
X76772D01*
G01X85237Y1730354D02*
X73228D01*
G01X85384D02*
X92717D01*
G01X77756Y1731634D02*
X76772D01*
G01X77756Y1731831D02*
X76772D01*
G01X77756Y1732224D02*
X76772D01*
G01X74724Y1732421D02*
X81890D01*
G01X92717Y1732717D02*
X85384D01*
G01X85237D02*
X73228D01*
G01X85237Y1733504D02*
X73228D01*
G01X85384D02*
X92717D01*
G01X74724Y1733996D02*
X81890D01*
G01X77756Y1734193D02*
X76772D01*
G01X77756Y1734587D02*
X76772D01*
G01X77756Y1734783D02*
X76772D01*
G01X92717Y1735866D02*
X85384D01*
G01X85237D02*
X73228D01*
G01X74331Y1735945D02*
X73228D01*
G01Y1736063D02*
X80763D01*
G01X76222Y1736555D02*
X78346D01*
G01X85237Y1736654D02*
X73228D01*
G01X85384D02*
X92717D01*
G01X76222Y1736850D02*
X75237D01*
G01X76222Y1737047D02*
X75237D01*
G01X74331Y1737244D02*
X80356D01*
G01X74331Y1738425D02*
X80356D01*
G01X76222Y1738622D02*
X75237D01*
G01X76222Y1738819D02*
X75237D01*
G01X92717Y1739016D02*
X85384D01*
G01X85237D02*
X73228D01*
G01X85237Y1739803D02*
X73228D01*
G01X85384D02*
X92717D01*
G01X82220Y1739882D02*
X80337D01*
G01X76222Y1740000D02*
X75237D01*
G01X76222Y1740197D02*
X75237D01*
G01X74331Y1740394D02*
X80356D01*
G01X74331Y1741575D02*
X80356D01*
G01X76222Y1741772D02*
X75237D01*
G01X76222Y1741969D02*
X75237D01*
G01X82220Y1742087D02*
X80337D01*
G01X92717Y1742165D02*
X85384D01*
G01X85237D02*
X73228D01*
G01X85237Y1742953D02*
X73228D01*
G01X85384D02*
X92717D01*
G01X76222Y1743150D02*
X75237D01*
G01X76222Y1743346D02*
X75237D01*
G01X74331Y1743543D02*
X80356D01*
G01X74331Y1744724D02*
X80356D01*
G01X76222Y1744921D02*
X75237D01*
G01X76222Y1745118D02*
X75237D01*
G01X92717Y1745315D02*
X85384D01*
G01X85237D02*
X73228D01*
G01X85237Y1746102D02*
X73228D01*
G01X85384D02*
X92717D01*
G01X76222Y1746299D02*
X75237D01*
G01X76222Y1746496D02*
X75237D01*
G01X74331Y1746693D02*
X80356D01*
G01X74331Y1747874D02*
X80356D01*
G01X76222Y1748071D02*
X75237D01*
G01X76222Y1748268D02*
X75237D01*
G01X92717Y1748465D02*
X85384D01*
G01X85237D02*
X73228D01*
G01X85237Y1749252D02*
X73228D01*
G01X85384D02*
X92717D01*
G01X82220Y1749331D02*
X80337D01*
G01X76222Y1749449D02*
X75237D01*
G01X76222Y1749646D02*
X75237D01*
G01X74331Y1749843D02*
X80356D01*
G01X74331Y1751024D02*
X80356D01*
G01X76222Y1751220D02*
X75237D01*
G01X76222Y1751417D02*
X75237D01*
G01X82220Y1751535D02*
X80337D01*
G01X92717Y1751614D02*
X85384D01*
G01X85237D02*
X73228D01*
G01X85237Y1752402D02*
X73228D01*
G01X85384D02*
X92717D01*
G01X76222Y1752598D02*
X75237D01*
G01X76222Y1752795D02*
X75237D01*
G01X74331Y1752992D02*
X80356D01*
G01X74331Y1754173D02*
X80356D01*
G01X76222Y1754370D02*
X75237D01*
G01X76222Y1754567D02*
X75237D01*
G01X92717Y1754764D02*
X85384D01*
G01X85237D02*
X73228D01*
G01X78346Y1754862D02*
X76222D01*
G01X73228Y1755354D02*
X80763D01*
G01X74331Y1755472D02*
X73228D01*
G01X85237Y1755551D02*
X73228D01*
G01X85384D02*
X92717D01*
G01X77756Y1756634D02*
X76772D01*
G01X77756Y1756831D02*
X76772D01*
G01X77756Y1757224D02*
X76772D01*
G01X74724Y1757421D02*
X81890D01*
G01X92717Y1757913D02*
X85384D01*
G01X85237D02*
X73228D01*
G01X85237Y1758701D02*
X73228D01*
G01X85384D02*
X92717D01*
G01X74724Y1758996D02*
X81890D01*
G01X77756Y1759193D02*
X76772D01*
G01X77756Y1759587D02*
X76772D01*
G01X77756Y1759783D02*
X76772D01*
G01X92717Y1761063D02*
X85384D01*
G01X85237D02*
X73228D01*
G01X77756Y1761634D02*
X76772D01*
G01X77756Y1761831D02*
X76772D01*
G01X85237Y1761850D02*
X73228D01*
G01X85384D02*
X92717D01*
G01X77756Y1762224D02*
X76772D01*
G01X74724Y1762421D02*
X81890D01*
G01X74724Y1763996D02*
X81890D01*
G01X77756Y1764193D02*
X76772D01*
G01X92717Y1764213D02*
X85384D01*
G01X85237D02*
X73228D01*
G01X77756Y1764587D02*
X76772D01*
G01X77756Y1764783D02*
X76772D01*
G01X85237Y1765000D02*
X73228D01*
G01X85384D02*
X92717D01*
G01X77756Y1766634D02*
X76772D01*
G01X77756Y1766831D02*
X76772D01*
G01X77756Y1767224D02*
X76772D01*
G01X92717Y1767362D02*
X85384D01*
G01X85237D02*
X73228D01*
G01X74724Y1767421D02*
X81890D01*
G01X85237Y1768150D02*
X73228D01*
G01X85384D02*
X92717D01*
G01X74724Y1768996D02*
X81890D01*
G01X77756Y1769193D02*
X76772D01*
G01X77756Y1769587D02*
X76772D01*
G01X77756Y1769783D02*
X76772D01*
G01X92717Y1770512D02*
X85384D01*
G01X85237D02*
X73228D01*
G01X85237Y1771299D02*
X73228D01*
G01X85384D02*
X92717D01*
G01X77756Y1771634D02*
X76772D01*
G01X77756Y1771831D02*
X76772D01*
G01X77756Y1772224D02*
X76772D01*
G01X51802Y1726417D02*
X51829Y1726421D01*
X51855Y1726432D01*
X51879Y1726450D01*
X51900Y1726475D01*
X51917Y1726505D01*
X51930Y1726539D01*
X51938Y1726575D01*
X51941Y1726614D01*
G01X51802Y1729567D02*
X51829Y1729570D01*
X51855Y1729581D01*
X51879Y1729600D01*
X51900Y1729624D01*
X51917Y1729654D01*
X51930Y1729688D01*
X51938Y1729725D01*
X51941Y1729764D01*
G01X51802Y1732717D02*
X51829Y1732720D01*
X51855Y1732731D01*
X51879Y1732749D01*
X51900Y1732774D01*
X51917Y1732804D01*
X51930Y1732838D01*
X51938Y1732874D01*
X51941Y1732913D01*
G01X51802Y1735866D02*
X51829Y1735870D01*
X51855Y1735881D01*
X51879Y1735899D01*
X51900Y1735924D01*
X51917Y1735954D01*
X51930Y1735987D01*
X51938Y1736024D01*
X51941Y1736063D01*
G01X51802Y1739016D02*
X51829Y1739019D01*
X51855Y1739030D01*
X51879Y1739048D01*
X51900Y1739073D01*
X51917Y1739103D01*
X51930Y1739137D01*
X51938Y1739174D01*
X51941Y1739213D01*
G01X51802Y1742165D02*
X51829Y1742169D01*
X51855Y1742180D01*
X51879Y1742198D01*
X51900Y1742223D01*
X51917Y1742253D01*
X51930Y1742287D01*
X51938Y1742323D01*
X51941Y1742362D01*
G01X51802Y1745315D02*
X51829Y1745319D01*
X51855Y1745330D01*
X51879Y1745348D01*
X51900Y1745372D01*
X51917Y1745402D01*
X51930Y1745436D01*
X51938Y1745473D01*
X51941Y1745512D01*
G01X51802Y1748465D02*
X51829Y1748468D01*
X51855Y1748479D01*
X51879Y1748497D01*
X51900Y1748522D01*
X51917Y1748552D01*
X51930Y1748586D01*
X51938Y1748622D01*
X51941Y1748661D01*
G01X51802Y1751614D02*
X51829Y1751618D01*
X51855Y1751629D01*
X51879Y1751647D01*
X51900Y1751672D01*
X51917Y1751702D01*
X51930Y1751735D01*
X51938Y1751772D01*
X51941Y1751811D01*
G01X51802Y1754764D02*
X51829Y1754767D01*
X51855Y1754778D01*
X51879Y1754796D01*
X51900Y1754821D01*
X51917Y1754851D01*
X51930Y1754885D01*
X51938Y1754922D01*
X51941Y1754961D01*
G01X51802Y1757913D02*
X51829Y1757917D01*
X51855Y1757928D01*
X51879Y1757946D01*
X51900Y1757971D01*
X51917Y1758001D01*
X51930Y1758035D01*
X51938Y1758071D01*
X51941Y1758110D01*
G01X51802Y1761063D02*
X51829Y1761067D01*
X51855Y1761078D01*
X51879Y1761096D01*
X51900Y1761120D01*
X51917Y1761150D01*
X51930Y1761184D01*
X51938Y1761221D01*
X51941Y1761260D01*
G01X51802Y1764213D02*
X51829Y1764216D01*
X51855Y1764227D01*
X51879Y1764245D01*
X51900Y1764270D01*
X51917Y1764300D01*
X51930Y1764334D01*
X51938Y1764370D01*
X51941Y1764409D01*
G01X51802Y1767362D02*
X51829Y1767366D01*
X51855Y1767377D01*
X51879Y1767395D01*
X51900Y1767420D01*
X51917Y1767450D01*
X51930Y1767483D01*
X51938Y1767520D01*
X51941Y1767559D01*
G01X51802Y1770512D02*
X51829Y1770515D01*
X51855Y1770526D01*
X51879Y1770544D01*
X51900Y1770569D01*
X51917Y1770599D01*
X51930Y1770633D01*
X51938Y1770670D01*
X51941Y1770709D01*
G01X51802Y1773661D02*
X51829Y1773665D01*
X51855Y1773676D01*
X51879Y1773694D01*
X51900Y1773719D01*
X51917Y1773749D01*
X51930Y1773783D01*
X51938Y1773819D01*
X51941Y1773858D01*
G01X51802Y1776811D02*
X51829Y1776815D01*
X51855Y1776826D01*
X51879Y1776844D01*
X51900Y1776869D01*
X51917Y1776898D01*
X51930Y1776932D01*
X51938Y1776969D01*
X51941Y1777008D01*
G01X51802Y1779961D02*
X51829Y1779964D01*
X51855Y1779975D01*
X51879Y1779993D01*
X51900Y1780018D01*
X51917Y1780048D01*
X51930Y1780082D01*
X51938Y1780119D01*
X51941Y1780157D01*
G01X51802Y1783110D02*
X51829Y1783114D01*
X51855Y1783125D01*
X51879Y1783143D01*
X51900Y1783168D01*
X51917Y1783198D01*
X51930Y1783231D01*
X51938Y1783268D01*
X51941Y1783307D01*
G01X74724Y1772421D02*
X81890D01*
G01X92717Y1773661D02*
X85384D01*
G01X85237D02*
X73228D01*
G01X74724Y1773996D02*
X81890D01*
G01X77756Y1774193D02*
X76772D01*
G01X85237Y1774449D02*
X73228D01*
G01X85384D02*
X92717D01*
G01X77756Y1774587D02*
X76772D01*
G01X77756Y1774783D02*
X76772D01*
G01X77756Y1776634D02*
X76772D01*
G01X92717Y1776811D02*
X85384D01*
G01X85237D02*
X73228D01*
G01X77756Y1776831D02*
X76772D01*
G01X77756Y1777224D02*
X76772D01*
G01X74724Y1777421D02*
X81890D01*
G01X85237Y1777598D02*
X73228D01*
G01X85384D02*
X92717D01*
G01X74724Y1778996D02*
X81890D01*
G01X77756Y1779193D02*
X76772D01*
G01X77756Y1779587D02*
X76772D01*
G01X77756Y1779783D02*
X76772D01*
G01X92717Y1779961D02*
X85384D01*
G01X85237D02*
X73228D01*
G01X85237Y1780748D02*
X73228D01*
G01X85384D02*
X92717D01*
G01X77756Y1781634D02*
X76772D01*
G01X77756Y1781831D02*
X76772D01*
G01X77756Y1782224D02*
X76772D01*
G01X74724Y1782421D02*
X81890D01*
G01X92717Y1783110D02*
X85384D01*
G01X85237D02*
X73228D01*
G01X85237Y1783898D02*
X73228D01*
G01X85384D02*
X92717D01*
G01X74724Y1783996D02*
X81890D01*
G01X77756Y1784193D02*
X76772D01*
G01X77756Y1784587D02*
X76772D01*
G01X77756Y1784783D02*
X76772D01*
G01X74331Y1734390D02*
G03X74724Y1733996I394J0D01*
G01Y1732421D02*
G03X74331Y1732028I1J-394D01*
G01Y1729390D02*
G03X74724Y1728996I394J0D01*
G01Y1727421D02*
G03X74331Y1727028I1J-394D01*
G01Y1784390D02*
G03X74724Y1783996I394J0D01*
G01Y1782421D02*
G03X74331Y1782028I1J-394D01*
G01Y1774390D02*
G03X74724Y1773996I394J0D01*
G01Y1772421D02*
G03X74331Y1772028I1J-394D01*
G01Y1779390D02*
G03X74724Y1778996I394J0D01*
G01Y1777421D02*
G03X74331Y1777028I1J-394D01*
G01Y1769390D02*
G03X74724Y1768996I394J0D01*
G01Y1767421D02*
G03X74331Y1767028I1J-394D01*
G01Y1764390D02*
G03X74724Y1763996I394J0D01*
G01Y1762421D02*
G03X74331Y1762028I1J-394D01*
G01Y1759390D02*
G03X74724Y1758996I394J0D01*
G01Y1757421D02*
G03X74331Y1757028I1J-394D01*
G01X52529Y1722421D02*
X52956Y1723012D01*
G01X52112D02*
X51839Y1722421D01*
G01X51428Y1723465D02*
X51417Y1723366D01*
X51389Y1723294D01*
X51351Y1723268D01*
G01X51428Y1723858D02*
Y1723465D01*
G01X51941D02*
Y1723858D01*
G01X52112Y1723406D02*
Y1723012D01*
G01X52956Y1723406D02*
Y1723012D01*
G01X53118Y1723465D02*
Y1723858D01*
G01X51941D02*
X51938Y1723896D01*
X51930Y1723933D01*
X51917Y1723967D01*
X51900Y1723997D01*
X51879Y1724022D01*
X51856Y1724040D01*
X51830Y1724051D01*
X51802Y1724055D01*
G01X75170D02*
Y1723268D01*
G01X75197Y1724055D02*
Y1723268D01*
G01X75573Y1724055D02*
Y1723268D01*
G01X75787Y1723996D02*
Y1722421D01*
G01X76772Y1724783D02*
Y1721634D01*
G01X77756Y1724783D02*
Y1721634D01*
G01X78740Y1723996D02*
Y1722421D01*
G01X78935Y1723268D02*
Y1724055D01*
G01X80919Y1723268D02*
Y1724055D01*
G01X81890Y1722421D02*
Y1723996D01*
G01X82570Y1724055D02*
Y1723268D01*
G01X84298Y1724055D02*
Y1726417D01*
G01X85237Y1724055D02*
Y1723268D01*
G01X85384Y1724055D02*
Y1723268D01*
G01X86976Y1724055D02*
Y1723268D01*
G01X87918D02*
Y1724055D01*
G01X90754Y1723268D02*
Y1724055D01*
G01X90943D02*
Y1723268D01*
G01X92717Y1724055D02*
Y1723268D01*
G01X51839Y1723996D02*
X52112Y1723406D01*
G01X52529Y1723996D02*
X52956Y1723406D01*
G01X51351Y1724055D02*
X51389Y1724029D01*
X51417Y1723957D01*
X51428Y1723858D01*
G01X77756Y1721634D02*
X76772D01*
G01X77756Y1721831D02*
X76772D01*
G01X77756Y1722224D02*
X76772D01*
G01X74724Y1722421D02*
X81890D01*
G01X92717Y1723268D02*
X85384D01*
G01X85237D02*
X73228D01*
G01X74724Y1723996D02*
X81890D01*
G01X85237Y1724055D02*
X73228D01*
G01X85384D02*
X92717D01*
G01X77756Y1724193D02*
X76772D01*
G01X77756Y1724587D02*
X76772D01*
G01X77756Y1724783D02*
X76772D01*
G01X51802Y1723268D02*
X51829Y1723271D01*
X51855Y1723282D01*
X51879Y1723300D01*
X51900Y1723325D01*
X51917Y1723355D01*
X51930Y1723389D01*
X51938Y1723426D01*
X51941Y1723465D01*
G01X74331Y1724390D02*
G03X74724Y1723996I394J0D01*
G01Y1722421D02*
G03X74331Y1722028I1J-394D01*
G01X46784Y1783996D02*
X46644Y1783800D01*
X46506Y1783603D01*
X46369Y1783406D01*
G01X42520Y1733976D02*
X44488Y1735945D01*
G01X46684Y1758996D02*
X46548Y1758800D01*
X46413Y1758603D01*
X46279Y1758406D01*
G01X46684Y1733996D02*
X46548Y1733800D01*
X46413Y1733603D01*
X46279Y1733406D01*
G01X46784Y1778996D02*
X46644Y1778800D01*
X46506Y1778603D01*
X46369Y1778406D01*
G01X46784Y1773996D02*
X46644Y1773800D01*
X46506Y1773603D01*
X46369Y1773406D01*
G01X46784Y1768996D02*
X46644Y1768800D01*
X46506Y1768603D01*
X46369Y1768406D01*
G01X46784Y1763996D02*
X46644Y1763800D01*
X46506Y1763603D01*
X46369Y1763406D01*
G01X46784Y1728996D02*
X46644Y1728800D01*
X46506Y1728603D01*
X46369Y1728406D01*
G01X50987Y1783012D02*
X50909Y1782421D01*
G01X50987Y1778012D02*
X50909Y1777421D01*
G01X50987Y1773012D02*
X50909Y1772421D01*
G01X50987Y1768012D02*
X50909Y1767421D01*
G01X50987Y1763012D02*
X50909Y1762421D01*
G01X50987Y1758012D02*
X50909Y1757421D01*
G01X50987Y1733012D02*
X50909Y1732421D01*
G01X50987Y1728012D02*
X50909Y1727421D01*
G01X43531Y1729508D02*
Y1734987D01*
G01Y1756430D02*
Y1761811D01*
G01X43701Y1756634D02*
Y1734783D01*
G01Y1761811D02*
Y1792815D01*
G01X46279Y1733012D02*
Y1733406D01*
G01Y1758012D02*
Y1758406D01*
G01X46369Y1728012D02*
Y1728406D01*
G01Y1763012D02*
Y1763406D01*
G01Y1768012D02*
Y1768406D01*
G01Y1773012D02*
Y1773406D01*
G01Y1778012D02*
Y1778406D01*
G01Y1783012D02*
Y1783406D01*
G01X46496Y1737340D02*
Y1738324D01*
G01Y1740490D02*
Y1741474D01*
G01Y1743639D02*
Y1744624D01*
G01Y1749939D02*
Y1750923D01*
G01Y1746789D02*
Y1747773D01*
G01Y1753088D02*
Y1754072D01*
G01X46506Y1780551D02*
Y1780157D01*
G01Y1783701D02*
Y1783307D01*
G01Y1777402D02*
Y1777008D01*
G01Y1771102D02*
Y1770709D01*
G01Y1774252D02*
Y1773858D01*
G01Y1767953D02*
Y1767559D01*
G01Y1761654D02*
Y1761260D01*
G01Y1764803D02*
Y1764409D01*
G01Y1758504D02*
Y1758110D01*
G01Y1755354D02*
Y1754961D01*
G01Y1752205D02*
Y1751811D01*
G01Y1749055D02*
Y1748661D01*
G01Y1745906D02*
Y1745512D01*
G01Y1742756D02*
Y1742362D01*
G01Y1739606D02*
Y1739213D01*
G01Y1733307D02*
Y1732913D01*
G01Y1736457D02*
Y1736063D01*
G01Y1730157D02*
Y1729764D01*
G01Y1727008D02*
Y1726614D01*
G01X48989Y1734783D02*
Y1735965D01*
G01Y1755453D02*
Y1756634D01*
G01X50720Y1754072D02*
Y1753088D01*
G01Y1750923D02*
Y1749939D01*
G01Y1747773D02*
Y1746789D01*
G01Y1744624D02*
Y1743639D01*
G01Y1738324D02*
Y1737340D01*
G01Y1741474D02*
Y1740490D01*
G01X50987Y1728012D02*
Y1728406D01*
G01Y1733012D02*
Y1733406D01*
G01Y1758012D02*
Y1758406D01*
G01Y1763012D02*
Y1763406D01*
G01Y1768012D02*
Y1768406D01*
G01Y1773012D02*
Y1773406D01*
G01Y1778012D02*
Y1778406D01*
G01Y1783012D02*
Y1783406D01*
G01X50720Y1753088D02*
Y1753050D01*
X50718Y1753013D01*
X50715Y1752980D01*
X50711Y1752949D01*
X50706Y1752925D01*
X50700Y1752907D01*
X50694Y1752895D01*
X50687Y1752891D01*
G01X50720Y1749939D02*
Y1749900D01*
X50718Y1749864D01*
X50715Y1749830D01*
X50711Y1749800D01*
X50706Y1749775D01*
X50700Y1749757D01*
X50694Y1749746D01*
X50687Y1749742D01*
G01X50720Y1746789D02*
Y1746751D01*
X50718Y1746714D01*
X50715Y1746680D01*
X50711Y1746650D01*
X50706Y1746626D01*
X50700Y1746607D01*
X50694Y1746596D01*
X50687Y1746592D01*
G01X50720Y1743639D02*
Y1743601D01*
X50718Y1743565D01*
X50715Y1743531D01*
X50711Y1743500D01*
X50706Y1743476D01*
X50700Y1743458D01*
X50694Y1743446D01*
X50687Y1743443D01*
G01X50720Y1740490D02*
Y1740452D01*
X50718Y1740415D01*
X50715Y1740381D01*
X50711Y1740351D01*
X50706Y1740326D01*
X50700Y1740308D01*
X50694Y1740297D01*
X50687Y1740293D01*
G01X50720Y1737340D02*
Y1737302D01*
X50718Y1737265D01*
X50715Y1737231D01*
X50711Y1737201D01*
X50706Y1737177D01*
X50700Y1737159D01*
X50694Y1737147D01*
X50687Y1737143D01*
G01X50987Y1728406D02*
X50909Y1728996D01*
G01X50987Y1733406D02*
X50909Y1733996D01*
G01X50987Y1758406D02*
X50909Y1758996D01*
G01X50987Y1763406D02*
X50909Y1763996D01*
G01X50987Y1768406D02*
X50909Y1768996D01*
G01X50987Y1773406D02*
X50909Y1773996D01*
G01X50987Y1778406D02*
X50909Y1778996D01*
G01X50987Y1783406D02*
X50909Y1783996D01*
G01X46496Y1737340D02*
X46530Y1737241D01*
X46618Y1737170D01*
X46744Y1737143D01*
G01X46496Y1740490D02*
X46530Y1740391D01*
X46618Y1740320D01*
X46744Y1740293D01*
G01X46496Y1743639D02*
X46530Y1743541D01*
X46618Y1743470D01*
X46744Y1743443D01*
G01X46496Y1746789D02*
X46530Y1746690D01*
X46618Y1746619D01*
X46744Y1746592D01*
G01X46496Y1749939D02*
X46530Y1749840D01*
X46618Y1749769D01*
X46744Y1749742D01*
G01X46496Y1753088D02*
X46530Y1752989D01*
X46618Y1752919D01*
X46744Y1752891D01*
G01X46506Y1726614D02*
X46538Y1726517D01*
X46626Y1726445D01*
X46753Y1726417D01*
G01X46506Y1729764D02*
X46538Y1729667D01*
X46626Y1729594D01*
X46753Y1729567D01*
G01X46506Y1732913D02*
X46538Y1732816D01*
X46626Y1732744D01*
X46753Y1732717D01*
G01X46506Y1736063D02*
X46538Y1735966D01*
X46626Y1735894D01*
X46753Y1735866D01*
G01X46506Y1739213D02*
X46538Y1739115D01*
X46626Y1739043D01*
X46753Y1739016D01*
G01X46506Y1742362D02*
X46538Y1742265D01*
X46626Y1742193D01*
X46753Y1742165D01*
G01X46506Y1745512D02*
X46538Y1745415D01*
X46626Y1745343D01*
X46753Y1745315D01*
G01X46506Y1748661D02*
X46538Y1748564D01*
X46626Y1748492D01*
X46753Y1748465D01*
G01X46506Y1751811D02*
X46538Y1751714D01*
X46626Y1751642D01*
X46753Y1751614D01*
G01X46506Y1754961D02*
X46538Y1754863D01*
X46626Y1754791D01*
X46753Y1754764D01*
G01X46506Y1758110D02*
X46538Y1758013D01*
X46626Y1757941D01*
X46753Y1757913D01*
G01X46506Y1761260D02*
X46538Y1761163D01*
X46626Y1761091D01*
X46753Y1761063D01*
G01X46506Y1764409D02*
X46538Y1764312D01*
X46626Y1764240D01*
X46753Y1764213D01*
G01X46506Y1767559D02*
X46538Y1767462D01*
X46626Y1767390D01*
X46753Y1767362D01*
G01X46506Y1770709D02*
X46538Y1770611D01*
X46626Y1770539D01*
X46753Y1770512D01*
G01X46506Y1773858D02*
X46538Y1773761D01*
X46626Y1773689D01*
X46753Y1773661D01*
G01X46506Y1777008D02*
X46538Y1776911D01*
X46626Y1776839D01*
X46753Y1776811D01*
G01X46506Y1780157D02*
X46538Y1780060D01*
X46626Y1779988D01*
X46753Y1779961D01*
G01X46506Y1783307D02*
X46538Y1783210D01*
X46626Y1783138D01*
X46753Y1783110D01*
G01X46369Y1728012D02*
X46506Y1727814D01*
X46644Y1727617D01*
X46784Y1727421D01*
G01X46369Y1763012D02*
X46506Y1762814D01*
X46644Y1762617D01*
X46784Y1762421D01*
G01X46369Y1768012D02*
X46506Y1767814D01*
X46644Y1767617D01*
X46784Y1767421D01*
G01X46369Y1773012D02*
X46506Y1772814D01*
X46644Y1772617D01*
X46784Y1772421D01*
G01X46369Y1778012D02*
X46506Y1777814D01*
X46644Y1777617D01*
X46784Y1777421D01*
G01X46369Y1783012D02*
X46506Y1782814D01*
X46644Y1782617D01*
X46784Y1782421D01*
G01X46279Y1733012D02*
X46413Y1732814D01*
X46548Y1732617D01*
X46684Y1732421D01*
G01X46279Y1758012D02*
X46413Y1757814D01*
X46548Y1757617D01*
X46684Y1757421D01*
G01X44488Y1755472D02*
X42520Y1757441D01*
G01X50687Y1738521D02*
X50694Y1738518D01*
X50700Y1738506D01*
X50706Y1738489D01*
X50711Y1738464D01*
X50715Y1738434D01*
X50718Y1738400D01*
X50720Y1738363D01*
Y1738324D01*
G01X50687Y1741671D02*
X50694Y1741667D01*
X50700Y1741656D01*
X50706Y1741638D01*
X50711Y1741613D01*
X50715Y1741583D01*
X50718Y1741550D01*
X50720Y1741513D01*
Y1741474D01*
G01X50687Y1744820D02*
X50694Y1744817D01*
X50700Y1744806D01*
X50706Y1744788D01*
X50711Y1744763D01*
X50715Y1744733D01*
X50718Y1744699D01*
X50720Y1744663D01*
Y1744624D01*
G01X50687Y1747970D02*
X50694Y1747967D01*
X50700Y1747955D01*
X50706Y1747937D01*
X50711Y1747913D01*
X50715Y1747883D01*
X50718Y1747849D01*
X50720Y1747812D01*
Y1747773D01*
G01X50687Y1751120D02*
X50694Y1751116D01*
X50700Y1751105D01*
X50706Y1751087D01*
X50711Y1751062D01*
X50715Y1751032D01*
X50718Y1750998D01*
X50720Y1750962D01*
Y1750923D01*
G01X50687Y1754269D02*
X50694Y1754266D01*
X50700Y1754254D01*
X50706Y1754237D01*
X50711Y1754212D01*
X50715Y1754182D01*
X50718Y1754148D01*
X50720Y1754111D01*
Y1754072D01*
G01X46753Y1726417D02*
X52838D01*
G01X53118Y1726614D02*
X46506D01*
G01Y1727008D02*
X53118D01*
G01X46753Y1727205D02*
X52838D01*
G01X46784Y1727421D02*
X52529D01*
G01X46369Y1728012D02*
X52956D01*
G01Y1728406D02*
X46369D01*
G01X52529Y1728996D02*
X46784D01*
G01X43531Y1729508D02*
X62992D01*
G01X46753Y1729567D02*
X52838D01*
G01X53118Y1729764D02*
X46506D01*
G01Y1730157D02*
X53118D01*
G01X46753Y1730354D02*
X52838D01*
G01X52597Y1732421D02*
X46684D01*
G01X46753Y1732717D02*
X52838D01*
G01X53118Y1732913D02*
X46506D01*
G01X46279Y1733012D02*
X53021D01*
G01X46506Y1733307D02*
X53118D01*
G01X53021Y1733406D02*
X46279D01*
G01X46753Y1733504D02*
X52838D01*
G01X71181Y1733602D02*
X44488D01*
G01X52597Y1733996D02*
X46684D01*
G01X48989Y1734783D02*
X42520D01*
G01X46753Y1735866D02*
X52838D01*
G01X62992Y1735945D02*
X44488D01*
G01X48989Y1735965D02*
X71181D01*
G01X53118Y1736063D02*
X46506D01*
G01Y1736457D02*
X53118D01*
G01X46753Y1736654D02*
X52838D01*
G01X52552Y1737143D02*
X46744D01*
G01X46496Y1737340D02*
X52814D01*
G01Y1738324D02*
X46496D01*
G01X52552Y1738521D02*
X46744D01*
G01X46753Y1739016D02*
X52838D01*
G01X53118Y1739213D02*
X46506D01*
G01Y1739606D02*
X53118D01*
G01X46753Y1739803D02*
X52838D01*
G01X52552Y1740293D02*
X46744D01*
G01X46496Y1740490D02*
X52814D01*
G01Y1741474D02*
X46496D01*
G01X52552Y1741671D02*
X46744D01*
G01X46753Y1742165D02*
X52838D01*
G01X53118Y1742362D02*
X46506D01*
G01Y1742756D02*
X53118D01*
G01X46753Y1742953D02*
X52838D01*
G01X52552Y1743443D02*
X46744D01*
G01X46496Y1743639D02*
X52814D01*
G01Y1744624D02*
X46496D01*
G01X52552Y1744820D02*
X46744D01*
G01X46753Y1745315D02*
X52838D01*
G01X53118Y1745512D02*
X46506D01*
G01Y1745906D02*
X53118D01*
G01X46753Y1746102D02*
X52838D01*
G01X52552Y1746592D02*
X46744D01*
G01X46496Y1746789D02*
X52814D01*
G01Y1747773D02*
X46496D01*
G01X52552Y1747970D02*
X46744D01*
G01X46753Y1748465D02*
X52838D01*
G01X53118Y1748661D02*
X46506D01*
G01Y1749055D02*
X53118D01*
G01X46753Y1749252D02*
X52838D01*
G01X52552Y1749742D02*
X46744D01*
G01X46496Y1749939D02*
X52814D01*
G01Y1750923D02*
X46496D01*
G01X52552Y1751120D02*
X46744D01*
G01X46753Y1751614D02*
X52838D01*
G01X53118Y1751811D02*
X46506D01*
G01Y1752205D02*
X53118D01*
G01X46753Y1752402D02*
X52838D01*
G01X52552Y1752891D02*
X46744D01*
G01X46496Y1753088D02*
X52814D01*
G01Y1754072D02*
X46496D01*
G01X52552Y1754269D02*
X46744D01*
G01X46753Y1754764D02*
X52838D01*
G01X53118Y1754961D02*
X46506D01*
G01Y1755354D02*
X53118D01*
G01X71181Y1755453D02*
X48989D01*
G01X62992Y1755472D02*
X44488D01*
G01X46753Y1755551D02*
X52838D01*
G01X42520Y1756634D02*
X48989D01*
G01X52597Y1757421D02*
X46684D01*
G01X44488Y1757815D02*
X71181D01*
G01X46753Y1757913D02*
X52838D01*
G01X46279Y1758012D02*
X53021D01*
G01X53118Y1758110D02*
X46506D01*
G01X53021Y1758406D02*
X46279D01*
G01X46506Y1758504D02*
X53118D01*
G01X46753Y1758701D02*
X52838D01*
G01X52597Y1758996D02*
X46684D01*
G01X46753Y1761063D02*
X52838D01*
G01X53118Y1761260D02*
X46506D01*
G01Y1761654D02*
X53118D01*
G01X62992Y1761811D02*
X43531D01*
G01X46753Y1761850D02*
X52838D01*
G01X46784Y1762421D02*
X52529D01*
G01X46369Y1763012D02*
X52956D01*
G01Y1763406D02*
X46369D01*
G01X52529Y1763996D02*
X46784D01*
G01X46753Y1764213D02*
X52838D01*
G01X53118Y1764409D02*
X46506D01*
G01Y1764803D02*
X53118D01*
G01X46753Y1765000D02*
X52838D01*
G01X46753Y1767362D02*
X52838D01*
G01X46784Y1767421D02*
X52529D01*
G01X53118Y1767559D02*
X46506D01*
G01Y1767953D02*
X53118D01*
G01X46369Y1768012D02*
X52956D01*
G01X46753Y1768150D02*
X52838D01*
G01X52956Y1768406D02*
X46369D01*
G01X52529Y1768996D02*
X46784D01*
G01X46753Y1770512D02*
X52838D01*
G01X53118Y1770709D02*
X46506D01*
G01Y1771102D02*
X53118D01*
G01X46753Y1771299D02*
X52838D01*
G01X46753Y1727205D02*
X46626Y1727177D01*
X46537Y1727104D01*
X46506Y1727008D01*
G01X46753Y1730354D02*
X46626Y1730326D01*
X46537Y1730254D01*
X46506Y1730157D01*
G01X46753Y1733504D02*
X46626Y1733476D01*
X46537Y1733403D01*
X46506Y1733307D01*
G01X46753Y1736654D02*
X46626Y1736626D01*
X46537Y1736553D01*
X46506Y1736457D01*
G01X46753Y1739803D02*
X46626Y1739775D01*
X46537Y1739702D01*
X46506Y1739606D01*
G01X46753Y1742953D02*
X46626Y1742925D01*
X46537Y1742852D01*
X46506Y1742756D01*
G01X46753Y1746102D02*
X46626Y1746074D01*
X46537Y1746002D01*
X46506Y1745906D01*
G01X46753Y1749252D02*
X46626Y1749224D01*
X46537Y1749151D01*
X46506Y1749055D01*
G01X46753Y1752402D02*
X46626Y1752374D01*
X46537Y1752301D01*
X46506Y1752205D01*
G01X46753Y1755551D02*
X46626Y1755523D01*
X46537Y1755450D01*
X46506Y1755354D01*
G01X46753Y1758701D02*
X46626Y1758673D01*
X46537Y1758600D01*
X46506Y1758504D01*
G01X46753Y1761850D02*
X46626Y1761822D01*
X46537Y1761750D01*
X46506Y1761654D01*
G01X46753Y1765000D02*
X46626Y1764972D01*
X46537Y1764899D01*
X46506Y1764803D01*
G01X46744Y1738521D02*
X46617Y1738494D01*
X46528Y1738421D01*
X46496Y1738324D01*
G01X46744Y1741671D02*
X46617Y1741644D01*
X46528Y1741571D01*
X46496Y1741474D01*
G01X46744Y1744820D02*
X46617Y1744793D01*
X46528Y1744720D01*
X46496Y1744624D01*
G01X46744Y1747970D02*
X46617Y1747943D01*
X46528Y1747870D01*
X46496Y1747773D01*
G01X46744Y1751120D02*
X46617Y1751093D01*
X46528Y1751020D01*
X46496Y1750923D01*
G01X46744Y1754269D02*
X46617Y1754242D01*
X46528Y1754169D01*
X46496Y1754072D01*
G01X46784Y1772421D02*
X52529D01*
G01X46369Y1773012D02*
X52956D01*
G01X71181Y1773051D02*
X44488D01*
G01X52956Y1773406D02*
X46369D01*
G01X46753Y1773661D02*
X52838D01*
G01X53118Y1773858D02*
X46506D01*
G01X52529Y1773996D02*
X46784D01*
G01X46506Y1774252D02*
X53118D01*
G01X46753Y1774449D02*
X52838D01*
G01X44488Y1775413D02*
X71181D01*
G01X46753Y1776811D02*
X52838D01*
G01X53118Y1777008D02*
X46506D01*
G01Y1777402D02*
X53118D01*
G01X46784Y1777421D02*
X52529D01*
G01X46753Y1777598D02*
X52838D01*
G01X46369Y1778012D02*
X52956D01*
G01Y1778406D02*
X46369D01*
G01X52529Y1778996D02*
X46784D01*
G01X46753Y1779961D02*
X52838D01*
G01X53118Y1780157D02*
X46506D01*
G01Y1780551D02*
X53118D01*
G01X46753Y1780748D02*
X52838D01*
G01X46784Y1782421D02*
X52529D01*
G01X46369Y1783012D02*
X52956D01*
G01X46753Y1783110D02*
X52838D01*
G01X53118Y1783307D02*
X46506D01*
G01X52956Y1783406D02*
X46369D01*
G01X46506Y1783701D02*
X53118D01*
G01X46753Y1783898D02*
X52838D01*
G01X52529Y1783996D02*
X46784D01*
G01X46753Y1768150D02*
X46626Y1768122D01*
X46537Y1768049D01*
X46506Y1767953D01*
G01X46753Y1771299D02*
X46626Y1771271D01*
X46537Y1771198D01*
X46506Y1771102D01*
G01X46753Y1774449D02*
X46626Y1774421D01*
X46537Y1774348D01*
X46506Y1774252D01*
G01X46753Y1777598D02*
X46626Y1777570D01*
X46537Y1777498D01*
X46506Y1777402D01*
G01X46753Y1780748D02*
X46626Y1780720D01*
X46537Y1780647D01*
X46506Y1780551D01*
G01X46753Y1783898D02*
X46626Y1783870D01*
X46537Y1783797D01*
X46506Y1783701D01*
G01X46784Y1723996D02*
X46644Y1723800D01*
X46506Y1723603D01*
X46369Y1723406D01*
G01X50987Y1723012D02*
X50909Y1722421D01*
G01X46369Y1723012D02*
Y1723406D01*
G01X46506Y1723858D02*
Y1723465D01*
G01X50987Y1723012D02*
Y1723406D01*
G01D02*
X50909Y1723996D01*
G01X46506Y1723465D02*
X46538Y1723367D01*
X46626Y1723295D01*
X46753Y1723268D01*
G01X46369Y1723012D02*
X46506Y1722814D01*
X46644Y1722617D01*
X46784Y1722421D01*
G01D02*
X52529D01*
G01X46369Y1723012D02*
X52956D01*
G01X46753Y1723268D02*
X52838D01*
G01X52956Y1723406D02*
X46369D01*
G01X53118Y1723465D02*
X46506D01*
G01Y1723858D02*
X53118D01*
G01X52529Y1723996D02*
X46784D01*
G01X46753Y1724055D02*
X52838D01*
G01X46753D02*
X46626Y1724027D01*
X46537Y1723954D01*
X46506Y1723858D01*
G01X80249Y1803259D02*
X79888Y1803022D01*
X79650Y1802672D01*
X79565Y1802269D01*
X79647Y1801867D01*
X79883Y1801515D01*
X80247Y1801274D01*
X80672Y1801189D01*
G01X80323Y1800467D02*
X80040Y1800289D01*
X79853Y1800024D01*
X79786Y1799722D01*
X79850Y1799421D01*
X80036Y1799154D01*
X80321Y1798973D01*
X80672Y1798907D01*
G01X76133Y1799148D02*
X75846Y1798970D01*
X75492Y1798907D01*
G01X79474Y1800818D02*
X79151Y1800399D01*
X78989Y1799915D01*
X79010Y1799411D01*
X79213Y1798934D01*
X79580Y1798530D01*
X80086Y1798263D01*
X80678Y1798169D01*
X81267Y1798266D01*
X81769Y1798535D01*
X82133Y1798939D01*
X82334Y1799417D01*
X82354Y1799922D01*
X82190Y1800403D01*
X81869Y1800818D01*
G01X76428Y1801809D02*
X74865Y1800281D01*
G01X81869Y1800818D02*
X82321Y1801258D01*
X82591Y1801794D01*
X82661Y1802365D01*
X82520Y1802929D01*
X82173Y1803453D01*
X81646Y1803846D01*
X81003Y1804050D01*
X80324Y1804047D01*
X79684Y1803839D01*
X79161Y1803443D01*
X78820Y1802920D01*
X78681Y1802359D01*
X78753Y1801791D01*
X79024Y1801257D01*
G01X87037Y1800818D02*
X87488Y1801258D01*
X87759Y1801794D01*
X87829Y1802365D01*
X87687Y1802929D01*
X87341Y1803453D01*
X86813Y1803846D01*
X86170Y1804050D01*
X85491Y1804047D01*
X84851Y1803839D01*
X84328Y1803443D01*
X83987Y1802920D01*
X83849Y1802359D01*
X83920Y1801791D01*
X84191Y1801257D01*
G01X75922Y1802353D02*
X74294Y1800806D01*
G01X81094Y1801274D02*
X81455Y1801509D01*
X81693Y1801860D01*
X81779Y1802263D01*
X81696Y1802665D01*
X81460Y1803018D01*
X81096Y1803258D01*
X80672Y1803343D01*
G01X85416Y1803259D02*
X85056Y1803022D01*
X84817Y1802672D01*
X84732Y1802269D01*
X84814Y1801867D01*
X85051Y1801515D01*
X85414Y1801274D01*
X85839Y1801189D01*
G01X86262Y1801274D02*
X86622Y1801509D01*
X86861Y1801860D01*
X86946Y1802263D01*
X86864Y1802665D01*
X86627Y1803018D01*
X86264Y1803258D01*
X85839Y1803343D01*
G01X81020Y1798972D02*
X81303Y1799150D01*
X81490Y1799415D01*
X81557Y1799717D01*
X81493Y1800017D01*
X81307Y1800284D01*
X81022Y1800466D01*
X80672Y1800531D01*
G01X85490Y1800467D02*
X85207Y1800289D01*
X85020Y1800024D01*
X84953Y1799722D01*
X85018Y1799421D01*
X85203Y1799154D01*
X85489Y1798973D01*
X85839Y1798907D01*
G01X86188Y1798972D02*
X86470Y1799150D01*
X86657Y1799415D01*
X86724Y1799717D01*
X86660Y1800017D01*
X86475Y1800284D01*
X86189Y1800466D01*
X85839Y1800531D01*
G01X74865Y1800281D02*
X74682Y1800016D01*
X74619Y1799718D01*
X74683Y1799420D01*
G01X76133Y1799148D02*
X76323Y1799415D01*
G01X74294Y1800806D02*
X73956Y1800344D01*
X73811Y1799826D01*
X73871Y1799308D01*
X74122Y1798824D01*
X74559Y1798430D01*
X75132Y1798206D01*
X75767Y1798187D01*
X76351Y1798374D01*
X76806Y1798726D01*
X77098Y1799198D01*
X77202Y1799719D01*
G01X84641Y1800818D02*
X84319Y1800399D01*
X84156Y1799915D01*
X84178Y1799411D01*
X84381Y1798934D01*
X84748Y1798530D01*
X85254Y1798263D01*
X85845Y1798169D01*
X86434Y1798266D01*
X86936Y1798535D01*
X87300Y1798939D01*
X87502Y1799417D01*
X87521Y1799922D01*
X87357Y1800403D01*
X87037Y1800818D01*
G01X77202Y1799719D02*
X77115Y1799243D01*
X76868Y1798800D01*
X76480Y1798448D01*
X75973Y1798229D01*
X75395Y1798172D01*
X74832Y1798294D01*
X74356Y1798577D01*
X74017Y1798981D01*
X73837Y1799438D01*
X73822Y1799919D01*
X73979Y1800389D01*
X74294Y1800806D01*
G01X76323Y1799415D02*
X76390Y1799719D01*
G01X66929Y1805295D02*
Y1796949D01*
G01X68565Y1798833D02*
Y1798169D01*
G01X70044Y1813110D02*
Y1811535D01*
G01X70079D02*
Y1813110D01*
G01X70103Y1811535D02*
Y1813110D01*
G01X70866Y1803327D02*
Y1799547D01*
G01Y1795138D02*
Y1797579D01*
G01X71426Y1813110D02*
Y1811535D01*
G01X71796D02*
Y1813110D01*
G01X72404Y1798169D02*
Y1798907D01*
G01X73585Y1804075D02*
Y1803337D01*
G01X73873Y1813110D02*
Y1811535D01*
G01X74243D02*
Y1813110D01*
G01X75567D02*
Y1811535D01*
G01X75591Y1813110D02*
Y1811535D01*
G01X75625D02*
Y1813110D01*
G01X76390Y1799867D02*
Y1799719D01*
G01X76772Y1794646D02*
Y1796949D01*
G01X77202Y1799719D02*
Y1799867D01*
G01X77497Y1803632D02*
Y1804075D01*
G01X79328Y1794587D02*
Y1794646D01*
G01X79967Y1796949D02*
Y1794193D01*
G01X81024Y1818228D02*
Y1805295D01*
G01X87841Y1796949D02*
Y1794193D01*
G01X89013Y1798833D02*
Y1798169D01*
G01X92852D02*
Y1798907D01*
G01X79583Y1794193D02*
X79328Y1794587D01*
G01X81869Y1800818D02*
X82192Y1800399D01*
X82355Y1799915D01*
X82333Y1799411D01*
X82130Y1798934D01*
X81763Y1798530D01*
X81257Y1798263D01*
X80666Y1798169D01*
X80077Y1798266D01*
X79574Y1798535D01*
X79210Y1798939D01*
X79009Y1799417D01*
X78989Y1799922D01*
X79154Y1800403D01*
X79474Y1800818D01*
G01X87037D02*
X87359Y1800399D01*
X87522Y1799915D01*
X87500Y1799411D01*
X87297Y1798934D01*
X86930Y1798530D01*
X86424Y1798263D01*
X85833Y1798169D01*
X85244Y1798266D01*
X84742Y1798535D01*
X84377Y1798939D01*
X84176Y1799417D01*
X84157Y1799922D01*
X84321Y1800403D01*
X84641Y1800818D01*
G01X74866Y1799157D02*
X74683Y1799422D01*
X74619Y1799721D01*
X74683Y1800017D01*
G01X79474Y1800818D02*
X79022Y1801258D01*
X78752Y1801794D01*
X78682Y1802365D01*
X78824Y1802929D01*
X79170Y1803453D01*
X79698Y1803846D01*
X80340Y1804050D01*
X81019Y1804047D01*
X81659Y1803839D01*
X82182Y1803443D01*
X82524Y1802920D01*
X82662Y1802359D01*
X82590Y1801791D01*
X82320Y1801257D01*
G01X84641Y1800818D02*
X84189Y1801258D01*
X83919Y1801794D01*
X83849Y1802365D01*
X83991Y1802929D01*
X84337Y1803453D01*
X84865Y1803846D01*
X85507Y1804050D01*
X86187Y1804047D01*
X86827Y1803839D01*
X87350Y1803443D01*
X87691Y1802920D01*
X87829Y1802359D01*
X87757Y1801791D01*
X87487Y1801257D01*
G01X80323Y1798972D02*
X80040Y1799150D01*
X79853Y1799415D01*
X79786Y1799717D01*
X79850Y1800017D01*
X80036Y1800284D01*
X80321Y1800466D01*
X80672Y1800531D01*
G01X81020Y1800467D02*
X81303Y1800289D01*
X81490Y1800024D01*
X81557Y1799722D01*
X81493Y1799421D01*
X81307Y1799154D01*
X81022Y1798973D01*
X80672Y1798907D01*
G01X85490Y1798972D02*
X85207Y1799150D01*
X85020Y1799415D01*
X84953Y1799717D01*
X85018Y1800017D01*
X85203Y1800284D01*
X85489Y1800466D01*
X85839Y1800531D01*
G01X86188Y1800467D02*
X86470Y1800289D01*
X86657Y1800024D01*
X86724Y1799722D01*
X86660Y1799421D01*
X86475Y1799154D01*
X86189Y1798973D01*
X85839Y1798907D01*
G01X75145Y1798976D02*
X74865Y1799157D01*
G01X80249Y1801274D02*
X79888Y1801509D01*
X79650Y1801860D01*
X79565Y1802263D01*
X79647Y1802665D01*
X79883Y1803018D01*
X80247Y1803258D01*
X80672Y1803343D01*
G01X81094Y1803259D02*
X81455Y1803022D01*
X81693Y1802672D01*
X81779Y1802269D01*
X81696Y1801867D01*
X81460Y1801515D01*
X81096Y1801274D01*
X80672Y1801189D01*
G01X85416Y1801274D02*
X85056Y1801509D01*
X84817Y1801860D01*
X84732Y1802263D01*
X84814Y1802665D01*
X85051Y1803018D01*
X85414Y1803258D01*
X85839Y1803343D01*
G01X86262Y1803259D02*
X86622Y1803022D01*
X86861Y1802672D01*
X86946Y1802269D01*
X86864Y1801867D01*
X86627Y1801515D01*
X86264Y1801274D01*
X85839Y1801189D01*
G01X75492Y1798907D02*
X75144Y1798977D01*
G01X93696Y1794193D02*
X73228D01*
G01X79328Y1794587D02*
X73228D01*
G01X79328Y1794646D02*
X73228D01*
G01X70866Y1795138D02*
X94488D01*
G01Y1797579D02*
X70866D01*
G01X68565Y1798169D02*
X72404D01*
G01X89013D02*
X92852D01*
G01Y1798907D02*
X89899D01*
G01X72404D02*
X69451D01*
G01X70866Y1799547D02*
X94488D01*
G01X77202Y1799867D02*
X76390D01*
G01X94488Y1803327D02*
X70866D01*
G01X73585Y1803337D02*
X76464D01*
G01X92113Y1804075D02*
X91228D01*
G01X77497D02*
X73585D01*
G01X71666D02*
X70780D01*
G01X81024Y1808051D02*
X64646D01*
G01X75000Y1810748D02*
X70669D01*
G01X75625Y1811535D02*
X70044D01*
G01Y1813110D02*
X75625D01*
G01X70669Y1813898D02*
X75000D01*
G01X81024Y1818228D02*
X64646D01*
G01X68565Y1798833D02*
G03X70780Y1804075I-7142J6107D01*
G01X69451Y1798907D02*
G03X71666Y1804075I-6937J6032D01*
G01X70669Y1813898D02*
G03Y1810748I0J-1575D01*
G01X89013Y1798833D02*
G03X91228Y1804075I-7142J6107D01*
G01X89899Y1798907D02*
G03X92113Y1804075I-6938J6030D01*
G01X86614Y1800512D02*
G03I-4528J0D01*
G01X76428Y1801809D02*
G03X77498Y1803632I-2809J2875D01*
G01X85591Y1800512D02*
G03I-3505J0D01*
G01X85433D02*
G03I-3347J0D01*
G01X84252D02*
G03I-2166J0D01*
G01X75922Y1802353D02*
G03X76464Y1803337I-1276J1344D01*
G01X75000Y1810748D02*
G03Y1813898I0J1575D01*
G01X44488Y1796949D02*
X42520Y1794980D01*
G01X40519Y1805264D02*
X40462Y1805124D01*
X40457Y1804884D01*
G01X40519Y1805264D02*
X40463Y1805130D01*
X40456Y1804894D01*
X40493Y1804565D01*
G01X40551Y1804114D02*
Y1796949D01*
G01X40492Y1804573D02*
X40547Y1804188D01*
G01X42520Y1796949D02*
X39236D01*
G01X44488D02*
X94488D01*
G01X66929Y1804114D02*
X40551D01*
G01Y1805295D02*
X94488D01*
G01X69602Y1829164D02*
X69696Y1829276D01*
G01Y1829148D02*
X69602Y1829037D01*
G01X68110Y1832579D02*
Y1830610D01*
G01Y1828051D02*
Y1830020D01*
G01X69602Y1829037D02*
Y1829164D01*
G01X69685Y1832874D02*
Y1832283D01*
G01Y1831102D02*
Y1829528D01*
G01Y1828346D02*
Y1827756D01*
G01X69696Y1828528D02*
Y1829148D01*
G01X69789Y1829276D02*
Y1828528D01*
G01X70669Y1827756D02*
Y1832874D01*
G01X70866D02*
Y1827756D01*
G01X71260Y1830020D02*
Y1828051D01*
G01Y1830610D02*
Y1832579D01*
G01X74409Y1830020D02*
Y1828051D01*
G01Y1830610D02*
Y1832579D01*
G01X74803Y1832874D02*
Y1827756D01*
G01X75000D02*
Y1832874D01*
G01X75984Y1827756D02*
Y1828346D01*
G01Y1829528D02*
Y1831102D01*
G01Y1832283D02*
Y1832874D01*
G01X77559Y1832579D02*
Y1830610D01*
G01Y1828051D02*
Y1830020D01*
G01X69685Y1827756D02*
X75984D01*
G01X71260Y1828051D02*
X68110D01*
G01X74409D02*
X77559D01*
G01X69789Y1828528D02*
X69696D01*
G01Y1829276D02*
X69789D01*
G01X77559Y1830020D02*
X74409D01*
G01X68110D02*
X71260D01*
G01X77559Y1830610D02*
X74409D01*
G01X68110D02*
X71260D01*
G01Y1832579D02*
X68110D01*
G01X74409D02*
X77559D01*
G01X75984Y1832874D02*
X69685D01*
G01Y1831102D02*
G03Y1832283I0J591D01*
G01Y1828346D02*
G03Y1829528I0J591D01*
G01X75984Y1832283D02*
G03Y1831102I0J-591D01*
G01Y1829528D02*
G03Y1828346I0J-591D01*
G01X176314Y-172119D02*
Y-191056D01*
G01X141738Y17712D02*
G03X125990I-7874J0D01*
G01X147643D02*
G03X120084I-13780J0D01*
G01X149612D02*
G03X118116I-15748J0D01*
G01X149612D02*
G03X118116I-15748J0D01*
G01X129828Y26406D02*
G03I-984J0D01*
G01X139868D02*
G03I-985J0D01*
G01X139769Y17712D02*
G03X127958I-5906J0D01*
G01X124809D02*
G03I-985J0D01*
G01X126154Y22731D02*
G03I-985J0D01*
G01X127958Y15349D02*
Y17712D01*
G01X125990D02*
Y15349D01*
G01X120084D02*
X127958D01*
G01X143542Y22731D02*
G03I-984J0D01*
G01X144887Y17712D02*
G03I-984J0D01*
G01X118116Y3932D02*
Y17712D01*
G01Y3932D02*
G03X149612I15748J0D01*
G01X141738Y15349D02*
Y17712D01*
G01X139769D02*
Y15349D01*
G01D02*
X147643D01*
G01D02*
Y17712D01*
G01X149612Y3932D02*
Y17712D01*
G01X120084D02*
Y15349D01*
G01X203543Y186831D02*
X149606D01*
G01X173228Y188799D02*
X149606D01*
G01X173228Y192579D02*
X149606D01*
G01Y200512D02*
Y186831D01*
G01X177165Y188012D02*
X203543D01*
G01X172428Y188051D02*
X173314D01*
G01X172298Y180591D02*
Y179016D01*
G01X172669D02*
Y180591D01*
G01X173228Y192579D02*
Y188799D01*
G01X173991Y180591D02*
Y179016D01*
G01X174016Y180591D02*
Y179016D01*
G01X174050D02*
Y180591D01*
G01X177165Y186831D02*
Y195177D01*
G01X179449Y173898D02*
Y200295D01*
G01X175529Y193292D02*
G03X173314Y188051I7141J-6107D01*
G01X174643Y193219D02*
G03X172428Y188051I6937J-6032D01*
G01X173425Y178228D02*
G03Y181378I0J1575D01*
G01X172835Y159547D02*
X175984D01*
G01Y161516D02*
X172835D01*
G01X175984Y162106D02*
X172835D01*
G01Y164075D02*
X175984D01*
G01X172835Y161516D02*
Y159547D01*
G01Y162106D02*
Y164075D01*
G01X173228Y164370D02*
Y159252D01*
G01X173425D02*
Y164370D01*
G01X174409Y159252D02*
Y159843D01*
G01Y163780D02*
Y164370D01*
G01Y161024D02*
Y162598D01*
G01X175984Y164075D02*
Y162106D01*
G01Y159547D02*
Y161516D01*
G01X174409Y163780D02*
G03Y162598I0J-591D01*
G01Y161024D02*
G03Y159843I0J-591D01*
G01X157906Y191659D02*
X157624Y191837D01*
X157437Y192102D01*
X157370Y192404D01*
X157434Y192704D01*
X157619Y192971D01*
X157905Y193153D01*
X158255Y193219D01*
G01X158604Y193154D02*
X158887Y192976D01*
X159074Y192711D01*
X159141Y192409D01*
X159076Y192108D01*
X158891Y191841D01*
X158606Y191660D01*
X158255Y191594D01*
G01X163074Y191659D02*
X162791Y191837D01*
X162604Y192102D01*
X162537Y192404D01*
X162601Y192704D01*
X162787Y192971D01*
X163072Y193153D01*
X163422Y193219D01*
G01X163772Y193154D02*
X164054Y192976D01*
X164241Y192711D01*
X164308Y192409D01*
X164244Y192108D01*
X164058Y191841D01*
X163773Y191660D01*
X163422Y191594D01*
G01X168949Y193149D02*
X169229Y192968D01*
G01X157832Y188867D02*
X157472Y189103D01*
X157233Y189453D01*
X157148Y189857D01*
X157231Y190259D01*
X157467Y190611D01*
X157830Y190851D01*
X158255Y190936D01*
G01X158678Y190852D02*
X159039Y190616D01*
X159277Y190266D01*
X159363Y189862D01*
X159280Y189460D01*
X159043Y189108D01*
X158680Y188868D01*
X158255Y188783D01*
G01X163000Y188867D02*
X162639Y189103D01*
X162401Y189453D01*
X162315Y189857D01*
X162398Y190259D01*
X162634Y190611D01*
X162998Y190851D01*
X163422Y190936D01*
G01X163846Y190852D02*
X164206Y190616D01*
X164444Y190266D01*
X164530Y189862D01*
X164447Y189460D01*
X164211Y189108D01*
X163847Y188868D01*
X163422Y188783D01*
G01X179449Y173898D02*
X163071D01*
G01X173425Y178228D02*
X169094D01*
G01X174050Y179016D02*
X168469D01*
G01Y180591D02*
X174050D01*
G01X169094Y181378D02*
X173425D01*
G01X179449Y184075D02*
X163071D01*
G01X151981Y188051D02*
X152867D01*
G01X166597D02*
X170509D01*
G01Y188789D02*
X167630D01*
G01X166892Y192259D02*
X167704D01*
G01X159453Y191307D02*
X159905Y190867D01*
X160175Y190331D01*
X160245Y189761D01*
X160104Y189197D01*
X159757Y188672D01*
X159230Y188279D01*
X158587Y188076D01*
X157907Y188078D01*
X157267Y188286D01*
X156744Y188683D01*
X156403Y189206D01*
X156265Y189767D01*
X156337Y190335D01*
X156607Y190869D01*
G01X164620Y191307D02*
X165072Y190867D01*
X165342Y190331D01*
X165413Y189761D01*
X165271Y189197D01*
X164924Y188672D01*
X164397Y188279D01*
X163754Y188076D01*
X163075Y188078D01*
X162435Y188286D01*
X161912Y188683D01*
X161570Y189206D01*
X161432Y189767D01*
X161504Y190335D01*
X161774Y190869D01*
G01X157057Y191307D02*
X156735Y191727D01*
X156572Y192210D01*
X156594Y192715D01*
X156797Y193192D01*
X157164Y193595D01*
X157670Y193863D01*
X158261Y193957D01*
X158850Y193859D01*
X159353Y193591D01*
X159717Y193187D01*
X159918Y192709D01*
X159937Y192204D01*
X159774Y191723D01*
X159453Y191307D01*
G01X162225D02*
X161902Y191727D01*
X161739Y192210D01*
X161761Y192715D01*
X161964Y193192D01*
X162331Y193595D01*
X162837Y193863D01*
X163428Y193957D01*
X164018Y193859D01*
X164520Y193591D01*
X164884Y193187D01*
X165085Y192709D01*
X165105Y192204D01*
X164941Y191723D01*
X164620Y191307D01*
G01X169229Y192969D02*
X169411Y192704D01*
X169476Y192405D01*
X169411Y192108D01*
G01X163071Y186831D02*
Y173898D01*
G01X166597Y188494D02*
Y188051D01*
G01X166892Y192406D02*
Y192259D01*
G01X167704D02*
Y192406D01*
G01X168469Y180591D02*
Y179016D01*
G01X168504D02*
Y180591D01*
G01X168528Y179016D02*
Y180591D01*
G01X169851D02*
Y179016D01*
G01X170221D02*
Y180591D01*
G01X170509Y188051D02*
Y188789D01*
G01X166892Y192406D02*
X166979Y192883D01*
X167226Y193326D01*
X167615Y193677D01*
X168121Y193897D01*
X168699Y193954D01*
X169263Y193831D01*
X169739Y193549D01*
X170078Y193144D01*
X170257Y192687D01*
X170272Y192207D01*
X170115Y191737D01*
X169801Y191320D01*
G01X167772Y192711D02*
X167704Y192406D01*
G01X169229Y191844D02*
X169412Y192110D01*
X169476Y192407D01*
X169411Y192705D01*
G01X167961Y192978D02*
X167771Y192710D01*
G01X169801Y191320D02*
X170138Y191781D01*
X170283Y192300D01*
X170223Y192818D01*
X169972Y193301D01*
X169535Y193696D01*
X168962Y193919D01*
X168328Y193938D01*
X167743Y193752D01*
X167288Y193399D01*
X166996Y192927D01*
X166892Y192406D01*
G01X159453Y191307D02*
X159776Y191727D01*
X159938Y192210D01*
X159917Y192715D01*
X159713Y193192D01*
X159347Y193595D01*
X158841Y193863D01*
X158250Y193957D01*
X157660Y193859D01*
X157158Y193591D01*
X156794Y193187D01*
X156593Y192709D01*
X156573Y192204D01*
X156737Y191723D01*
X157057Y191307D01*
G01X164620D02*
X164943Y191727D01*
X165106Y192210D01*
X165084Y192715D01*
X164881Y193192D01*
X164514Y193595D01*
X164008Y193863D01*
X163417Y193957D01*
X162828Y193859D01*
X162325Y193591D01*
X161961Y193187D01*
X161760Y192709D01*
X161741Y192204D01*
X161904Y191723D01*
X162225Y191307D01*
G01X169229Y191844D02*
X167667Y190317D01*
G01X157057Y191307D02*
X156606Y190867D01*
X156336Y190331D01*
X156265Y189761D01*
X156407Y189197D01*
X156754Y188672D01*
X157281Y188279D01*
X157924Y188076D01*
X158603Y188078D01*
X159243Y188286D01*
X159766Y188683D01*
X160107Y189206D01*
X160245Y189767D01*
X160174Y190335D01*
X159904Y190869D01*
G01X162225Y191307D02*
X161773Y190867D01*
X161503Y190331D01*
X161433Y189761D01*
X161574Y189197D01*
X161921Y188672D01*
X162448Y188279D01*
X163091Y188076D01*
X163770Y188078D01*
X164411Y188286D01*
X164933Y188683D01*
X165275Y189206D01*
X165413Y189767D01*
X165341Y190335D01*
X165071Y190869D01*
G01X169801Y191320D02*
X168172Y189773D01*
G01X157832Y190852D02*
X157472Y190616D01*
X157233Y190266D01*
X157148Y189862D01*
X157231Y189460D01*
X157467Y189108D01*
X157830Y188868D01*
X158255Y188783D01*
G01X158678Y188867D02*
X159039Y189103D01*
X159277Y189453D01*
X159363Y189857D01*
X159280Y190259D01*
X159043Y190611D01*
X158680Y190851D01*
X158255Y190936D01*
G01X163000Y190852D02*
X162639Y190616D01*
X162401Y190266D01*
X162315Y189862D01*
X162398Y189460D01*
X162634Y189108D01*
X162998Y188868D01*
X163422Y188783D01*
G01X163846Y188867D02*
X164206Y189103D01*
X164444Y189453D01*
X164530Y189857D01*
X164447Y190259D01*
X164211Y190611D01*
X163847Y190851D01*
X163422Y190936D01*
G01X157906Y193154D02*
X157624Y192976D01*
X157437Y192711D01*
X157370Y192409D01*
X157434Y192108D01*
X157619Y191841D01*
X157905Y191660D01*
X158255Y191594D01*
G01X158604Y191659D02*
X158887Y191837D01*
X159074Y192102D01*
X159141Y192404D01*
X159076Y192704D01*
X158891Y192971D01*
X158606Y193153D01*
X158255Y193219D01*
G01X163074Y193154D02*
X162791Y192976D01*
X162604Y192711D01*
X162537Y192409D01*
X162601Y192108D01*
X162787Y191841D01*
X163072Y191660D01*
X163422Y191594D01*
G01X163772Y191659D02*
X164054Y191837D01*
X164241Y192102D01*
X164308Y192404D01*
X164244Y192704D01*
X164058Y192971D01*
X163773Y193153D01*
X163422Y193219D01*
G01X167961Y192978D02*
X168248Y193156D01*
X168602Y193218D01*
G01X155081Y193292D02*
G03X152866Y188051I7141J-6107D01*
G01X154195Y193219D02*
G03X151981Y188051I6938J-6031D01*
G01X166535Y191614D02*
G03I-4527J0D01*
G01X167667Y190317D02*
G03X166597Y188494I2809J-2874D01*
G01X165512Y191614D02*
G03I-3504J0D01*
G01X165354D02*
G03I-3346J0D01*
G01X164173D02*
G03I-2165J0D01*
G01X168172Y189773D02*
G03X167630Y188789I1276J-1344D01*
G01X169094Y181378D02*
G03Y178228I0J-1575D01*
G01X168110Y159252D02*
X174409D01*
G01X169685Y159547D02*
X166535D01*
G01X168215Y160024D02*
X168121D01*
G01Y160772D02*
X168215D01*
G01X166535Y161516D02*
X169685D01*
G01X166535Y162106D02*
X169685D01*
G01Y164075D02*
X166535D01*
G01X174409Y164370D02*
X168110D01*
G01X166535Y164075D02*
Y162106D01*
G01Y159547D02*
Y161516D01*
G01X168028Y160533D02*
Y160660D01*
G01X168110Y164370D02*
Y163780D01*
G01Y162598D02*
Y161024D01*
G01Y159843D02*
Y159252D01*
G01X168121Y160024D02*
Y160644D01*
G01X168215Y160772D02*
Y160024D01*
G01X169094Y159252D02*
Y164370D01*
G01X169291D02*
Y159252D01*
G01X169685Y161516D02*
Y159547D01*
G01Y162106D02*
Y164075D01*
G01X168028Y160660D02*
X168121Y160772D01*
G01Y160644D02*
X168028Y160533D01*
G01X168110Y162598D02*
G03Y163780I0J591D01*
G01Y159843D02*
G03Y161024I0J591D01*
G01X200563Y230315D02*
X181102D01*
G01X199606Y234311D02*
X172913D01*
G01X199606Y236654D02*
X181102D01*
G01X195106Y236673D02*
X172913D01*
G01X195106Y256161D02*
X172913D01*
G01X181102Y256181D02*
X199606D01*
G01Y258524D02*
X172913D01*
G01X200563Y262618D02*
X181102D01*
G01X174882Y256161D02*
Y236673D01*
G01Y258524D02*
Y274862D01*
G01X167323Y225295D02*
X166339D01*
G01X167323Y225492D02*
X166339D01*
G01X151378Y227126D02*
X158710D01*
G01X158857D02*
X170866D01*
G01X167323Y227343D02*
X166339D01*
G01X167323Y227539D02*
X166339D01*
G01X170866Y227913D02*
X158857D01*
G01X158710D02*
X151378D01*
G01X167323Y227933D02*
X166339D01*
G01X162205Y228130D02*
X169370D01*
G01X162205Y229705D02*
X169370D01*
G01X167323Y229902D02*
X166339D01*
G01X151378Y230276D02*
X158710D01*
G01X158857D02*
X170866D01*
G01X167323Y230295D02*
X166339D01*
G01X167323Y230492D02*
X166339D01*
G01X170866Y231063D02*
X158857D01*
G01X158710D02*
X151378D01*
G01X167323Y232343D02*
X166339D01*
G01X167323Y232539D02*
X166339D01*
G01X167323Y232933D02*
X166339D01*
G01X162205Y233130D02*
X169370D01*
G01X151378Y233425D02*
X158710D01*
G01X158857D02*
X170866D01*
G01Y234213D02*
X158857D01*
G01X158710D02*
X151378D01*
G01X162205Y234705D02*
X169370D01*
G01X167323Y234902D02*
X166339D01*
G01X167323Y235295D02*
X166339D01*
G01X167323Y235492D02*
X166339D01*
G01X151378Y236575D02*
X158710D01*
G01X158857D02*
X170866D01*
G01Y236654D02*
X169764D01*
G01X163331Y236772D02*
X170866D01*
G01X167872Y237264D02*
X165748D01*
G01X170866Y237362D02*
X158857D01*
G01X158710D02*
X151378D01*
G01X168857Y237559D02*
X167872D01*
G01X168857Y237756D02*
X167872D01*
G01X169764Y237953D02*
X163739D01*
G01X169764Y239134D02*
X163739D01*
G01X168857Y239331D02*
X167872D01*
G01X168857Y239528D02*
X167872D01*
G01X151378Y239724D02*
X158710D01*
G01X158857D02*
X170866D01*
G01Y240512D02*
X158857D01*
G01X158710D02*
X151378D01*
G01X161874Y240591D02*
X163757D01*
G01X168857Y240709D02*
X167872D01*
G01X168857Y240906D02*
X167872D01*
G01X169764Y241102D02*
X163739D01*
G01X169764Y242283D02*
X163739D01*
G01X168857Y242480D02*
X167872D01*
G01X168857Y242677D02*
X167872D01*
G01X163757Y242795D02*
X161874D01*
G01X151378Y242874D02*
X158710D01*
G01X158857D02*
X170866D01*
G01Y243661D02*
X158857D01*
G01X158710D02*
X151378D01*
G01X168857Y243858D02*
X167872D01*
G01X168857Y244055D02*
X167872D01*
G01X169764Y244252D02*
X163739D01*
G01X169764Y245433D02*
X163739D01*
G01X168857Y245630D02*
X167872D01*
G01X168857Y245827D02*
X167872D01*
G01X151378Y246024D02*
X158710D01*
G01X158857D02*
X170866D01*
G01Y246811D02*
X158857D01*
G01X158710D02*
X151378D01*
G01X168857Y247008D02*
X167872D01*
G01X168857Y247205D02*
X167872D01*
G01X169764Y247402D02*
X163739D01*
G01X169764Y248583D02*
X163739D01*
G01X168857Y248780D02*
X167872D01*
G01X168857Y248976D02*
X167872D01*
G01X151378Y249173D02*
X158710D01*
G01X158857D02*
X170866D01*
G01Y249961D02*
X158857D01*
G01X158710D02*
X151378D01*
G01X161874Y250039D02*
X163757D01*
G01X168857Y250157D02*
X167872D01*
G01X168857Y250354D02*
X167872D01*
G01X169764Y250551D02*
X163739D01*
G01X169764Y251732D02*
X163739D01*
G01X168857Y251929D02*
X167872D01*
G01X168857Y252126D02*
X167872D01*
G01X163757Y252244D02*
X161874D01*
G01X151378Y252323D02*
X158710D01*
G01X158857D02*
X170866D01*
G01Y253110D02*
X158857D01*
G01X158710D02*
X151378D01*
G01X168857Y253307D02*
X167872D01*
G01X168857Y253504D02*
X167872D01*
G01X169764Y253701D02*
X163739D01*
G01X169764Y254882D02*
X163739D01*
G01X168857Y255079D02*
X167872D01*
G01X168857Y255276D02*
X167872D01*
G01X151378Y255472D02*
X158710D01*
G01X158857D02*
X170866D01*
G01X167872Y255571D02*
X165748D01*
G01X170866Y256063D02*
X163331D01*
G01X170866Y256181D02*
X169764D01*
G01X170866Y256260D02*
X158857D01*
G01X158710D02*
X151378D01*
G01X167323Y257343D02*
X166339D01*
G01X167323Y257539D02*
X166339D01*
G01X167323Y257933D02*
X166339D01*
G01X162205Y258130D02*
X169370D01*
G01X151378Y258622D02*
X158710D01*
G01X158857D02*
X170866D01*
G01Y259409D02*
X158857D01*
G01X158710D02*
X151378D01*
G01X162205Y259705D02*
X169370D01*
G01X167323Y259902D02*
X166339D01*
G01X167323Y260295D02*
X166339D01*
G01X167323Y260492D02*
X166339D01*
G01X151378Y261772D02*
X158710D01*
G01X158857D02*
X170866D01*
G01X167323Y262343D02*
X166339D01*
G01X167323Y262539D02*
X166339D01*
G01X170866Y262559D02*
X158857D01*
G01X158710D02*
X151378D01*
G01X167323Y262933D02*
X166339D01*
G01X162205Y263130D02*
X169370D01*
G01X162205Y264705D02*
X169370D01*
G01X167323Y264902D02*
X166339D01*
G01X151378Y264921D02*
X158710D01*
G01X158857D02*
X170866D01*
G01X151378Y227126D02*
Y227913D01*
G01Y233425D02*
Y234213D01*
G01Y230276D02*
Y231063D01*
G01Y236575D02*
Y237362D01*
G01Y242874D02*
Y243661D01*
G01Y239724D02*
Y240512D01*
G01Y246024D02*
Y246811D01*
G01Y252323D02*
Y253110D01*
G01Y249173D02*
Y249961D01*
G01Y255472D02*
Y256260D01*
G01Y261772D02*
Y262559D01*
G01Y258622D02*
Y259409D01*
G01Y264921D02*
Y265709D01*
G01X153151Y227126D02*
Y227913D01*
G01Y233425D02*
Y234213D01*
G01Y230276D02*
Y231063D01*
G01Y236575D02*
Y237362D01*
G01Y242874D02*
Y243661D01*
G01Y239724D02*
Y240512D01*
G01Y246024D02*
Y246811D01*
G01Y252323D02*
Y253110D01*
G01Y249173D02*
Y249961D01*
G01Y255472D02*
Y256260D01*
G01Y261772D02*
Y262559D01*
G01Y258622D02*
Y259409D01*
G01Y264921D02*
Y265709D01*
G01X153340D02*
Y264921D01*
G01Y262559D02*
Y261772D01*
G01Y259409D02*
Y258622D01*
G01Y256260D02*
Y255472D01*
G01Y253110D02*
Y252323D01*
G01Y249961D02*
Y249173D01*
G01Y246811D02*
Y246024D01*
G01Y243661D02*
Y242874D01*
G01Y240512D02*
Y239724D01*
G01Y237362D02*
Y236575D01*
G01Y234213D02*
Y233425D01*
G01Y231063D02*
Y230276D01*
G01Y227913D02*
Y227126D01*
G01X156176Y265709D02*
Y264921D01*
G01Y262559D02*
Y261772D01*
G01Y259409D02*
Y258622D01*
G01Y256260D02*
Y255472D01*
G01Y253110D02*
Y252323D01*
G01Y249961D02*
Y249173D01*
G01Y246811D02*
Y246024D01*
G01Y243661D02*
Y242874D01*
G01Y240512D02*
Y239724D01*
G01Y237362D02*
Y236575D01*
G01Y234213D02*
Y233425D01*
G01Y231063D02*
Y230276D01*
G01Y227913D02*
Y227126D01*
G01X157118D02*
Y227913D01*
G01Y233425D02*
Y234213D01*
G01Y230276D02*
Y231063D01*
G01Y236575D02*
Y237362D01*
G01Y242874D02*
Y243661D01*
G01Y239724D02*
Y240512D01*
G01Y246024D02*
Y246811D01*
G01Y252323D02*
Y253110D01*
G01Y249173D02*
Y249961D01*
G01Y255472D02*
Y256260D01*
G01Y261772D02*
Y262559D01*
G01Y258622D02*
Y259409D01*
G01Y264921D02*
Y265709D01*
G01X158710Y227126D02*
Y227913D01*
G01Y233425D02*
Y234213D01*
G01Y230276D02*
Y231063D01*
G01Y236575D02*
Y237362D01*
G01Y242874D02*
Y243661D01*
G01Y239724D02*
Y240512D01*
G01Y246024D02*
Y246811D01*
G01Y252323D02*
Y253110D01*
G01Y249173D02*
Y249961D01*
G01Y255472D02*
Y256260D01*
G01Y261772D02*
Y262559D01*
G01Y258622D02*
Y259409D01*
G01Y264921D02*
Y265709D01*
G01X158857Y227126D02*
Y227913D01*
G01Y233425D02*
Y234213D01*
G01Y230276D02*
Y231063D01*
G01Y236575D02*
Y237362D01*
G01Y242874D02*
Y243661D01*
G01Y239724D02*
Y240512D01*
G01Y246024D02*
Y246811D01*
G01Y252323D02*
Y253110D01*
G01Y249173D02*
Y249961D01*
G01Y255472D02*
Y256260D01*
G01Y261772D02*
Y262559D01*
G01Y258622D02*
Y259409D01*
G01Y264921D02*
Y265709D01*
G01X159796Y264921D02*
Y262559D01*
G01Y261772D02*
Y259409D01*
G01Y258622D02*
Y256260D01*
G01Y255472D02*
Y253110D01*
G01Y252323D02*
Y249961D01*
G01Y249173D02*
Y246811D01*
G01Y246024D02*
Y243661D01*
G01Y242874D02*
Y240512D01*
G01Y239724D02*
Y237362D01*
G01Y236575D02*
Y234213D01*
G01Y233425D02*
Y231063D01*
G01Y230276D02*
Y227913D01*
G01X161524Y227126D02*
Y227913D01*
G01Y233425D02*
Y234213D01*
G01Y230276D02*
Y231063D01*
G01Y236575D02*
Y237362D01*
G01Y242874D02*
Y243661D01*
G01Y239724D02*
Y240512D01*
G01Y246024D02*
Y246811D01*
G01Y252323D02*
Y253110D01*
G01Y249173D02*
Y249961D01*
G01Y255472D02*
Y256260D01*
G01Y261772D02*
Y262559D01*
G01Y258622D02*
Y259409D01*
G01Y264921D02*
Y265709D01*
G01X161874Y240591D02*
Y242795D01*
G01Y250039D02*
Y252244D01*
G01X162205Y264705D02*
Y263130D01*
G01Y259705D02*
Y258130D01*
G01Y234705D02*
Y233130D01*
G01Y229705D02*
Y228130D01*
G01X163176Y265709D02*
Y264921D01*
G01Y262559D02*
Y261772D01*
G01Y259409D02*
Y258622D01*
G01Y256260D02*
Y255472D01*
G01Y253110D02*
Y252323D01*
G01Y249961D02*
Y249173D01*
G01Y246811D02*
Y246024D01*
G01Y243661D02*
Y242874D01*
G01Y240512D02*
Y239724D01*
G01Y237362D02*
Y236575D01*
G01Y234213D02*
Y233425D01*
G01Y231063D02*
Y230276D01*
G01Y227913D02*
Y227126D01*
G01X163331Y236772D02*
Y240591D01*
G01Y242795D02*
Y250039D01*
G01Y252244D02*
Y256063D01*
G01X163739Y254882D02*
Y253701D01*
G01Y251732D02*
Y250551D01*
G01Y248583D02*
Y247402D01*
G01Y245433D02*
Y244252D01*
G01Y242283D02*
Y241102D01*
G01Y239134D02*
Y237953D01*
G01X163757Y252244D02*
Y250039D01*
G01Y242795D02*
Y240591D01*
G01X163809Y236772D02*
Y256063D01*
G01X165159Y265709D02*
Y264921D01*
G01Y262559D02*
Y261772D01*
G01Y259409D02*
Y258622D01*
G01Y256260D02*
Y255472D01*
G01Y253110D02*
Y252323D01*
G01Y249961D02*
Y249173D01*
G01Y246811D02*
Y246024D01*
G01Y243661D02*
Y242874D01*
G01Y240512D02*
Y239724D01*
G01Y237362D02*
Y236575D01*
G01Y234213D02*
Y233425D01*
G01Y231063D02*
Y230276D01*
G01Y227913D02*
Y227126D01*
G01X165354Y264705D02*
Y263130D01*
G01Y259705D02*
Y258130D01*
G01Y234705D02*
Y233130D01*
G01Y229705D02*
Y228130D01*
G01X166339Y265492D02*
Y262343D01*
G01Y260492D02*
Y257343D01*
G01Y235492D02*
Y232343D01*
G01Y230492D02*
Y227343D01*
G01X166888Y254882D02*
Y253701D01*
G01Y251732D02*
Y250551D01*
G01Y248583D02*
Y247402D01*
G01Y245433D02*
Y244252D01*
G01Y242283D02*
Y241102D01*
G01Y239134D02*
Y237953D01*
G01X167165Y236772D02*
Y256063D01*
G01X167323Y265492D02*
Y262343D01*
G01Y260492D02*
Y257343D01*
G01Y235492D02*
Y232343D01*
G01Y230492D02*
Y227343D01*
G01X167872Y237264D02*
Y255571D01*
G01X168082Y256063D02*
Y236772D01*
G01X168307Y264705D02*
Y263130D01*
G01Y259705D02*
Y258130D01*
G01Y234705D02*
Y233130D01*
G01Y229705D02*
Y228130D01*
G01X168521Y227126D02*
Y227913D01*
G01Y233425D02*
Y234213D01*
G01Y230276D02*
Y231063D01*
G01Y236575D02*
Y237362D01*
G01Y242874D02*
Y243661D01*
G01Y239724D02*
Y240512D01*
G01Y246024D02*
Y246811D01*
G01Y252323D02*
Y253110D01*
G01Y249173D02*
Y249961D01*
G01Y255472D02*
Y256260D01*
G01Y261772D02*
Y262559D01*
G01Y258622D02*
Y259409D01*
G01Y264921D02*
Y265709D01*
G01X168583Y256063D02*
Y236772D01*
G01X168857Y255472D02*
Y253110D01*
G01Y252323D02*
Y249961D01*
G01Y249173D02*
Y246811D01*
G01Y246024D02*
Y243661D01*
G01Y242874D02*
Y240512D01*
G01Y239724D02*
Y237362D01*
G01X168898Y227126D02*
Y227913D01*
G01Y233425D02*
Y234213D01*
G01Y230276D02*
Y231063D01*
G01Y236575D02*
Y237362D01*
G01Y242874D02*
Y243661D01*
G01Y239724D02*
Y240512D01*
G01Y246024D02*
Y246811D01*
G01Y252323D02*
Y253110D01*
G01Y249173D02*
Y249961D01*
G01Y255472D02*
Y256260D01*
G01Y261772D02*
Y262559D01*
G01Y258622D02*
Y259409D01*
G01Y264921D02*
Y265709D01*
G01X168924Y227126D02*
Y227913D01*
G01Y233425D02*
Y234213D01*
G01Y230276D02*
Y231063D01*
G01Y236575D02*
Y237362D01*
G01Y242874D02*
Y243661D01*
G01Y239724D02*
Y240512D01*
G01Y246024D02*
Y246811D01*
G01Y252323D02*
Y253110D01*
G01Y249173D02*
Y249961D01*
G01Y255472D02*
Y256260D01*
G01Y261772D02*
Y262559D01*
G01Y258622D02*
Y259409D01*
G01Y264921D02*
Y265709D01*
G01X169370Y236772D02*
Y256063D01*
G01X169685D02*
Y236772D01*
G01X169764Y227736D02*
G03X169370Y228130I-394J0D01*
G01Y229705D02*
G03X169764Y230098I0J394D01*
G01Y232736D02*
G03X169370Y233130I-394J0D01*
G01Y234705D02*
G03X169764Y235098I0J394D01*
G01Y257736D02*
G03X169370Y258130I-394J0D01*
G01Y259705D02*
G03X169764Y260098I0J394D01*
G01Y262736D02*
G03X169370Y263130I-394J0D01*
G01Y264705D02*
G03X169764Y265098I0J394D01*
G01X167323Y265295D02*
X166339D01*
G01X167323Y265492D02*
X166339D01*
G01X170866Y265709D02*
X158857D01*
G01X158710D02*
X151378D01*
G01X159796Y268071D02*
Y265709D01*
G01X149606Y194547D02*
X173228D01*
G01X199606Y195177D02*
X149606D01*
G01X173228Y196988D02*
X149606D01*
G01X150399Y197933D02*
X170866D01*
G01X169764Y200512D02*
X149606D01*
G01X149924D02*
Y195177D01*
G01X150399Y200512D02*
Y197933D01*
G01X172441Y201758D02*
X172789Y201673D01*
G01X172876Y202185D02*
X172615Y202270D01*
G01X175315Y204403D02*
X174967Y204573D01*
G01X174880Y204061D02*
X175141Y203891D01*
G01X171690Y193219D02*
X174643D01*
G01X175529Y193957D02*
X171690D01*
G01X199606Y200098D02*
X181102D01*
G01X179449Y200295D02*
X172913D01*
G01X172789Y201673D02*
X173137D01*
G01X173050Y202185D02*
X172876D01*
G01X174618Y204061D02*
X174880D01*
G01X174967Y204573D02*
X174531D01*
G01X173137Y205256D02*
X172441D01*
G01X175925Y205768D02*
X172528D01*
G01X171831Y206280D02*
X175925D01*
G01X199606Y216713D02*
X172913D01*
G01X199606Y219075D02*
X172913D01*
G01X172441Y205256D02*
X171831Y205768D01*
G01X172528D02*
X173137Y205256D01*
G01X172092Y202100D02*
X172441Y201758D01*
G01X175664Y204061D02*
X175315Y204403D01*
G01X174793Y201417D02*
X175141Y201502D01*
G01X173137Y201673D02*
X173486Y201758D01*
G01X172615Y202270D02*
X172441Y202526D01*
G01X175141Y203891D02*
X175315Y203635D01*
G01X171918Y202441D02*
X172092Y202100D01*
G01X175838Y203720D02*
X175664Y204061D01*
G01X172441Y202526D02*
X172353Y202782D01*
G01X171831D02*
X171918Y202441D01*
G01X175315Y203635D02*
X175402Y203294D01*
G01X175925D02*
X175838Y203720D01*
G01X171690Y193957D02*
Y193219D01*
G01X171831Y203209D02*
Y202782D01*
G01Y205768D02*
Y206280D01*
G01X172353Y202782D02*
Y203294D01*
G01X172789Y203806D02*
Y204317D01*
G01X172913Y200295D02*
Y332539D01*
G01X173228Y196988D02*
Y194547D01*
G01X173573Y203294D02*
Y202782D01*
G01X174096D02*
Y203294D01*
G01X174793Y201929D02*
Y201417D01*
G01X174882Y234311D02*
Y219075D01*
G01Y216713D02*
Y200295D01*
G01X175402Y203294D02*
Y202611D01*
G01X175529Y193292D02*
Y193957D01*
G01X175925Y206280D02*
Y205768D01*
G01Y202611D02*
Y203294D01*
G01X179134Y200886D02*
Y199114D01*
G01X181102Y332736D02*
Y200098D01*
G01X171918Y203635D02*
X171831Y203209D01*
G01X173660Y203720D02*
X173573Y203294D01*
G01X175838Y202185D02*
X175925Y202611D01*
G01X174096Y203294D02*
X174183Y203635D01*
G01X174009Y202441D02*
X174096Y202782D01*
G01X175402Y202611D02*
X175315Y202270D01*
G01X172353Y203294D02*
X172441Y203550D01*
G01X173573Y202782D02*
X173486Y202526D01*
G01X173834Y204061D02*
X173660Y203720D01*
G01X173834Y202100D02*
X174009Y202441D01*
G01X175577Y201758D02*
X175838Y202185D01*
G01X174183Y203635D02*
X174357Y203891D01*
G01X173486Y202526D02*
X173311Y202270D01*
G01X172179Y203976D02*
X171918Y203635D01*
G01X172441Y203550D02*
X172615Y203720D01*
G01X174183Y204403D02*
X173834Y204061D01*
G01X173486Y201758D02*
X173834Y202100D01*
G01X175315Y202270D02*
X175054Y202014D01*
G01X172528Y204232D02*
X172179Y203976D01*
G01X174357Y203891D02*
X174618Y204061D01*
G01X175141Y201502D02*
X175577Y201758D01*
G01X172615Y203720D02*
X172789Y203806D01*
G01X174531Y204573D02*
X174183Y204403D01*
G01X172789Y204317D02*
X172528Y204232D01*
G01X173311Y202270D02*
X173050Y202185D01*
G01X175054Y202014D02*
X174793Y201929D01*
G01X168602Y193218D02*
X168950Y193149D01*
G01X151243Y193219D02*
X154195D01*
G01X155081Y193957D02*
X151243D01*
G01X170866Y197480D02*
X164766D01*
G01Y197539D02*
X170866D01*
G01X169764Y199114D02*
X179134D01*
G01X170866Y199705D02*
X201575D01*
G01X169764Y200886D02*
X179134D01*
G01X167323Y202343D02*
X166339D01*
G01X165748Y202500D02*
X156763D01*
G01X167323Y202539D02*
X166339D01*
G01X167323Y202933D02*
X166339D01*
G01X161240Y202953D02*
X169311D01*
G01X162205Y203130D02*
X169370D01*
G01X162205Y204705D02*
X169370D01*
G01X167323Y204902D02*
X166339D01*
G01X169311Y204921D02*
X161240D01*
G01X151378Y205079D02*
X158710D01*
G01X158857D02*
X170866D01*
G01X167323Y205295D02*
X166339D01*
G01X167323Y205492D02*
X166339D01*
G01X170866Y205866D02*
X158857D01*
G01X158710D02*
X151378D01*
G01X167323Y207343D02*
X166339D01*
G01X167323Y207539D02*
X166339D01*
G01X167323Y207933D02*
X166339D01*
G01X162205Y208130D02*
X169370D01*
G01X151378Y208228D02*
X158710D01*
G01X158857D02*
X170866D01*
G01Y209016D02*
X158857D01*
G01X158710D02*
X151378D01*
G01X162205Y209705D02*
X169370D01*
G01X167323Y209902D02*
X166339D01*
G01X167323Y210295D02*
X166339D01*
G01X167323Y210492D02*
X166339D01*
G01X151378Y211378D02*
X158710D01*
G01X158857D02*
X170866D01*
G01Y212165D02*
X158857D01*
G01X158710D02*
X151378D01*
G01X167323Y212343D02*
X166339D01*
G01X167323Y212539D02*
X166339D01*
G01X167323Y212933D02*
X166339D01*
G01X162205Y213130D02*
X169370D01*
G01X151378Y214528D02*
X158710D01*
G01X158857D02*
X170866D01*
G01X162205Y214705D02*
X169370D01*
G01X167323Y214902D02*
X166339D01*
G01X167323Y215295D02*
X166339D01*
G01X170866Y215315D02*
X158857D01*
G01X158710D02*
X151378D01*
G01X167323Y215492D02*
X166339D01*
G01X167323Y217343D02*
X166339D01*
G01X167323Y217539D02*
X166339D01*
G01X151378Y217677D02*
X158710D01*
G01X158857D02*
X170866D01*
G01X167323Y217933D02*
X166339D01*
G01X162205Y218130D02*
X169370D01*
G01X170866Y218465D02*
X158857D01*
G01X158710D02*
X151378D01*
G01X162205Y219705D02*
X169370D01*
G01X167323Y219902D02*
X166339D01*
G01X167323Y220295D02*
X166339D01*
G01X167323Y220492D02*
X166339D01*
G01X151378Y220827D02*
X158710D01*
G01X158857D02*
X170866D01*
G01Y221614D02*
X158857D01*
G01X158710D02*
X151378D01*
G01X167323Y222343D02*
X166339D01*
G01X167323Y222539D02*
X166339D01*
G01X167323Y222933D02*
X166339D01*
G01X162205Y223130D02*
X169370D01*
G01X151378Y223976D02*
X158710D01*
G01X158857D02*
X170866D01*
G01X162205Y224705D02*
X169370D01*
G01X170866Y224764D02*
X158857D01*
G01X158710D02*
X151378D01*
G01X167323Y224902D02*
X166339D01*
G01X164511Y197933D02*
X164766Y197539D01*
G01X151243Y193957D02*
Y193219D01*
G01X151378Y205079D02*
Y205866D01*
G01Y208228D02*
Y209016D01*
G01Y214528D02*
Y215315D01*
G01Y211378D02*
Y212165D01*
G01Y217677D02*
Y218465D01*
G01Y223976D02*
Y224764D01*
G01Y220827D02*
Y221614D01*
G01X153151Y205079D02*
Y205866D01*
G01Y208228D02*
Y209016D01*
G01Y214528D02*
Y215315D01*
G01Y211378D02*
Y212165D01*
G01Y217677D02*
Y218465D01*
G01Y223976D02*
Y224764D01*
G01Y220827D02*
Y221614D01*
G01X153340Y224764D02*
Y223976D01*
G01Y221614D02*
Y220827D01*
G01Y218465D02*
Y217677D01*
G01Y215315D02*
Y214528D01*
G01Y212165D02*
Y211378D01*
G01Y209016D02*
Y208228D01*
G01Y205866D02*
Y205079D01*
G01X155081Y193292D02*
Y193957D01*
G01X156176Y224764D02*
Y223976D01*
G01Y221614D02*
Y220827D01*
G01Y218465D02*
Y217677D01*
G01Y215315D02*
Y214528D01*
G01Y212165D02*
Y211378D01*
G01Y209016D02*
Y208228D01*
G01Y205866D02*
Y205079D01*
G01X156253Y195177D02*
Y197933D01*
G01X156763Y334902D02*
Y197933D01*
G01X157118Y205079D02*
Y205866D01*
G01Y208228D02*
Y209016D01*
G01Y214528D02*
Y215315D01*
G01Y211378D02*
Y212165D01*
G01Y217677D02*
Y218465D01*
G01Y223976D02*
Y224764D01*
G01Y220827D02*
Y221614D01*
G01X158710Y205079D02*
Y205866D01*
G01Y208228D02*
Y209016D01*
G01Y214528D02*
Y215315D01*
G01Y211378D02*
Y212165D01*
G01Y217677D02*
Y218465D01*
G01Y223976D02*
Y224764D01*
G01Y220827D02*
Y221614D01*
G01X158857Y205079D02*
Y205866D01*
G01Y208228D02*
Y209016D01*
G01Y214528D02*
Y215315D01*
G01Y211378D02*
Y212165D01*
G01Y217677D02*
Y218465D01*
G01Y223976D02*
Y224764D01*
G01Y220827D02*
Y221614D01*
G01X159796Y227126D02*
Y224764D01*
G01Y223976D02*
Y221614D01*
G01Y220827D02*
Y218465D01*
G01Y217677D02*
Y215315D01*
G01Y214528D02*
Y212165D01*
G01Y211378D02*
Y209016D01*
G01Y208228D02*
Y205866D01*
G01Y205079D02*
Y202500D01*
G01X161240Y204921D02*
Y202953D01*
G01X161524Y205079D02*
Y205866D01*
G01Y208228D02*
Y209016D01*
G01Y214528D02*
Y215315D01*
G01Y211378D02*
Y212165D01*
G01Y217677D02*
Y218465D01*
G01Y223976D02*
Y224764D01*
G01Y220827D02*
Y221614D01*
G01X162205Y224705D02*
Y223130D01*
G01Y219705D02*
Y218130D01*
G01Y214705D02*
Y213130D01*
G01Y209705D02*
Y208130D01*
G01Y204705D02*
Y203130D01*
G01X163176Y224764D02*
Y223976D01*
G01Y221614D02*
Y220827D01*
G01Y218465D02*
Y217677D01*
G01Y215315D02*
Y214528D01*
G01Y212165D02*
Y211378D01*
G01Y209016D02*
Y208228D01*
G01Y205866D02*
Y205079D01*
G01X164127Y195177D02*
Y197933D01*
G01X164766Y197539D02*
Y197480D01*
G01X165159Y224764D02*
Y223976D01*
G01Y221614D02*
Y220827D01*
G01Y218465D02*
Y217677D01*
G01Y215315D02*
Y214528D01*
G01Y212165D02*
Y211378D01*
G01Y209016D02*
Y208228D01*
G01Y205866D02*
Y205079D01*
G01X165293Y200512D02*
Y332126D01*
G01X165354Y224705D02*
Y223130D01*
G01Y219705D02*
Y218130D01*
G01Y214705D02*
Y213130D01*
G01Y209705D02*
Y208130D01*
G01Y204705D02*
Y203130D01*
G01X165748Y197933D02*
Y334902D01*
G01X166339Y225492D02*
Y222343D01*
G01Y220492D02*
Y217343D01*
G01Y215492D02*
Y212343D01*
G01Y210492D02*
Y207343D01*
G01Y205492D02*
Y202343D01*
G01X167323Y225492D02*
Y222343D01*
G01Y220492D02*
Y217343D01*
G01Y215492D02*
Y212343D01*
G01Y210492D02*
Y207343D01*
G01Y205492D02*
Y202343D01*
G01Y197480D02*
Y195177D01*
G01X168307Y224705D02*
Y223130D01*
G01Y219705D02*
Y218130D01*
G01Y214705D02*
Y213130D01*
G01Y209705D02*
Y208130D01*
G01Y204705D02*
Y203130D01*
G01X168521Y205079D02*
Y205866D01*
G01Y208228D02*
Y209016D01*
G01Y214528D02*
Y215315D01*
G01Y211378D02*
Y212165D01*
G01Y217677D02*
Y218465D01*
G01Y223976D02*
Y224764D01*
G01Y220827D02*
Y221614D01*
G01X168898Y205079D02*
Y205866D01*
G01Y208228D02*
Y209016D01*
G01Y214528D02*
Y215315D01*
G01Y211378D02*
Y212165D01*
G01Y217677D02*
Y218465D01*
G01Y223976D02*
Y224764D01*
G01Y220827D02*
Y221614D01*
G01X168924Y205079D02*
Y205866D01*
G01Y208228D02*
Y209016D01*
G01Y214528D02*
Y215315D01*
G01Y211378D02*
Y212165D01*
G01Y217677D02*
Y218465D01*
G01Y223976D02*
Y224764D01*
G01Y220827D02*
Y221614D01*
G01X169311Y202953D02*
Y204921D01*
G01X169764Y197933D02*
Y334902D01*
G01X170866Y335354D02*
Y197480D01*
G01X169764Y207736D02*
G03X169370Y208130I-394J0D01*
G01Y209705D02*
G03X169764Y210098I0J394D01*
G01Y217736D02*
G03X169370Y218130I-394J0D01*
G01Y219705D02*
G03X169764Y220098I0J394D01*
G01Y212736D02*
G03X169370Y213130I-394J0D01*
G01Y214705D02*
G03X169764Y215098I0J394D01*
G01Y222736D02*
G03X169370Y223130I-394J0D01*
G01Y224705D02*
G03X169764Y225098I0J394D01*
G01Y202736D02*
G03X169370Y203130I-394J0D01*
G01Y204705D02*
G03X169764Y205098I0J394D01*
G01X149606Y332126D02*
X169764D01*
G01X150399Y334902D02*
X170866D01*
G01X149606Y335886D02*
X173228D01*
G01X199606Y337657D02*
X149606D01*
G01X173228Y338287D02*
X149606D01*
G01Y346004D02*
Y332126D01*
G01X149924Y337657D02*
Y332126D01*
G01X150399Y334902D02*
Y332126D01*
G01X199606Y293760D02*
X172913D01*
G01X199606Y296122D02*
X172913D01*
G01X199606Y312657D02*
X172913D01*
G01X199606Y315020D02*
X172913D01*
G01X179449Y332539D02*
X172913D01*
G01X199606Y332736D02*
X181102D01*
G01X173228Y338287D02*
Y335886D01*
G01X174882Y296122D02*
Y312657D01*
G01Y315020D02*
Y332539D01*
G01X177165Y346004D02*
Y337657D01*
G01X179134Y333720D02*
Y331949D01*
G01X179449Y332539D02*
Y358937D01*
G01X199606Y274862D02*
X172913D01*
G01X199606Y277224D02*
X172913D01*
G01X174882D02*
Y293760D01*
G01X167323Y285295D02*
X166339D01*
G01X167323Y285492D02*
X166339D01*
G01X151378Y286969D02*
X158710D01*
G01X158857D02*
X170866D01*
G01X167323Y287343D02*
X166339D01*
G01X167323Y287539D02*
X166339D01*
G01X170866Y287756D02*
X158857D01*
G01X158710D02*
X151378D01*
G01X167323Y287933D02*
X166339D01*
G01X162205Y288130D02*
X169370D01*
G01X162205Y289705D02*
X169370D01*
G01X167323Y289902D02*
X166339D01*
G01X151378Y290118D02*
X158710D01*
G01X158857D02*
X170866D01*
G01X167323Y290295D02*
X166339D01*
G01X167323Y290492D02*
X166339D01*
G01X170866Y290906D02*
X158857D01*
G01X158710D02*
X151378D01*
G01X167323Y292343D02*
X166339D01*
G01X167323Y292539D02*
X166339D01*
G01X167323Y292933D02*
X166339D01*
G01X162205Y293130D02*
X169370D01*
G01X151378Y293268D02*
X158710D01*
G01X158857D02*
X170866D01*
G01Y294055D02*
X158857D01*
G01X158710D02*
X151378D01*
G01X162205Y294705D02*
X169370D01*
G01X167323Y294902D02*
X166339D01*
G01X167323Y295295D02*
X166339D01*
G01X167323Y295492D02*
X166339D01*
G01X151378Y296417D02*
X158710D01*
G01X158857D02*
X170866D01*
G01Y297205D02*
X158857D01*
G01X158710D02*
X151378D01*
G01X167323Y297343D02*
X166339D01*
G01X167323Y297539D02*
X166339D01*
G01X167323Y297933D02*
X166339D01*
G01X162205Y298130D02*
X169370D01*
G01X151378Y299567D02*
X158710D01*
G01X158857D02*
X170866D01*
G01X162205Y299705D02*
X169370D01*
G01X167323Y299902D02*
X166339D01*
G01X167323Y300295D02*
X166339D01*
G01X170866Y300354D02*
X158857D01*
G01X158710D02*
X151378D01*
G01X167323Y300492D02*
X166339D01*
G01X167323Y302343D02*
X166339D01*
G01X167323Y302539D02*
X166339D01*
G01X151378Y302717D02*
X158710D01*
G01X158857D02*
X170866D01*
G01X167323Y302933D02*
X166339D01*
G01X162205Y303130D02*
X169370D01*
G01X170866Y303504D02*
X158857D01*
G01X158710D02*
X151378D01*
G01X162205Y304705D02*
X169370D01*
G01X167323Y304902D02*
X166339D01*
G01X167323Y305295D02*
X166339D01*
G01X167323Y305492D02*
X166339D01*
G01X151378Y305866D02*
X158710D01*
G01X158857D02*
X170866D01*
G01Y306654D02*
X158857D01*
G01X158710D02*
X151378D01*
G01X167323Y307343D02*
X166339D01*
G01X167323Y307539D02*
X166339D01*
G01X167323Y307933D02*
X166339D01*
G01X162205Y308130D02*
X169370D01*
G01X151378Y309016D02*
X158710D01*
G01X158857D02*
X170866D01*
G01X162205Y309705D02*
X169370D01*
G01X170866Y309803D02*
X158857D01*
G01X158710D02*
X151378D01*
G01X167323Y309902D02*
X166339D01*
G01X167323Y310295D02*
X166339D01*
G01X167323Y310492D02*
X166339D01*
G01X170866Y311713D02*
X169764D01*
G01X151378Y312165D02*
X158710D01*
G01X158857D02*
X170866D01*
G01X169291Y312343D02*
X168307D01*
G01X169291Y312539D02*
X168307D01*
G01X169291Y312933D02*
X168307D01*
G01X170866Y312953D02*
X158857D01*
G01X158710D02*
X151378D01*
G01X169764Y313130D02*
X164173D01*
G01X169764Y314705D02*
X164173D01*
G01X169291Y314902D02*
X168307D01*
G01X169291Y315295D02*
X168307D01*
G01X151378Y315315D02*
X158710D01*
G01X158857D02*
X170866D01*
G01X169291Y315492D02*
X168307D01*
G01X170866Y316102D02*
X158857D01*
G01X158710D02*
X151378D01*
G01X170866Y316122D02*
X169764D01*
G01X167323Y317343D02*
X166339D01*
G01X167323Y317539D02*
X166339D01*
G01X167323Y317933D02*
X166339D01*
G01X162205Y318130D02*
X169370D01*
G01X151378Y318465D02*
X158710D01*
G01X158857D02*
X170866D01*
G01Y319252D02*
X158857D01*
G01X158710D02*
X151378D01*
G01X162205Y319705D02*
X169370D01*
G01X167323Y319902D02*
X166339D01*
G01X167323Y320295D02*
X166339D01*
G01X167323Y320492D02*
X166339D01*
G01X151378Y321614D02*
X158710D01*
G01X158857D02*
X170866D01*
G01X167323Y322343D02*
X166339D01*
G01X170866Y322402D02*
X158857D01*
G01X158710D02*
X151378D01*
G01X167323Y322539D02*
X166339D01*
G01X167323Y322933D02*
X166339D01*
G01X162205Y323130D02*
X169370D01*
G01X162205Y324705D02*
X169370D01*
G01X151378Y324764D02*
X158710D01*
G01X158857D02*
X170866D01*
G01X167323Y324902D02*
X166339D01*
G01X167323Y325295D02*
X166339D01*
G01X167323Y325492D02*
X166339D01*
G01X170866Y325551D02*
X158857D01*
G01X158710D02*
X151378D01*
G01X167323Y327343D02*
X166339D01*
G01X167323Y327539D02*
X166339D01*
G01X151378Y327913D02*
X158710D01*
G01X158857D02*
X170866D01*
G01X167323Y327933D02*
X166339D01*
G01X162205Y328130D02*
X169370D01*
G01X170866Y328701D02*
X158857D01*
G01X158710D02*
X151378D01*
G01X162205Y329705D02*
X169370D01*
G01X167323Y329902D02*
X166339D01*
G01X167323Y330295D02*
X166339D01*
G01X165748Y330374D02*
X156763D01*
G01X167323Y330492D02*
X166339D01*
G01X169764Y331949D02*
X179134D01*
G01X201575Y333130D02*
X170866D01*
G01X169764Y333720D02*
X179134D01*
G01X164766Y335295D02*
X170866D01*
G01X164766Y335354D02*
X170866D01*
G01X159704Y337323D02*
X164311D01*
G01X163962Y338504D02*
X160054D01*
G01X163962D02*
X163980Y338448D01*
X164032Y338282D01*
X164111Y338024D01*
X164207Y337696D01*
X164311Y337323D01*
G01X151378Y290118D02*
Y290906D01*
G01Y286969D02*
Y287756D01*
G01Y293268D02*
Y294055D01*
G01Y299567D02*
Y300354D01*
G01Y296417D02*
Y297205D01*
G01Y302717D02*
Y303504D01*
G01Y309016D02*
Y309803D01*
G01Y305866D02*
Y306654D01*
G01Y312165D02*
Y312953D01*
G01Y318465D02*
Y319252D01*
G01Y315315D02*
Y316102D01*
G01Y321614D02*
Y322402D01*
G01Y327913D02*
Y328701D01*
G01Y324764D02*
Y325551D01*
G01X153151Y290118D02*
Y290906D01*
G01Y286969D02*
Y287756D01*
G01Y293268D02*
Y294055D01*
G01Y299567D02*
Y300354D01*
G01Y296417D02*
Y297205D01*
G01Y302717D02*
Y303504D01*
G01Y309016D02*
Y309803D01*
G01Y305866D02*
Y306654D01*
G01Y312165D02*
Y312953D01*
G01Y318465D02*
Y319252D01*
G01Y315315D02*
Y316102D01*
G01Y321614D02*
Y322402D01*
G01Y327913D02*
Y328701D01*
G01Y324764D02*
Y325551D01*
G01X153340Y328701D02*
Y327913D01*
G01Y325551D02*
Y324764D01*
G01Y322402D02*
Y321614D01*
G01Y319252D02*
Y318465D01*
G01Y316102D02*
Y315315D01*
G01Y312953D02*
Y312165D01*
G01Y309803D02*
Y309016D01*
G01Y306654D02*
Y305866D01*
G01Y303504D02*
Y302717D01*
G01Y300354D02*
Y299567D01*
G01Y297205D02*
Y296417D01*
G01Y294055D02*
Y293268D01*
G01Y290906D02*
Y290118D01*
G01Y287756D02*
Y286969D01*
G01X156176Y328701D02*
Y327913D01*
G01Y325551D02*
Y324764D01*
G01Y322402D02*
Y321614D01*
G01Y319252D02*
Y318465D01*
G01Y316102D02*
Y315315D01*
G01Y312953D02*
Y312165D01*
G01Y309803D02*
Y309016D01*
G01Y306654D02*
Y305866D01*
G01Y303504D02*
Y302717D01*
G01Y300354D02*
Y299567D01*
G01Y297205D02*
Y296417D01*
G01Y294055D02*
Y293268D01*
G01Y290906D02*
Y290118D01*
G01Y287756D02*
Y286969D01*
G01X156253Y334902D02*
Y337657D01*
G01X157118Y290118D02*
Y290906D01*
G01Y286969D02*
Y287756D01*
G01Y293268D02*
Y294055D01*
G01Y299567D02*
Y300354D01*
G01Y296417D02*
Y297205D01*
G01Y302717D02*
Y303504D01*
G01Y309016D02*
Y309803D01*
G01Y305866D02*
Y306654D01*
G01Y312165D02*
Y312953D01*
G01Y318465D02*
Y319252D01*
G01Y315315D02*
Y316102D01*
G01Y321614D02*
Y322402D01*
G01Y327913D02*
Y328701D01*
G01Y324764D02*
Y325551D01*
G01X158710Y290118D02*
Y290906D01*
G01Y286969D02*
Y287756D01*
G01Y293268D02*
Y294055D01*
G01Y299567D02*
Y300354D01*
G01Y296417D02*
Y297205D01*
G01Y302717D02*
Y303504D01*
G01Y309016D02*
Y309803D01*
G01Y305866D02*
Y306654D01*
G01Y312165D02*
Y312953D01*
G01Y318465D02*
Y319252D01*
G01Y315315D02*
Y316102D01*
G01Y321614D02*
Y322402D01*
G01Y327913D02*
Y328701D01*
G01Y324764D02*
Y325551D01*
G01X158857Y290118D02*
Y290906D01*
G01Y286969D02*
Y287756D01*
G01Y293268D02*
Y294055D01*
G01Y299567D02*
Y300354D01*
G01Y296417D02*
Y297205D01*
G01Y302717D02*
Y303504D01*
G01Y309016D02*
Y309803D01*
G01Y305866D02*
Y306654D01*
G01Y312165D02*
Y312953D01*
G01Y318465D02*
Y319252D01*
G01Y315315D02*
Y316102D01*
G01Y321614D02*
Y322402D01*
G01Y327913D02*
Y328701D01*
G01Y324764D02*
Y325551D01*
G01X159796Y330374D02*
Y328701D01*
G01Y327913D02*
Y325551D01*
G01Y324764D02*
Y322402D01*
G01Y321614D02*
Y319252D01*
G01Y318465D02*
Y316102D01*
G01Y315315D02*
Y312953D01*
G01Y312165D02*
Y309803D01*
G01Y309016D02*
Y306654D01*
G01Y305866D02*
Y303504D01*
G01Y302717D02*
Y300354D01*
G01Y299567D02*
Y297205D01*
G01Y296417D02*
Y294055D01*
G01Y293268D02*
Y290906D01*
G01Y290118D02*
Y287756D01*
G01X161524Y290118D02*
Y290906D01*
G01Y286969D02*
Y287756D01*
G01Y293268D02*
Y294055D01*
G01Y299567D02*
Y300354D01*
G01Y296417D02*
Y297205D01*
G01Y302717D02*
Y303504D01*
G01Y309016D02*
Y309803D01*
G01Y305866D02*
Y306654D01*
G01Y312165D02*
Y312953D01*
G01Y318465D02*
Y319252D01*
G01Y315315D02*
Y316102D01*
G01Y321614D02*
Y322402D01*
G01Y327913D02*
Y328701D01*
G01Y324764D02*
Y325551D01*
G01X162205Y329705D02*
Y328130D01*
G01Y324705D02*
Y323130D01*
G01Y319705D02*
Y318130D01*
G01Y309705D02*
Y308130D01*
G01Y304705D02*
Y303130D01*
G01Y299705D02*
Y298130D01*
G01Y294705D02*
Y293130D01*
G01Y289705D02*
Y288130D01*
G01X163176Y328701D02*
Y327913D01*
G01Y325551D02*
Y324764D01*
G01Y322402D02*
Y321614D01*
G01Y319252D02*
Y318465D01*
G01Y316102D02*
Y315315D01*
G01Y312953D02*
Y312165D01*
G01Y309803D02*
Y309016D01*
G01Y306654D02*
Y305866D01*
G01Y303504D02*
Y302717D01*
G01Y300354D02*
Y299567D01*
G01Y297205D02*
Y296417D01*
G01Y294055D02*
Y293268D01*
G01Y290906D02*
Y290118D01*
G01Y287756D02*
Y286969D01*
G01X164127Y334902D02*
Y337657D01*
G01X164173Y314705D02*
Y313130D01*
G01X164766Y335354D02*
Y335295D01*
G01X165159Y328701D02*
Y327913D01*
G01Y325551D02*
Y324764D01*
G01Y322402D02*
Y321614D01*
G01Y319252D02*
Y318465D01*
G01Y316102D02*
Y315315D01*
G01Y312953D02*
Y312165D01*
G01Y309803D02*
Y309016D01*
G01Y306654D02*
Y305866D01*
G01Y303504D02*
Y302717D01*
G01Y300354D02*
Y299567D01*
G01Y297205D02*
Y296417D01*
G01Y294055D02*
Y293268D01*
G01Y290906D02*
Y290118D01*
G01Y287756D02*
Y286969D01*
G01X165354Y329705D02*
Y328130D01*
G01Y324705D02*
Y323130D01*
G01Y319705D02*
Y318130D01*
G01Y309705D02*
Y308130D01*
G01Y304705D02*
Y303130D01*
G01Y299705D02*
Y298130D01*
G01Y294705D02*
Y293130D01*
G01Y289705D02*
Y288130D01*
G01X166339Y330492D02*
Y327343D01*
G01Y325492D02*
Y322343D01*
G01Y320492D02*
Y317343D01*
G01Y310492D02*
Y307343D01*
G01Y305492D02*
Y302343D01*
G01Y300492D02*
Y297343D01*
G01Y295492D02*
Y292343D01*
G01Y290492D02*
Y287343D01*
G01X167323Y337657D02*
Y335354D01*
G01Y330492D02*
Y327343D01*
G01Y325492D02*
Y322343D01*
G01Y320492D02*
Y317343D01*
G01Y314705D02*
Y313130D01*
G01Y310492D02*
Y307343D01*
G01Y305492D02*
Y302343D01*
G01Y300492D02*
Y297343D01*
G01Y295492D02*
Y292343D01*
G01Y290492D02*
Y287343D01*
G01X168307Y329705D02*
Y328130D01*
G01Y324705D02*
Y323130D01*
G01Y319705D02*
Y318130D01*
G01Y315492D02*
Y312343D01*
G01Y309705D02*
Y308130D01*
G01Y304705D02*
Y303130D01*
G01Y299705D02*
Y298130D01*
G01Y294705D02*
Y293130D01*
G01Y289705D02*
Y288130D01*
G01X168521Y290118D02*
Y290906D01*
G01Y286969D02*
Y287756D01*
G01Y293268D02*
Y294055D01*
G01Y299567D02*
Y300354D01*
G01Y296417D02*
Y297205D01*
G01Y302717D02*
Y303504D01*
G01Y309016D02*
Y309803D01*
G01Y305866D02*
Y306654D01*
G01Y312165D02*
Y312953D01*
G01Y318465D02*
Y319252D01*
G01Y315315D02*
Y316102D01*
G01Y321614D02*
Y322402D01*
G01Y327913D02*
Y328701D01*
G01Y324764D02*
Y325551D01*
G01X168898Y290118D02*
Y290906D01*
G01Y286969D02*
Y287756D01*
G01Y293268D02*
Y294055D01*
G01Y299567D02*
Y300354D01*
G01Y296417D02*
Y297205D01*
G01Y302717D02*
Y303504D01*
G01Y309016D02*
Y309803D01*
G01Y305866D02*
Y306654D01*
G01Y312165D02*
Y312953D01*
G01Y318465D02*
Y319252D01*
G01Y315315D02*
Y316102D01*
G01Y321614D02*
Y322402D01*
G01Y327913D02*
Y328701D01*
G01Y324764D02*
Y325551D01*
G01X168924Y290118D02*
Y290906D01*
G01Y286969D02*
Y287756D01*
G01Y293268D02*
Y294055D01*
G01Y299567D02*
Y300354D01*
G01Y296417D02*
Y297205D01*
G01Y302717D02*
Y303504D01*
G01Y309016D02*
Y309803D01*
G01Y305866D02*
Y306654D01*
G01Y312165D02*
Y312953D01*
G01Y318465D02*
Y319252D01*
G01Y315315D02*
Y316102D01*
G01Y321614D02*
Y322402D01*
G01Y327913D02*
Y328701D01*
G01Y324764D02*
Y325551D01*
G01X169291Y315492D02*
Y312343D01*
G01X160054Y338504D02*
X160035Y338448D01*
X159983Y338283D01*
X159905Y338024D01*
X159809Y337697D01*
X159704Y337323D01*
G01X164766Y335295D02*
X164511Y334902D01*
G01X159704Y345118D02*
G03Y337323I2304J-3897D01*
G01X164311D02*
G03Y345118I-2304J3898D01*
G01X165512Y341220D02*
G03I-3504J0D01*
G01X163962Y338504D02*
G03Y343937I-1954J2717D01*
G01X160054D02*
G03Y338504I1954J-2716D01*
G01X169764Y297736D02*
G03X169370Y298130I-394J0D01*
G01Y299705D02*
G03X169764Y300098I0J394D01*
G01Y302736D02*
G03X169370Y303130I-394J0D01*
G01Y304705D02*
G03X169764Y305098I0J394D01*
G01Y292736D02*
G03X169370Y293130I-394J0D01*
G01Y294705D02*
G03X169764Y295098I0J394D01*
G01Y287736D02*
G03X169370Y288130I-394J0D01*
G01Y289705D02*
G03X169764Y290098I0J394D01*
G01Y322736D02*
G03X169370Y323130I-394J0D01*
G01Y324705D02*
G03X169764Y325098I0J394D01*
G01Y317736D02*
G03X169370Y318130I-394J0D01*
G01Y319705D02*
G03X169764Y320098I0J394D01*
G01Y327736D02*
G03X169370Y328130I-394J0D01*
G01Y329705D02*
G03X169764Y330098I0J394D01*
G01Y307736D02*
G03X169370Y308130I-394J0D01*
G01Y309705D02*
G03X169764Y310098I0J394D01*
G01X167323Y267343D02*
X166339D01*
G01X167323Y267539D02*
X166339D01*
G01X167323Y267933D02*
X166339D01*
G01X151378Y268071D02*
X158710D01*
G01X158857D02*
X170866D01*
G01X162205Y268130D02*
X169370D01*
G01X170866Y268858D02*
X158857D01*
G01X158710D02*
X151378D01*
G01X162205Y269705D02*
X169370D01*
G01X167323Y269902D02*
X166339D01*
G01X167323Y270295D02*
X166339D01*
G01X167323Y270492D02*
X166339D01*
G01X151378Y271220D02*
X158710D01*
G01X158857D02*
X170866D01*
G01Y271713D02*
X169764D01*
G01X170866Y272008D02*
X158857D01*
G01X158710D02*
X151378D01*
G01X169291Y272343D02*
X168307D01*
G01X169291Y272539D02*
X168307D01*
G01X169291Y272933D02*
X168307D01*
G01X169764Y273130D02*
X164173D01*
G01X151378Y274370D02*
X158710D01*
G01X158857D02*
X170866D01*
G01X169764Y274705D02*
X164173D01*
G01X169291Y274902D02*
X168307D01*
G01X170866Y275157D02*
X158857D01*
G01X158710D02*
X151378D01*
G01X169291Y275295D02*
X168307D01*
G01X169291Y275492D02*
X168307D01*
G01X169764Y276122D02*
X170866D01*
G01X167323Y277343D02*
X166339D01*
G01X151378Y277520D02*
X158710D01*
G01X158857D02*
X170866D01*
G01X167323Y277539D02*
X166339D01*
G01X167323Y277933D02*
X166339D01*
G01X162205Y278130D02*
X169370D01*
G01X170866Y278307D02*
X158857D01*
G01X158710D02*
X151378D01*
G01X162205Y279705D02*
X169370D01*
G01X167323Y279902D02*
X166339D01*
G01X167323Y280295D02*
X166339D01*
G01X167323Y280492D02*
X166339D01*
G01X151378Y280669D02*
X158710D01*
G01X158857D02*
X170866D01*
G01Y281457D02*
X158857D01*
G01X158710D02*
X151378D01*
G01X167323Y282343D02*
X166339D01*
G01X167323Y282539D02*
X166339D01*
G01X167323Y282933D02*
X166339D01*
G01X162205Y283130D02*
X169370D01*
G01X151378Y283819D02*
X158710D01*
G01X158857D02*
X170866D01*
G01Y284606D02*
X158857D01*
G01X158710D02*
X151378D01*
G01X162205Y284705D02*
X169370D01*
G01X167323Y284902D02*
X166339D01*
G01X151378Y271220D02*
Y272008D01*
G01Y268071D02*
Y268858D01*
G01Y274370D02*
Y275157D01*
G01Y280669D02*
Y281457D01*
G01Y277520D02*
Y278307D01*
G01Y283819D02*
Y284606D01*
G01X153151Y271220D02*
Y272008D01*
G01Y268071D02*
Y268858D01*
G01Y274370D02*
Y275157D01*
G01Y280669D02*
Y281457D01*
G01Y277520D02*
Y278307D01*
G01Y283819D02*
Y284606D01*
G01X153340D02*
Y283819D01*
G01Y281457D02*
Y280669D01*
G01Y278307D02*
Y277520D01*
G01Y275157D02*
Y274370D01*
G01Y272008D02*
Y271220D01*
G01Y268858D02*
Y268071D01*
G01X156176Y284606D02*
Y283819D01*
G01Y281457D02*
Y280669D01*
G01Y278307D02*
Y277520D01*
G01Y275157D02*
Y274370D01*
G01Y272008D02*
Y271220D01*
G01Y268858D02*
Y268071D01*
G01X157118Y271220D02*
Y272008D01*
G01Y268071D02*
Y268858D01*
G01Y274370D02*
Y275157D01*
G01Y280669D02*
Y281457D01*
G01Y277520D02*
Y278307D01*
G01Y283819D02*
Y284606D01*
G01X158710Y271220D02*
Y272008D01*
G01Y268071D02*
Y268858D01*
G01Y274370D02*
Y275157D01*
G01Y280669D02*
Y281457D01*
G01Y277520D02*
Y278307D01*
G01Y283819D02*
Y284606D01*
G01X158857Y271220D02*
Y272008D01*
G01Y268071D02*
Y268858D01*
G01Y274370D02*
Y275157D01*
G01Y280669D02*
Y281457D01*
G01Y277520D02*
Y278307D01*
G01Y283819D02*
Y284606D01*
G01X159796Y286969D02*
Y284606D01*
G01Y283819D02*
Y281457D01*
G01Y280669D02*
Y278307D01*
G01Y277520D02*
Y275157D01*
G01Y274370D02*
Y272008D01*
G01Y271220D02*
Y268858D01*
G01X161524Y271220D02*
Y272008D01*
G01Y268071D02*
Y268858D01*
G01Y274370D02*
Y275157D01*
G01Y280669D02*
Y281457D01*
G01Y277520D02*
Y278307D01*
G01Y283819D02*
Y284606D01*
G01X162205Y284705D02*
Y283130D01*
G01Y279705D02*
Y278130D01*
G01Y269705D02*
Y268130D01*
G01X163176Y284606D02*
Y283819D01*
G01Y281457D02*
Y280669D01*
G01Y278307D02*
Y277520D01*
G01Y275157D02*
Y274370D01*
G01Y272008D02*
Y271220D01*
G01Y268858D02*
Y268071D01*
G01X164173Y274705D02*
Y273130D01*
G01X165159Y284606D02*
Y283819D01*
G01Y281457D02*
Y280669D01*
G01Y278307D02*
Y277520D01*
G01Y275157D02*
Y274370D01*
G01Y272008D02*
Y271220D01*
G01Y268858D02*
Y268071D01*
G01X165354Y284705D02*
Y283130D01*
G01Y279705D02*
Y278130D01*
G01Y269705D02*
Y268130D01*
G01X166339Y285492D02*
Y282343D01*
G01Y280492D02*
Y277343D01*
G01Y270492D02*
Y267343D01*
G01X167323Y285492D02*
Y282343D01*
G01Y280492D02*
Y277343D01*
G01Y274705D02*
Y273130D01*
G01Y270492D02*
Y267343D01*
G01X168307Y284705D02*
Y283130D01*
G01Y279705D02*
Y278130D01*
G01Y275492D02*
Y272343D01*
G01Y269705D02*
Y268130D01*
G01X168521Y271220D02*
Y272008D01*
G01Y268071D02*
Y268858D01*
G01Y274370D02*
Y275157D01*
G01Y280669D02*
Y281457D01*
G01Y277520D02*
Y278307D01*
G01Y283819D02*
Y284606D01*
G01X168898Y271220D02*
Y272008D01*
G01Y268071D02*
Y268858D01*
G01Y274370D02*
Y275157D01*
G01Y280669D02*
Y281457D01*
G01Y277520D02*
Y278307D01*
G01Y283819D02*
Y284606D01*
G01X168924Y271220D02*
Y272008D01*
G01Y268071D02*
Y268858D01*
G01Y274370D02*
Y275157D01*
G01Y280669D02*
Y281457D01*
G01Y277520D02*
Y278307D01*
G01Y283819D02*
Y284606D01*
G01X169291Y275492D02*
Y272343D01*
G01X169764Y282736D02*
G03X169370Y283130I-394J0D01*
G01Y284705D02*
G03X169764Y285098I0J394D01*
G01Y267736D02*
G03X169370Y268130I-394J0D01*
G01Y269705D02*
G03X169764Y270098I0J394D01*
G01Y277736D02*
G03X169370Y278130I-394J0D01*
G01Y279705D02*
G03X169764Y280098I0J394D01*
G01X149606Y346004D02*
X203543D01*
G01X172298Y353819D02*
Y352244D01*
G01X172669D02*
Y353819D01*
G01X173991D02*
Y352244D01*
G01X174016Y353819D02*
Y352244D01*
G01X174050D02*
Y353819D01*
G01X173425Y351457D02*
G03Y354606I0J1574D01*
G01X179449Y348760D02*
X163071D01*
G01X173425Y351457D02*
X169094D01*
G01X174050Y352244D02*
X168469D01*
G01Y353819D02*
X174050D01*
G01X169094Y354606D02*
X173425D01*
G01X179449Y358937D02*
X163071D01*
G01D02*
Y346004D01*
G01X168469Y353819D02*
Y352244D01*
G01X168504D02*
Y353819D01*
G01X168528Y352244D02*
Y353819D01*
G01X169851D02*
Y352244D01*
G01X170221D02*
Y353819D01*
G01X169094Y354606D02*
G03Y351457I0J-1574D01*
G01X173228Y340256D02*
X149606D01*
G01X173228Y344035D02*
X149606D01*
G01X175424Y340595D02*
X173982D01*
G01X175424Y344602D02*
X173984D01*
G01X203543Y344823D02*
X177165D01*
G01X172554Y344602D02*
Y342077D01*
G01X173228Y344035D02*
Y340256D01*
G01X173982Y341152D02*
Y340595D01*
G01X173984Y342077D02*
Y344602D01*
G01X175424D02*
Y340595D01*
G01X171201Y341146D02*
G03X173982Y341152I1388J1207D01*
G01X172554Y342077D02*
G03X173984I715J0D01*
G01X162472Y338848D02*
X161012D01*
G01X155667Y340595D02*
X154050D01*
G01X152755D02*
X151373D01*
G01X158865Y342177D02*
X157440D01*
G01X158866Y343003D02*
X155867D01*
G01X157500Y343446D02*
X155997D01*
G01X160054Y343937D02*
X163962D01*
G01X169664Y344602D02*
X168271D01*
G01X172554D02*
X171094D01*
G01X162472D02*
X161012D01*
G01X155840D02*
X154432D01*
G01X152896D02*
X151347D01*
G01X164311Y345118D02*
X159704D01*
G01X154398Y342455D02*
X155667Y340595D01*
G01X153444Y341581D02*
X154050Y340595D01*
G01X151347Y344602D02*
X152668Y342446D01*
G01X152896Y344602D02*
X153641Y343324D01*
G01X160054Y343937D02*
X160035Y343993D01*
X159983Y344158D01*
X159904Y344417D01*
X159809Y344744D01*
X159704Y345118D01*
G01X161012Y344602D02*
Y338848D01*
G01X162472Y344602D02*
Y338848D01*
G01X168271Y344602D02*
Y341673D01*
G01X169664Y344602D02*
Y342077D01*
G01X171094D02*
Y344602D01*
G01X164311Y345118D02*
X164208Y344749D01*
X164112Y344419D01*
X164032Y344157D01*
X163980Y343991D01*
X163962Y343937D01*
G01X154432Y344602D02*
X153641Y343324D01*
G01X155840Y344602D02*
X154398Y342455D01*
G01X153444Y341581D02*
X152755Y340595D01*
G01X152668Y342446D02*
X151373Y340595D01*
G01X158425Y344802D02*
G03X156840Y344515I-262J-3073D01*
G01X157440Y342177D02*
G03X158865I713J-82D01*
G01X160247Y341769D02*
G03X160421Y342429I-4018J1412D01*
G01D02*
G03Y342926I-3524J249D01*
G01X155867Y343003D02*
G03X156206Y341560I3014J-53D01*
G01X160421Y342924D02*
G03X160159Y343787I-2971J-431D01*
G01X157440Y340587D02*
G03X159082Y340630I757J2475D01*
G01X160161Y343785D02*
G03X158422Y344802I-1807J-1094D01*
G01X159082Y340630D02*
G03X160247Y341769I-729J1911D01*
G01X156205Y341560D02*
G03X157439Y340586I1736J930D01*
G01X156840Y344515D02*
G03X155997Y343446I704J-1422D01*
G01X158865Y343003D02*
G03X158091Y343811I-792J16D01*
G01D02*
G03X157500Y343446I-9J-646D01*
G01X164173Y341220D02*
G03I-2165J0D01*
G01X166065Y341809D02*
G03Y343493I-2237J842D01*
G01X163250Y341514D02*
G03X163771Y340949I1351J723D01*
G01X163770Y344391D02*
G03X163249Y343826I830J-1288D01*
G01X163771Y340948D02*
G03X166817Y340949I1522J2362D01*
G01X166816Y344393D02*
G03X163770Y344392I-1522J-2362D01*
G01X163249Y343826D02*
G03X163250Y341514I2163J-1155D01*
G01X167338D02*
G03X167337Y343828I-2163J1156D01*
G01X164592Y343493D02*
G03Y341809I2236J-842D01*
G01X166817Y340949D02*
G03X167338Y341514I-830J1288D01*
G01X167337Y343828D02*
G03X166816Y344393I-1351J-723D01*
G01X168271Y341673D02*
G03X168565Y341002I914J0D01*
G01X164592Y341809D02*
G03X166065I737J277D01*
G01Y343493D02*
G03X164592I-737J-277D01*
G01X168565Y341002D02*
G03X171201Y341146I1248J1351D01*
G01X169664Y342077D02*
G03X171094I715J0D01*
G01X182579Y538976D02*
X178937D01*
G01X182579Y539961D02*
X178937D01*
G01X182579Y541535D02*
X178937D01*
G01X182579Y542520D02*
X178937D01*
G01X182579Y544094D02*
X178937D01*
G01X182579Y545079D02*
X178937D01*
G01X182579Y546654D02*
X178937D01*
G01X182579Y547638D02*
X178937D01*
G01Y537205D02*
Y549409D01*
G01X179134Y547638D02*
Y546654D01*
G01Y545079D02*
Y544094D01*
G01Y542520D02*
Y541535D01*
G01Y539961D02*
Y538976D01*
G01X179215Y547638D02*
Y546654D01*
G01Y545079D02*
Y544094D01*
G01Y542520D02*
Y541535D01*
G01Y539961D02*
Y538976D01*
G01X180610Y547638D02*
Y546654D01*
G01Y545079D02*
Y544094D01*
G01Y542520D02*
Y541535D01*
G01Y539961D02*
Y538976D01*
G01X180692Y547638D02*
Y546654D01*
G01Y545079D02*
Y544094D01*
G01Y542520D02*
Y541535D01*
G01Y539961D02*
Y538976D01*
G01X182579Y547638D02*
Y546654D01*
G01Y545079D02*
Y544094D01*
G01Y542520D02*
Y541535D01*
G01Y539961D02*
Y538976D01*
G01X159941Y533268D02*
X186516D01*
G01X167520Y537205D02*
X178937D01*
G01X167520Y538976D02*
X163878D01*
G01X167520Y539961D02*
X163878D01*
G01X167520Y541535D02*
X163878D01*
G01X167520Y542520D02*
X163878D01*
G01X167520Y544094D02*
X163878D01*
G01X167520Y545079D02*
X163878D01*
G01X167520Y546654D02*
X163878D01*
G01X163179Y546811D02*
X163085D01*
G01Y547559D02*
X163179D01*
G01X167520Y547638D02*
X163878D01*
G01X178937Y549409D02*
X167520D01*
G01X186516Y553346D02*
X159941D01*
G01D02*
Y533268D01*
G01X162992Y547320D02*
Y547448D01*
G01X163085Y546811D02*
Y547431D01*
G01X163179Y547559D02*
Y546811D01*
G01X163878Y547638D02*
Y546654D01*
G01Y545079D02*
Y544094D01*
G01Y542520D02*
Y541535D01*
G01Y539961D02*
Y538976D01*
G01X165765Y547638D02*
Y546654D01*
G01Y545079D02*
Y544094D01*
G01Y542520D02*
Y541535D01*
G01Y539961D02*
Y538976D01*
G01X165846Y547638D02*
Y546654D01*
G01Y545079D02*
Y544094D01*
G01Y542520D02*
Y541535D01*
G01Y539961D02*
Y538976D01*
G01X167241Y547638D02*
Y546654D01*
G01Y545079D02*
Y544094D01*
G01Y542520D02*
Y541535D01*
G01Y539961D02*
Y538976D01*
G01X167323Y547638D02*
Y546654D01*
G01Y545079D02*
Y544094D01*
G01Y542520D02*
Y541535D01*
G01Y539961D02*
Y538976D01*
G01X167520Y549409D02*
Y537205D01*
G01X162992Y547448D02*
X163085Y547559D01*
G01Y547431D02*
X162992Y547320D01*
G01X169882Y547244D02*
G03I-591J0D01*
G01X203543Y592343D02*
X149606D01*
G01X173228Y594311D02*
X149606D01*
G01X173228Y598091D02*
X149606D01*
G01Y600059D02*
X173228D01*
G01X199606Y600689D02*
X149606D01*
G01X173228Y602500D02*
X149606D01*
G01X150399Y603445D02*
X170866D01*
G01X169764Y606024D02*
X149606D01*
G01D02*
Y592343D01*
G01X149924Y606024D02*
Y600689D01*
G01X150399Y606024D02*
Y603445D01*
G01X172441Y607270D02*
X172789Y607185D01*
G01X172876Y607697D02*
X172615Y607782D01*
G01X175315Y609915D02*
X174967Y610085D01*
G01X174880Y609573D02*
X175141Y609403D01*
G01X172441Y610768D02*
X171831Y611280D01*
G01X172528D02*
X173137Y610768D01*
G01X172092Y607611D02*
X172441Y607270D01*
G01X175664Y609573D02*
X175315Y609915D01*
G01X172615Y607782D02*
X172441Y608038D01*
G01X175141Y609403D02*
X175315Y609147D01*
G01X171918Y607953D02*
X172092Y607611D01*
G01X175838Y609232D02*
X175664Y609573D01*
G01X177165Y593524D02*
X203543D01*
G01X172428Y593563D02*
X173314D01*
G01X171690Y598730D02*
X174643D01*
G01X175529Y599469D02*
X171690D01*
G01X199606Y605610D02*
X181102D01*
G01X179449Y605807D02*
X172913D01*
G01X172789Y607185D02*
X173137D01*
G01X173050Y607697D02*
X172876D01*
G01X174618Y609573D02*
X174880D01*
G01X174967Y610085D02*
X174531D01*
G01X173137Y610768D02*
X172441D01*
G01X175925Y611280D02*
X172528D01*
G01X171831Y611791D02*
X175925D01*
G01X199606Y622224D02*
X172913D01*
G01X172441Y608038D02*
X172353Y608294D01*
G01X171831D02*
X171918Y607953D01*
G01X175315Y609147D02*
X175402Y608806D01*
G01X175925D02*
X175838Y609232D01*
G01X171690Y599469D02*
Y598730D01*
G01X171831Y608720D02*
Y608294D01*
G01Y611280D02*
Y611791D01*
G01X172353Y608294D02*
Y608806D01*
G01X172789Y609317D02*
Y609829D01*
G01X172913Y605807D02*
Y738051D01*
G01X173228Y602500D02*
Y600059D01*
G01Y598091D02*
Y594311D01*
G01X173573Y608806D02*
Y608294D01*
G01X174096D02*
Y608806D01*
G01X174793Y607441D02*
Y606929D01*
G01X174882Y639823D02*
Y624587D01*
G01Y622224D02*
Y605807D01*
G01X175402Y608806D02*
Y608123D01*
G01X175529Y598804D02*
Y599469D01*
G01X175925Y611791D02*
Y611280D01*
G01Y608123D02*
Y608806D01*
G01X177165Y592343D02*
Y600689D01*
G01X179134Y606398D02*
Y604626D01*
G01X181102Y738248D02*
Y605610D01*
G01X174793Y606929D02*
X175141Y607014D01*
G01X173137Y607185D02*
X173486Y607270D01*
G01X199606Y624587D02*
X172913D01*
G01X171918Y609147D02*
X171831Y608720D01*
G01X173660Y609232D02*
X173573Y608806D01*
G01X175838Y607697D02*
X175925Y608123D01*
G01X174096Y608806D02*
X174183Y609147D01*
G01X174009Y607953D02*
X174096Y608294D01*
G01X175402Y608123D02*
X175315Y607782D01*
G01X172353Y608806D02*
X172441Y609061D01*
G01X173573Y608294D02*
X173486Y608038D01*
G01X173834Y609573D02*
X173660Y609232D01*
G01X173834Y607611D02*
X174009Y607953D01*
G01X175577Y607270D02*
X175838Y607697D01*
G01X174183Y609147D02*
X174357Y609403D01*
G01X173486Y608038D02*
X173311Y607782D01*
G01X172179Y609488D02*
X171918Y609147D01*
G01X172441Y609061D02*
X172615Y609232D01*
G01X174183Y609915D02*
X173834Y609573D01*
G01X173486Y607270D02*
X173834Y607611D01*
G01X175315Y607782D02*
X175054Y607526D01*
G01X172528Y609744D02*
X172179Y609488D01*
G01X174357Y609403D02*
X174618Y609573D01*
G01X175141Y607014D02*
X175577Y607270D01*
G01X172615Y609232D02*
X172789Y609317D01*
G01X174531Y610085D02*
X174183Y609915D01*
G01X172789Y609829D02*
X172528Y609744D01*
G01X173311Y607782D02*
X173050Y607697D01*
G01X175054Y607526D02*
X174793Y607441D01*
G01X175529Y598804D02*
G03X173314Y593563I7141J-6107D01*
G01X174643Y598730D02*
G03X172428Y593563I6937J-6032D01*
G01X157832Y594379D02*
X157472Y594615D01*
X157233Y594965D01*
X157148Y595369D01*
X157231Y595771D01*
X157467Y596123D01*
X157830Y596363D01*
X158255Y596448D01*
G01X158678Y596364D02*
X159039Y596128D01*
X159277Y595778D01*
X159363Y595374D01*
X159280Y594972D01*
X159043Y594620D01*
X158680Y594380D01*
X158255Y594295D01*
G01X163000Y594379D02*
X162639Y594615D01*
X162401Y594965D01*
X162315Y595369D01*
X162398Y595771D01*
X162634Y596123D01*
X162998Y596363D01*
X163422Y596448D01*
G01X159453Y596819D02*
X159905Y596379D01*
X160175Y595843D01*
X160245Y595273D01*
X160104Y594709D01*
X159757Y594184D01*
X159230Y593791D01*
X158587Y593588D01*
X157907Y593590D01*
X157267Y593798D01*
X156744Y594194D01*
X156403Y594718D01*
X156265Y595279D01*
X156337Y595847D01*
X156607Y596381D01*
G01X164620Y596819D02*
X165072Y596379D01*
X165342Y595843D01*
X165413Y595273D01*
X165271Y594709D01*
X164924Y594184D01*
X164397Y593791D01*
X163754Y593588D01*
X163075Y593590D01*
X162435Y593798D01*
X161912Y594194D01*
X161570Y594718D01*
X161432Y595279D01*
X161504Y595847D01*
X161774Y596381D01*
G01X168602Y598730D02*
X168950Y598661D01*
G01X157906Y597171D02*
X157624Y597349D01*
X157437Y597614D01*
X157370Y597916D01*
X157434Y598216D01*
X157619Y598483D01*
X157905Y598665D01*
X158255Y598730D01*
G01X158604Y598665D02*
X158887Y598487D01*
X159074Y598222D01*
X159141Y597920D01*
X159076Y597620D01*
X158891Y597353D01*
X158606Y597172D01*
X158255Y597106D01*
G01X163074Y597171D02*
X162791Y597349D01*
X162604Y597614D01*
X162537Y597916D01*
X162601Y598216D01*
X162787Y598483D01*
X163072Y598665D01*
X163422Y598730D01*
G01X163772Y598665D02*
X164054Y598487D01*
X164241Y598222D01*
X164308Y597920D01*
X164244Y597620D01*
X164058Y597353D01*
X163773Y597172D01*
X163422Y597106D01*
G01X168949Y598661D02*
X169229Y598480D01*
G01X163846Y596364D02*
X164206Y596128D01*
X164444Y595778D01*
X164530Y595374D01*
X164447Y594972D01*
X164211Y594620D01*
X163847Y594380D01*
X163422Y594295D01*
G01X157057Y596819D02*
X156735Y597239D01*
X156572Y597722D01*
X156594Y598227D01*
X156797Y598704D01*
X157164Y599107D01*
X157670Y599374D01*
X158261Y599469D01*
X158850Y599371D01*
X159353Y599102D01*
X159717Y598698D01*
X159918Y598220D01*
X159937Y597716D01*
X159774Y597235D01*
X159453Y596819D01*
G01X162225D02*
X161902Y597239D01*
X161739Y597722D01*
X161761Y598227D01*
X161964Y598704D01*
X162331Y599107D01*
X162837Y599374D01*
X163428Y599469D01*
X164018Y599371D01*
X164520Y599102D01*
X164884Y598698D01*
X165085Y598220D01*
X165105Y597716D01*
X164941Y597235D01*
X164620Y596819D01*
G01X169229Y598481D02*
X169411Y598216D01*
X169476Y597917D01*
X169411Y597620D01*
G01X164511Y603445D02*
X164766Y603051D01*
G01X168469Y586102D02*
X174050D01*
G01X169094Y586890D02*
X173425D01*
G01X179449Y589587D02*
X163071D01*
G01X151981Y593563D02*
X152867D01*
G01X166597D02*
X170509D01*
G01Y594301D02*
X167630D01*
G01X166892Y597770D02*
X167704D01*
G01X151243Y598730D02*
X154195D01*
G01X155081Y599469D02*
X151243D01*
G01X170866Y602992D02*
X164766D01*
G01Y603051D02*
X170866D01*
G01X169764Y604626D02*
X179134D01*
G01X170866Y605217D02*
X201575D01*
G01X169764Y606398D02*
X179134D01*
G01X167323Y607854D02*
X166339D01*
G01X165748Y608012D02*
X156763D01*
G01X167323Y608051D02*
X166339D01*
G01X167323Y608445D02*
X166339D01*
G01X161240Y608465D02*
X169311D01*
G01X162205Y608642D02*
X169370D01*
G01X162205Y610217D02*
X169370D01*
G01X167323Y610413D02*
X166339D01*
G01X169311Y610433D02*
X161240D01*
G01X151378Y610591D02*
X158710D01*
G01X158857D02*
X170866D01*
G01X167323Y610807D02*
X166339D01*
G01X167323Y611004D02*
X166339D01*
G01X170866Y611378D02*
X158857D01*
G01X158710D02*
X151378D01*
G01X167323Y612854D02*
X166339D01*
G01X167323Y613051D02*
X166339D01*
G01X167323Y613445D02*
X166339D01*
G01X162205Y613642D02*
X169370D01*
G01X151378Y613740D02*
X158710D01*
G01X158857D02*
X170866D01*
G01Y614528D02*
X158857D01*
G01X158710D02*
X151378D01*
G01X162205Y615217D02*
X169370D01*
G01X167323Y615413D02*
X166339D01*
G01X167323Y615807D02*
X166339D01*
G01X167323Y616004D02*
X166339D01*
G01X151378Y616890D02*
X158710D01*
G01X158857D02*
X170866D01*
G01Y617677D02*
X158857D01*
G01X158710D02*
X151378D01*
G01X167323Y617854D02*
X166339D01*
G01X167323Y618051D02*
X166339D01*
G01X167323Y618445D02*
X166339D01*
G01X162205Y618642D02*
X169370D01*
G01X151378Y620039D02*
X158710D01*
G01X158857D02*
X170866D01*
G01X162205Y620217D02*
X169370D01*
G01X167323Y620413D02*
X166339D01*
G01X167323Y620807D02*
X166339D01*
G01X170866Y620827D02*
X158857D01*
G01X158710D02*
X151378D01*
G01X167323Y621004D02*
X166339D01*
G01X167323Y622854D02*
X166339D01*
G01X167323Y623051D02*
X166339D01*
G01X151378Y623189D02*
X158710D01*
G01X158857D02*
X170866D01*
G01X151243Y599469D02*
Y598730D01*
G01X151378Y610591D02*
Y611378D01*
G01Y616890D02*
Y617677D01*
G01Y613740D02*
Y614528D01*
G01Y620039D02*
Y620827D01*
G01Y623189D02*
Y623976D01*
G01X153151Y610591D02*
Y611378D01*
G01Y616890D02*
Y617677D01*
G01Y613740D02*
Y614528D01*
G01Y620039D02*
Y620827D01*
G01Y623189D02*
Y623976D01*
G01X153340D02*
Y623189D01*
G01Y620827D02*
Y620039D01*
G01Y617677D02*
Y616890D01*
G01Y614528D02*
Y613740D01*
G01Y611378D02*
Y610591D01*
G01X155081Y598804D02*
Y599469D01*
G01X156176Y623976D02*
Y623189D01*
G01Y620827D02*
Y620039D01*
G01Y617677D02*
Y616890D01*
G01Y614528D02*
Y613740D01*
G01Y611378D02*
Y610591D01*
G01X156253Y600689D02*
Y603445D01*
G01X156763Y740413D02*
Y603445D01*
G01X157118Y610591D02*
Y611378D01*
G01Y616890D02*
Y617677D01*
G01Y613740D02*
Y614528D01*
G01Y620039D02*
Y620827D01*
G01Y623189D02*
Y623976D01*
G01X158710Y610591D02*
Y611378D01*
G01Y616890D02*
Y617677D01*
G01Y613740D02*
Y614528D01*
G01Y620039D02*
Y620827D01*
G01Y623189D02*
Y623976D01*
G01X158857Y610591D02*
Y611378D01*
G01Y616890D02*
Y617677D01*
G01Y613740D02*
Y614528D01*
G01Y620039D02*
Y620827D01*
G01Y623189D02*
Y623976D01*
G01X159796Y626339D02*
Y623976D01*
G01Y623189D02*
Y620827D01*
G01Y620039D02*
Y617677D01*
G01Y616890D02*
Y614528D01*
G01Y610591D02*
Y608012D01*
G01Y613740D02*
Y611378D01*
G01X161240Y610433D02*
Y608465D01*
G01X161524Y610591D02*
Y611378D01*
G01Y616890D02*
Y617677D01*
G01Y613740D02*
Y614528D01*
G01Y620039D02*
Y620827D01*
G01Y623189D02*
Y623976D01*
G01X162205Y625217D02*
Y623642D01*
G01Y620217D02*
Y618642D01*
G01Y615217D02*
Y613642D01*
G01Y610217D02*
Y608642D01*
G01X163176Y623976D02*
Y623189D01*
G01Y620827D02*
Y620039D01*
G01Y617677D02*
Y616890D01*
G01Y614528D02*
Y613740D01*
G01Y611378D02*
Y610591D01*
G01X164127Y600689D02*
Y603445D01*
G01X164766Y603051D02*
Y602992D01*
G01X165159Y623976D02*
Y623189D01*
G01Y620827D02*
Y620039D01*
G01Y617677D02*
Y616890D01*
G01Y614528D02*
Y613740D01*
G01Y611378D02*
Y610591D01*
G01X165293Y606024D02*
Y737638D01*
G01X165354Y625217D02*
Y623642D01*
G01Y620217D02*
Y618642D01*
G01Y615217D02*
Y613642D01*
G01Y610217D02*
Y608642D01*
G01X165748Y603445D02*
Y740413D01*
G01X166339Y626004D02*
Y622854D01*
G01Y621004D02*
Y617854D01*
G01Y616004D02*
Y612854D01*
G01Y611004D02*
Y607854D01*
G01X166597Y594006D02*
Y593563D01*
G01X166892Y597918D02*
Y597770D01*
G01X167323Y626004D02*
Y622854D01*
G01Y621004D02*
Y617854D01*
G01Y616004D02*
Y612854D01*
G01Y611004D02*
Y607854D01*
G01Y602992D02*
Y600689D01*
G01X167704Y597770D02*
Y597918D01*
G01X168307Y625217D02*
Y623642D01*
G01Y620217D02*
Y618642D01*
G01Y615217D02*
Y613642D01*
G01Y610217D02*
Y608642D01*
G01X168521Y610591D02*
Y611378D01*
G01Y616890D02*
Y617677D01*
G01Y613740D02*
Y614528D01*
G01Y620039D02*
Y620827D01*
G01Y623189D02*
Y623976D01*
G01X168898Y610591D02*
Y611378D01*
G01Y616890D02*
Y617677D01*
G01Y613740D02*
Y614528D01*
G01Y620039D02*
Y620827D01*
G01Y623189D02*
Y623976D01*
G01X168924Y610591D02*
Y611378D01*
G01Y616890D02*
Y617677D01*
G01Y613740D02*
Y614528D01*
G01Y620039D02*
Y620827D01*
G01Y623189D02*
Y623976D01*
G01X169311Y608465D02*
Y610433D01*
G01X169764Y603445D02*
Y740413D01*
G01X170509Y593563D02*
Y594301D01*
G01X170866Y740866D02*
Y602992D01*
G01X167323Y623445D02*
X166339D01*
G01X162205Y623642D02*
X169370D01*
G01X170866Y623976D02*
X158857D01*
G01X158710D02*
X151378D01*
G01X162205Y625217D02*
X169370D01*
G01X166892Y597918D02*
X166979Y598395D01*
X167226Y598837D01*
X167615Y599189D01*
X168121Y599409D01*
X168699Y599465D01*
X169263Y599343D01*
X169739Y599061D01*
X170078Y598656D01*
X170257Y598199D01*
X170272Y597719D01*
X170115Y597248D01*
X169801Y596831D01*
G01X167772Y598223D02*
X167704Y597918D01*
G01X169229Y597356D02*
X169412Y597622D01*
X169476Y597919D01*
X169411Y598217D01*
G01X167961Y598490D02*
X167771Y598222D01*
G01X169801Y596831D02*
X170138Y597293D01*
X170283Y597812D01*
X170223Y598330D01*
X169972Y598813D01*
X169535Y599208D01*
X168962Y599431D01*
X168328Y599450D01*
X167743Y599264D01*
X167288Y598911D01*
X166996Y598439D01*
X166892Y597918D01*
G01X159453Y596819D02*
X159776Y597239D01*
X159938Y597722D01*
X159917Y598227D01*
X159713Y598704D01*
X159347Y599107D01*
X158841Y599374D01*
X158250Y599469D01*
X157660Y599371D01*
X157158Y599102D01*
X156794Y598698D01*
X156593Y598220D01*
X156573Y597716D01*
X156737Y597235D01*
X157057Y596819D01*
G01X164620D02*
X164943Y597239D01*
X165106Y597722D01*
X165084Y598227D01*
X164881Y598704D01*
X164514Y599107D01*
X164008Y599374D01*
X163417Y599469D01*
X162828Y599371D01*
X162325Y599102D01*
X161961Y598698D01*
X161760Y598220D01*
X161741Y597716D01*
X161904Y597235D01*
X162225Y596819D01*
G01X169229Y597356D02*
X167667Y595829D01*
G01X157057Y596819D02*
X156606Y596379D01*
X156336Y595843D01*
X156265Y595273D01*
X156407Y594709D01*
X156754Y594184D01*
X157281Y593791D01*
X157924Y593588D01*
X158603Y593590D01*
X159243Y593798D01*
X159766Y594194D01*
X160107Y594718D01*
X160245Y595279D01*
X160174Y595847D01*
X159904Y596381D01*
G01X162225Y596819D02*
X161773Y596379D01*
X161503Y595843D01*
X161433Y595273D01*
X161574Y594709D01*
X161921Y594184D01*
X162448Y593791D01*
X163091Y593588D01*
X163770Y593590D01*
X164411Y593798D01*
X164933Y594194D01*
X165275Y594718D01*
X165413Y595279D01*
X165341Y595847D01*
X165071Y596381D01*
G01X169801Y596831D02*
X168172Y595285D01*
G01X157832Y596364D02*
X157472Y596128D01*
X157233Y595778D01*
X157148Y595374D01*
X157231Y594972D01*
X157467Y594620D01*
X157830Y594380D01*
X158255Y594295D01*
G01X158678Y594379D02*
X159039Y594615D01*
X159277Y594965D01*
X159363Y595369D01*
X159280Y595771D01*
X159043Y596123D01*
X158680Y596363D01*
X158255Y596448D01*
G01X163000Y596364D02*
X162639Y596128D01*
X162401Y595778D01*
X162315Y595374D01*
X162398Y594972D01*
X162634Y594620D01*
X162998Y594380D01*
X163422Y594295D01*
G01X163846Y594379D02*
X164206Y594615D01*
X164444Y594965D01*
X164530Y595369D01*
X164447Y595771D01*
X164211Y596123D01*
X163847Y596363D01*
X163422Y596448D01*
G01X157906Y598665D02*
X157624Y598487D01*
X157437Y598222D01*
X157370Y597920D01*
X157434Y597620D01*
X157619Y597353D01*
X157905Y597172D01*
X158255Y597106D01*
G01X158604Y597171D02*
X158887Y597349D01*
X159074Y597614D01*
X159141Y597916D01*
X159076Y598216D01*
X158891Y598483D01*
X158606Y598665D01*
X158255Y598730D01*
G01X163074Y598665D02*
X162791Y598487D01*
X162604Y598222D01*
X162537Y597920D01*
X162601Y597620D01*
X162787Y597353D01*
X163072Y597172D01*
X163422Y597106D01*
G01X163772Y597171D02*
X164054Y597349D01*
X164241Y597614D01*
X164308Y597916D01*
X164244Y598216D01*
X164058Y598483D01*
X163773Y598665D01*
X163422Y598730D01*
G01X167961Y598490D02*
X168248Y598668D01*
X168602Y598730D01*
G01X155081Y598804D02*
G03X152866Y593563I7142J-6107D01*
G01X154195Y598730D02*
G03X151981Y593563I6938J-6031D01*
G01X166535Y597126D02*
G03I-4527J0D01*
G01X165512D02*
G03I-3504J0D01*
G01X165354D02*
G03I-3346J0D01*
G01X164173D02*
G03I-2165J0D01*
G01X168172Y595285D02*
G03X167630Y594301I1276J-1344D01*
G01X169764Y613248D02*
G03X169370Y613642I-394J0D01*
G01Y615217D02*
G03X169764Y615610I0J394D01*
G01Y623248D02*
G03X169370Y623642I-394J0D01*
G01Y625217D02*
G03X169764Y625610I0J394D01*
G01Y618248D02*
G03X169370Y618642I-394J0D01*
G01Y620217D02*
G03X169764Y620610I0J394D01*
G01Y608248D02*
G03X169370Y608642I-394J0D01*
G01Y610217D02*
G03X169764Y610610I0J394D01*
G01X167667Y595829D02*
G03X166597Y594006I2809J-2874D01*
G01X151378Y626339D02*
Y627126D01*
G01Y629488D02*
Y630276D01*
G01X153151Y626339D02*
Y627126D01*
G01Y629488D02*
Y630276D01*
G01X153340D02*
Y629488D01*
G01Y627126D02*
Y626339D01*
G01X156176Y630276D02*
Y629488D01*
G01Y627126D02*
Y626339D01*
G01X157118D02*
Y627126D01*
G01Y629488D02*
Y630276D01*
G01X158710Y626339D02*
Y627126D01*
G01Y629488D02*
Y630276D01*
G01X158857Y626339D02*
Y627126D01*
G01Y629488D02*
Y630276D01*
G01X159796Y629488D02*
Y627126D01*
G01X161524Y626339D02*
Y627126D01*
G01Y629488D02*
Y630276D01*
G01X162205Y630217D02*
Y628642D01*
G01X163176Y630276D02*
Y629488D01*
G01Y627126D02*
Y626339D01*
G01X165159Y630276D02*
Y629488D01*
G01Y627126D02*
Y626339D01*
G01X165354Y630217D02*
Y628642D01*
G01X166339Y631004D02*
Y627854D01*
G01X167323Y631004D02*
Y627854D01*
G01X168307Y630217D02*
Y628642D01*
G01X168521Y626339D02*
Y627126D01*
G01Y629488D02*
Y630276D01*
G01X168898Y626339D02*
Y627126D01*
G01Y629488D02*
Y630276D01*
G01X168924Y626339D02*
Y627126D01*
G01Y629488D02*
Y630276D01*
G01X167323Y625413D02*
X166339D01*
G01X167323Y625807D02*
X166339D01*
G01X167323Y626004D02*
X166339D01*
G01X151378Y626339D02*
X158710D01*
G01X158857D02*
X170866D01*
G01Y627126D02*
X158857D01*
G01X158710D02*
X151378D01*
G01X167323Y627854D02*
X166339D01*
G01X167323Y628051D02*
X166339D01*
G01X167323Y628445D02*
X166339D01*
G01X162205Y628642D02*
X169370D01*
G01X151378Y629488D02*
X158710D01*
G01X158857D02*
X170866D01*
G01X169764Y628248D02*
G03X169370Y628642I-394J0D01*
G01X172835Y565059D02*
X175984D01*
G01Y567028D02*
X172835D01*
G01X175984Y567618D02*
X172835D01*
G01Y569587D02*
X175984D01*
G01X172298Y586102D02*
Y584528D01*
G01X172669D02*
Y586102D01*
G01X172835Y567028D02*
Y565059D01*
G01Y567618D02*
Y569587D01*
G01X173228Y569882D02*
Y564764D01*
G01X173425D02*
Y569882D01*
G01X173991Y586102D02*
Y584528D01*
G01X174016Y586102D02*
Y584528D01*
G01X174050D02*
Y586102D01*
G01X174409Y564764D02*
Y565354D01*
G01Y569291D02*
Y569882D01*
G01Y566535D02*
Y568110D01*
G01X175984Y569587D02*
Y567618D01*
G01Y565059D02*
Y567028D01*
G01X179449Y579409D02*
Y605807D01*
G01X173425Y583740D02*
G03Y586890I0J1575D01*
G01X174409Y569291D02*
G03Y568110I0J-591D01*
G01Y566535D02*
G03Y565354I0J-591D01*
G01X168110Y564764D02*
X174409D01*
G01X169685Y565059D02*
X166535D01*
G01X168215Y565535D02*
X168121D01*
G01Y566283D02*
X168215D01*
G01X166535Y567028D02*
X169685D01*
G01X166535Y567618D02*
X169685D01*
G01Y569587D02*
X166535D01*
G01X174409Y569882D02*
X168110D01*
G01X179449Y579409D02*
X163071D01*
G01X173425Y583740D02*
X169094D01*
G01X174050Y584528D02*
X168469D01*
G01X163071Y592343D02*
Y579409D01*
G01X166535Y569587D02*
Y567618D01*
G01Y565059D02*
Y567028D01*
G01X168028Y566044D02*
Y566172D01*
G01X168110Y569882D02*
Y569291D01*
G01Y568110D02*
Y566535D01*
G01Y565354D02*
Y564764D01*
G01X168121Y565535D02*
Y566156D01*
G01X168215Y566283D02*
Y565535D01*
G01X168469Y586102D02*
Y584528D01*
G01X168504D02*
Y586102D01*
G01X168528Y584528D02*
Y586102D01*
G01X169094Y564764D02*
Y569882D01*
G01X169291D02*
Y564764D01*
G01X169685Y567028D02*
Y565059D01*
G01Y567618D02*
Y569587D01*
G01X169851Y586102D02*
Y584528D01*
G01X170221D02*
Y586102D01*
G01X168028Y566172D02*
X168121Y566283D01*
G01Y566156D02*
X168028Y566044D01*
G01X169094Y586890D02*
G03Y583740I0J-1575D01*
G01X168110Y568110D02*
G03Y569291I0J590D01*
G01Y565354D02*
G03Y566535I0J590D01*
G01X174882Y664035D02*
Y680374D01*
G01Y682736D02*
Y699272D01*
G01Y701634D02*
Y718169D01*
G01X195106Y661673D02*
X172913D01*
G01X181102Y661693D02*
X199606D01*
G01Y664035D02*
X172913D01*
G01X200563Y668130D02*
X181102D01*
G01X199606Y680374D02*
X172913D01*
G01X199606Y682736D02*
X172913D01*
G01X199606Y699272D02*
X172913D01*
G01X199606Y701634D02*
X172913D01*
G01X174882Y661673D02*
Y642185D01*
G01X200563Y635827D02*
X181102D01*
G01X199606Y639823D02*
X172913D01*
G01X199606Y642165D02*
X181102D01*
G01X195106Y642185D02*
X172913D01*
G01X151378Y648386D02*
Y649173D01*
G01Y654685D02*
Y655472D01*
G01Y651535D02*
Y652323D01*
G01Y657835D02*
Y658622D01*
G01Y664134D02*
Y664921D01*
G01Y660984D02*
Y661772D01*
G01Y667283D02*
Y668071D01*
G01Y673583D02*
Y674370D01*
G01Y670433D02*
Y671220D01*
G01Y676732D02*
Y677520D01*
G01Y683031D02*
Y683819D01*
G01Y679882D02*
Y680669D01*
G01Y686181D02*
Y686969D01*
G01Y692480D02*
Y693268D01*
G01Y689331D02*
Y690118D01*
G01Y695630D02*
Y696417D01*
G01Y701929D02*
Y702717D01*
G01Y698780D02*
Y699567D01*
G01X153151Y648386D02*
Y649173D01*
G01Y654685D02*
Y655472D01*
G01Y651535D02*
Y652323D01*
G01Y657835D02*
Y658622D01*
G01Y664134D02*
Y664921D01*
G01Y660984D02*
Y661772D01*
G01Y667283D02*
Y668071D01*
G01Y673583D02*
Y674370D01*
G01Y670433D02*
Y671220D01*
G01Y676732D02*
Y677520D01*
G01Y683031D02*
Y683819D01*
G01Y679882D02*
Y680669D01*
G01Y686181D02*
Y686969D01*
G01Y692480D02*
Y693268D01*
G01Y689331D02*
Y690118D01*
G01Y695630D02*
Y696417D01*
G01Y701929D02*
Y702717D01*
G01Y698780D02*
Y699567D01*
G01X153340Y702717D02*
Y701929D01*
G01Y699567D02*
Y698780D01*
G01Y696417D02*
Y695630D01*
G01Y693268D02*
Y692480D01*
G01Y690118D02*
Y689331D01*
G01Y686969D02*
Y686181D01*
G01Y683819D02*
Y683031D01*
G01Y680669D02*
Y679882D01*
G01Y677520D02*
Y676732D01*
G01Y674370D02*
Y673583D01*
G01Y671220D02*
Y670433D01*
G01Y668071D02*
Y667283D01*
G01Y664921D02*
Y664134D01*
G01Y661772D02*
Y660984D01*
G01Y658622D02*
Y657835D01*
G01Y655472D02*
Y654685D01*
G01Y652323D02*
Y651535D01*
G01Y649173D02*
Y648386D01*
G01X156176Y702717D02*
Y701929D01*
G01Y699567D02*
Y698780D01*
G01Y696417D02*
Y695630D01*
G01Y693268D02*
Y692480D01*
G01Y690118D02*
Y689331D01*
G01Y686969D02*
Y686181D01*
G01Y683819D02*
Y683031D01*
G01Y680669D02*
Y679882D01*
G01Y677520D02*
Y676732D01*
G01Y674370D02*
Y673583D01*
G01Y671220D02*
Y670433D01*
G01Y668071D02*
Y667283D01*
G01Y664921D02*
Y664134D01*
G01Y661772D02*
Y660984D01*
G01Y658622D02*
Y657835D01*
G01Y655472D02*
Y654685D01*
G01Y652323D02*
Y651535D01*
G01Y649173D02*
Y648386D01*
G01X157118D02*
Y649173D01*
G01Y654685D02*
Y655472D01*
G01Y651535D02*
Y652323D01*
G01Y657835D02*
Y658622D01*
G01Y664134D02*
Y664921D01*
G01Y660984D02*
Y661772D01*
G01Y667283D02*
Y668071D01*
G01Y673583D02*
Y674370D01*
G01Y670433D02*
Y671220D01*
G01Y676732D02*
Y677520D01*
G01Y683031D02*
Y683819D01*
G01Y679882D02*
Y680669D01*
G01Y686181D02*
Y686969D01*
G01Y692480D02*
Y693268D01*
G01Y689331D02*
Y690118D01*
G01Y695630D02*
Y696417D01*
G01Y701929D02*
Y702717D01*
G01Y698780D02*
Y699567D01*
G01X158710Y648386D02*
Y649173D01*
G01Y654685D02*
Y655472D01*
G01Y651535D02*
Y652323D01*
G01Y657835D02*
Y658622D01*
G01Y664134D02*
Y664921D01*
G01Y660984D02*
Y661772D01*
G01Y667283D02*
Y668071D01*
G01Y673583D02*
Y674370D01*
G01Y670433D02*
Y671220D01*
G01Y676732D02*
Y677520D01*
G01Y683031D02*
Y683819D01*
G01Y679882D02*
Y680669D01*
G01Y686181D02*
Y686969D01*
G01Y692480D02*
Y693268D01*
G01Y689331D02*
Y690118D01*
G01Y695630D02*
Y696417D01*
G01Y701929D02*
Y702717D01*
G01Y698780D02*
Y699567D01*
G01X158857Y648386D02*
Y649173D01*
G01Y654685D02*
Y655472D01*
G01Y651535D02*
Y652323D01*
G01Y657835D02*
Y658622D01*
G01Y664134D02*
Y664921D01*
G01Y660984D02*
Y661772D01*
G01Y667283D02*
Y668071D01*
G01Y673583D02*
Y674370D01*
G01Y670433D02*
Y671220D01*
G01Y676732D02*
Y677520D01*
G01Y683031D02*
Y683819D01*
G01Y679882D02*
Y680669D01*
G01Y686181D02*
Y686969D01*
G01Y692480D02*
Y693268D01*
G01Y689331D02*
Y690118D01*
G01Y695630D02*
Y696417D01*
G01Y701929D02*
Y702717D01*
G01Y698780D02*
Y699567D01*
G01X159796Y701929D02*
Y699567D01*
G01Y698780D02*
Y696417D01*
G01Y695630D02*
Y693268D01*
G01Y692480D02*
Y690118D01*
G01Y689331D02*
Y686969D01*
G01Y686181D02*
Y683819D01*
G01Y683031D02*
Y680669D01*
G01Y679882D02*
Y677520D01*
G01Y676732D02*
Y674370D01*
G01Y673583D02*
Y671220D01*
G01Y670433D02*
Y668071D01*
G01Y667283D02*
Y664921D01*
G01Y664134D02*
Y661772D01*
G01Y660984D02*
Y658622D01*
G01Y657835D02*
Y655472D01*
G01Y654685D02*
Y652323D01*
G01Y651535D02*
Y649173D01*
G01Y648386D02*
Y646024D01*
G01X161524Y648386D02*
Y649173D01*
G01Y654685D02*
Y655472D01*
G01Y651535D02*
Y652323D01*
G01Y657835D02*
Y658622D01*
G01Y664134D02*
Y664921D01*
G01Y660984D02*
Y661772D01*
G01Y667283D02*
Y668071D01*
G01Y673583D02*
Y674370D01*
G01Y670433D02*
Y671220D01*
G01Y676732D02*
Y677520D01*
G01Y683031D02*
Y683819D01*
G01Y679882D02*
Y680669D01*
G01Y686181D02*
Y686969D01*
G01Y692480D02*
Y693268D01*
G01Y689331D02*
Y690118D01*
G01Y695630D02*
Y696417D01*
G01Y701929D02*
Y702717D01*
G01Y698780D02*
Y699567D01*
G01X161874Y646102D02*
Y648307D01*
G01Y655551D02*
Y657756D01*
G01X162205Y700217D02*
Y698642D01*
G01Y695217D02*
Y693642D01*
G01Y690217D02*
Y688642D01*
G01Y685217D02*
Y683642D01*
G01Y675217D02*
Y673642D01*
G01Y670217D02*
Y668642D01*
G01Y665217D02*
Y663642D01*
G01X163176Y702717D02*
Y701929D01*
G01Y699567D02*
Y698780D01*
G01Y696417D02*
Y695630D01*
G01Y693268D02*
Y692480D01*
G01Y690118D02*
Y689331D01*
G01Y686969D02*
Y686181D01*
G01Y683819D02*
Y683031D01*
G01Y680669D02*
Y679882D01*
G01Y677520D02*
Y676732D01*
G01Y674370D02*
Y673583D01*
G01Y671220D02*
Y670433D01*
G01Y668071D02*
Y667283D01*
G01Y664921D02*
Y664134D01*
G01Y661772D02*
Y660984D01*
G01Y658622D02*
Y657835D01*
G01Y655472D02*
Y654685D01*
G01Y652323D02*
Y651535D01*
G01Y649173D02*
Y648386D01*
G01X163331Y648307D02*
Y655551D01*
G01Y657756D02*
Y661575D01*
G01X163739Y657244D02*
Y656063D01*
G01Y660394D02*
Y659213D01*
G01Y654094D02*
Y652913D01*
G01Y650945D02*
Y649764D01*
G01Y647795D02*
Y646614D01*
G01X163757Y657756D02*
Y655551D01*
G01Y648307D02*
Y646102D01*
G01X164173Y680217D02*
Y678642D01*
G01X165159Y702717D02*
Y701929D01*
G01Y699567D02*
Y698780D01*
G01Y696417D02*
Y695630D01*
G01Y693268D02*
Y692480D01*
G01Y690118D02*
Y689331D01*
G01Y686969D02*
Y686181D01*
G01Y683819D02*
Y683031D01*
G01Y680669D02*
Y679882D01*
G01Y677520D02*
Y676732D01*
G01Y674370D02*
Y673583D01*
G01Y671220D02*
Y670433D01*
G01Y668071D02*
Y667283D01*
G01Y664921D02*
Y664134D01*
G01Y661772D02*
Y660984D01*
G01Y658622D02*
Y657835D01*
G01Y655472D02*
Y654685D01*
G01Y652323D02*
Y651535D01*
G01Y649173D02*
Y648386D01*
G01X165354Y700217D02*
Y698642D01*
G01Y695217D02*
Y693642D01*
G01Y690217D02*
Y688642D01*
G01Y685217D02*
Y683642D01*
G01Y675217D02*
Y673642D01*
G01Y670217D02*
Y668642D01*
G01Y665217D02*
Y663642D01*
G01X166339Y701004D02*
Y697854D01*
G01Y696004D02*
Y692854D01*
G01Y691004D02*
Y687854D01*
G01Y686004D02*
Y682854D01*
G01Y676004D02*
Y672854D01*
G01Y671004D02*
Y667854D01*
G01Y666004D02*
Y662854D01*
G01X166888Y657244D02*
Y656063D01*
G01Y660394D02*
Y659213D01*
G01Y654094D02*
Y652913D01*
G01Y650945D02*
Y649764D01*
G01Y647795D02*
Y646614D01*
G01X167323Y701004D02*
Y697854D01*
G01Y696004D02*
Y692854D01*
G01Y691004D02*
Y687854D01*
G01Y686004D02*
Y682854D01*
G01Y680217D02*
Y678642D01*
G01Y676004D02*
Y672854D01*
G01Y671004D02*
Y667854D01*
G01Y666004D02*
Y662854D01*
G01X168307Y700217D02*
Y698642D01*
G01Y695217D02*
Y693642D01*
G01Y690217D02*
Y688642D01*
G01Y685217D02*
Y683642D01*
G01Y681004D02*
Y677854D01*
G01Y675217D02*
Y673642D01*
G01Y670217D02*
Y668642D01*
G01Y665217D02*
Y663642D01*
G01X168521Y648386D02*
Y649173D01*
G01Y654685D02*
Y655472D01*
G01Y651535D02*
Y652323D01*
G01Y657835D02*
Y658622D01*
G01Y664134D02*
Y664921D01*
G01Y660984D02*
Y661772D01*
G01Y667283D02*
Y668071D01*
G01Y673583D02*
Y674370D01*
G01Y670433D02*
Y671220D01*
G01Y676732D02*
Y677520D01*
G01Y683031D02*
Y683819D01*
G01Y679882D02*
Y680669D01*
G01Y686181D02*
Y686969D01*
G01Y692480D02*
Y693268D01*
G01Y689331D02*
Y690118D01*
G01Y695630D02*
Y696417D01*
G01Y701929D02*
Y702717D01*
G01Y698780D02*
Y699567D01*
G01X168857Y660984D02*
Y658622D01*
G01Y657835D02*
Y655472D01*
G01Y654685D02*
Y652323D01*
G01Y651535D02*
Y649173D01*
G01Y648386D02*
Y646024D01*
G01X168898Y648386D02*
Y649173D01*
G01Y654685D02*
Y655472D01*
G01Y651535D02*
Y652323D01*
G01Y657835D02*
Y658622D01*
G01Y664134D02*
Y664921D01*
G01Y660984D02*
Y661772D01*
G01Y667283D02*
Y668071D01*
G01Y673583D02*
Y674370D01*
G01Y670433D02*
Y671220D01*
G01Y676732D02*
Y677520D01*
G01Y683031D02*
Y683819D01*
G01Y679882D02*
Y680669D01*
G01Y686181D02*
Y686969D01*
G01Y692480D02*
Y693268D01*
G01Y689331D02*
Y690118D01*
G01Y695630D02*
Y696417D01*
G01Y701929D02*
Y702717D01*
G01Y698780D02*
Y699567D01*
G01X168924Y648386D02*
Y649173D01*
G01Y654685D02*
Y655472D01*
G01Y651535D02*
Y652323D01*
G01Y657835D02*
Y658622D01*
G01Y664134D02*
Y664921D01*
G01Y660984D02*
Y661772D01*
G01Y667283D02*
Y668071D01*
G01Y673583D02*
Y674370D01*
G01Y670433D02*
Y671220D01*
G01Y676732D02*
Y677520D01*
G01Y683031D02*
Y683819D01*
G01Y679882D02*
Y680669D01*
G01Y686181D02*
Y686969D01*
G01Y692480D02*
Y693268D01*
G01Y689331D02*
Y690118D01*
G01Y695630D02*
Y696417D01*
G01Y701929D02*
Y702717D01*
G01Y698780D02*
Y699567D01*
G01X169291Y681004D02*
Y677854D01*
G01X170866Y646024D02*
X158857D01*
G01X158710D02*
X151378D01*
G01X161874Y646102D02*
X163757D01*
G01X168857Y646220D02*
X167872D01*
G01X168857Y646417D02*
X167872D01*
G01X169764Y646614D02*
X163739D01*
G01X169764Y647795D02*
X163739D01*
G01X168857Y647992D02*
X167872D01*
G01X168857Y648189D02*
X167872D01*
G01X163757Y648307D02*
X161874D01*
G01X151378Y648386D02*
X158710D01*
G01X158857D02*
X170866D01*
G01Y649173D02*
X158857D01*
G01X158710D02*
X151378D01*
G01X168857Y649370D02*
X167872D01*
G01X168857Y649567D02*
X167872D01*
G01X169764Y649764D02*
X163739D01*
G01X169764Y650945D02*
X163739D01*
G01X168857Y651142D02*
X167872D01*
G01X168857Y651339D02*
X167872D01*
G01X151378Y651535D02*
X158710D01*
G01X158857D02*
X170866D01*
G01Y652323D02*
X158857D01*
G01X158710D02*
X151378D01*
G01X168857Y652520D02*
X167872D01*
G01X168857Y652717D02*
X167872D01*
G01X169764Y652913D02*
X163739D01*
G01X169764Y654094D02*
X163739D01*
G01X168857Y654291D02*
X167872D01*
G01X168857Y654488D02*
X167872D01*
G01X151378Y654685D02*
X158710D01*
G01X158857D02*
X170866D01*
G01Y655472D02*
X158857D01*
G01X158710D02*
X151378D01*
G01X161874Y655551D02*
X163757D01*
G01X168857Y655669D02*
X167872D01*
G01X168857Y655866D02*
X167872D01*
G01X169764Y656063D02*
X163739D01*
G01X169764Y657244D02*
X163739D01*
G01X168857Y657441D02*
X167872D01*
G01X168857Y657638D02*
X167872D01*
G01X163757Y657756D02*
X161874D01*
G01X151378Y657835D02*
X158710D01*
G01X158857D02*
X170866D01*
G01Y658622D02*
X158857D01*
G01X158710D02*
X151378D01*
G01X168857Y658819D02*
X167872D01*
G01X168857Y659016D02*
X167872D01*
G01X169764Y659213D02*
X163739D01*
G01X169764Y660394D02*
X163739D01*
G01X168857Y660591D02*
X167872D01*
G01X168857Y660787D02*
X167872D01*
G01X151378Y660984D02*
X158710D01*
G01X158857D02*
X170866D01*
G01X167872Y661083D02*
X165748D01*
G01X170866Y661575D02*
X163331D01*
G01X170866Y661693D02*
X169764D01*
G01X170866Y661772D02*
X158857D01*
G01X158710D02*
X151378D01*
G01X167323Y662854D02*
X166339D01*
G01X167323Y663051D02*
X166339D01*
G01X167323Y663445D02*
X166339D01*
G01X162205Y663642D02*
X169370D01*
G01X151378Y664134D02*
X158710D01*
G01X158857D02*
X170866D01*
G01Y664921D02*
X158857D01*
G01X158710D02*
X151378D01*
G01X162205Y665217D02*
X169370D01*
G01X167323Y665413D02*
X166339D01*
G01X167323Y665807D02*
X166339D01*
G01X167323Y666004D02*
X166339D01*
G01X151378Y667283D02*
X158710D01*
G01X158857D02*
X170866D01*
G01X167323Y667854D02*
X166339D01*
G01X167323Y668051D02*
X166339D01*
G01X170866Y668071D02*
X158857D01*
G01X158710D02*
X151378D01*
G01X167323Y668445D02*
X166339D01*
G01X162205Y668642D02*
X169370D01*
G01X162205Y670217D02*
X169370D01*
G01X167323Y670413D02*
X166339D01*
G01X151378Y670433D02*
X158710D01*
G01X158857D02*
X170866D01*
G01X167323Y670807D02*
X166339D01*
G01X167323Y671004D02*
X166339D01*
G01X170866Y671220D02*
X158857D01*
G01X158710D02*
X151378D01*
G01X167323Y672854D02*
X166339D01*
G01X167323Y673051D02*
X166339D01*
G01X167323Y673445D02*
X166339D01*
G01X151378Y673583D02*
X158710D01*
G01X158857D02*
X170866D01*
G01X162205Y673642D02*
X169370D01*
G01X170866Y674370D02*
X158857D01*
G01X158710D02*
X151378D01*
G01X162205Y675217D02*
X169370D01*
G01X167323Y675413D02*
X166339D01*
G01X167323Y675807D02*
X166339D01*
G01X167323Y676004D02*
X166339D01*
G01X151378Y676732D02*
X158710D01*
G01X158857D02*
X170866D01*
G01Y677224D02*
X169764D01*
G01X170866Y677520D02*
X158857D01*
G01X158710D02*
X151378D01*
G01X169291Y677854D02*
X168307D01*
G01X169291Y678051D02*
X168307D01*
G01X169291Y678445D02*
X168307D01*
G01X169764Y678642D02*
X164173D01*
G01X151378Y679882D02*
X158710D01*
G01X158857D02*
X170866D01*
G01X169764Y680217D02*
X164173D01*
G01X169291Y680413D02*
X168307D01*
G01X170866Y680669D02*
X158857D01*
G01X158710D02*
X151378D01*
G01X169291Y680807D02*
X168307D01*
G01X169291Y681004D02*
X168307D01*
G01X169764Y681634D02*
X170866D01*
G01X167323Y682854D02*
X166339D01*
G01X151378Y683031D02*
X158710D01*
G01X158857D02*
X170866D01*
G01X167323Y683051D02*
X166339D01*
G01X167323Y683445D02*
X166339D01*
G01X162205Y683642D02*
X169370D01*
G01X170866Y683819D02*
X158857D01*
G01X158710D02*
X151378D01*
G01X162205Y685217D02*
X169370D01*
G01X167323Y685413D02*
X166339D01*
G01X167323Y685807D02*
X166339D01*
G01X167323Y686004D02*
X166339D01*
G01X151378Y686181D02*
X158710D01*
G01X158857D02*
X170866D01*
G01Y686969D02*
X158857D01*
G01X158710D02*
X151378D01*
G01X167323Y687854D02*
X166339D01*
G01X167323Y688051D02*
X166339D01*
G01X167323Y688445D02*
X166339D01*
G01X162205Y688642D02*
X169370D01*
G01X151378Y689331D02*
X158710D01*
G01X158857D02*
X170866D01*
G01Y690118D02*
X158857D01*
G01X158710D02*
X151378D01*
G01X162205Y690217D02*
X169370D01*
G01X167323Y690413D02*
X166339D01*
G01X167323Y690807D02*
X166339D01*
G01X167323Y691004D02*
X166339D01*
G01X151378Y692480D02*
X158710D01*
G01X158857D02*
X170866D01*
G01X167323Y692854D02*
X166339D01*
G01X167323Y693051D02*
X166339D01*
G01X170866Y693268D02*
X158857D01*
G01X158710D02*
X151378D01*
G01X167323Y693445D02*
X166339D01*
G01X162205Y693642D02*
X169370D01*
G01X162205Y695217D02*
X169370D01*
G01X167323Y695413D02*
X166339D01*
G01X151378Y695630D02*
X158710D01*
G01X158857D02*
X170866D01*
G01X167323Y695807D02*
X166339D01*
G01X167323Y696004D02*
X166339D01*
G01X170866Y696417D02*
X158857D01*
G01X158710D02*
X151378D01*
G01X167323Y697854D02*
X166339D01*
G01X167323Y698051D02*
X166339D01*
G01X167323Y698445D02*
X166339D01*
G01X162205Y698642D02*
X169370D01*
G01X151378Y698780D02*
X158710D01*
G01X158857D02*
X170866D01*
G01Y699567D02*
X158857D01*
G01X158710D02*
X151378D01*
G01X162205Y700217D02*
X169370D01*
G01X167323Y700413D02*
X166339D01*
G01X167323Y700807D02*
X166339D01*
G01X167323Y701004D02*
X166339D01*
G01X151378Y701929D02*
X158710D01*
G01X158857D02*
X170866D01*
G01X169764Y663248D02*
G03X169370Y663642I-394J0D01*
G01Y665217D02*
G03X169764Y665610I0J394D01*
G01Y688248D02*
G03X169370Y688642I-394J0D01*
G01Y690217D02*
G03X169764Y690610I0J394D01*
G01Y698248D02*
G03X169370Y698642I-394J0D01*
G01Y700217D02*
G03X169764Y700610I0J394D01*
G01Y693248D02*
G03X169370Y693642I-394J0D01*
G01Y695217D02*
G03X169764Y695610I0J394D01*
G01Y673248D02*
G03X169370Y673642I-394J0D01*
G01Y675217D02*
G03X169764Y675610I0J394D01*
G01Y668248D02*
G03X169370Y668642I-394J0D01*
G01Y670217D02*
G03X169764Y670610I0J394D01*
G01Y683248D02*
G03X169370Y683642I-394J0D01*
G01Y685217D02*
G03X169764Y685610I0J394D01*
G01X151378Y635787D02*
Y636575D01*
G01Y632638D02*
Y633425D01*
G01Y638937D02*
Y639724D01*
G01Y645236D02*
Y646024D01*
G01Y642087D02*
Y642874D01*
G01X153151Y635787D02*
Y636575D01*
G01Y632638D02*
Y633425D01*
G01Y638937D02*
Y639724D01*
G01Y645236D02*
Y646024D01*
G01Y642087D02*
Y642874D01*
G01X153340Y646024D02*
Y645236D01*
G01Y642874D02*
Y642087D01*
G01Y639724D02*
Y638937D01*
G01Y636575D02*
Y635787D01*
G01Y633425D02*
Y632638D01*
G01X156176Y646024D02*
Y645236D01*
G01Y642874D02*
Y642087D01*
G01Y639724D02*
Y638937D01*
G01Y636575D02*
Y635787D01*
G01Y633425D02*
Y632638D01*
G01X157118Y635787D02*
Y636575D01*
G01Y632638D02*
Y633425D01*
G01Y638937D02*
Y639724D01*
G01Y645236D02*
Y646024D01*
G01Y642087D02*
Y642874D01*
G01X158710Y635787D02*
Y636575D01*
G01Y632638D02*
Y633425D01*
G01Y638937D02*
Y639724D01*
G01Y645236D02*
Y646024D01*
G01Y642087D02*
Y642874D01*
G01X158857Y635787D02*
Y636575D01*
G01Y632638D02*
Y633425D01*
G01Y638937D02*
Y639724D01*
G01Y645236D02*
Y646024D01*
G01Y642087D02*
Y642874D01*
G01X159796Y645236D02*
Y642874D01*
G01Y642087D02*
Y639724D01*
G01Y638937D02*
Y636575D01*
G01Y635787D02*
Y633425D01*
G01Y632638D02*
Y630276D01*
G01X161524Y635787D02*
Y636575D01*
G01Y632638D02*
Y633425D01*
G01Y638937D02*
Y639724D01*
G01Y645236D02*
Y646024D01*
G01Y642087D02*
Y642874D01*
G01X162205Y640217D02*
Y638642D01*
G01Y635217D02*
Y633642D01*
G01X163176Y646024D02*
Y645236D01*
G01Y642874D02*
Y642087D01*
G01Y639724D02*
Y638937D01*
G01Y636575D02*
Y635787D01*
G01Y633425D02*
Y632638D01*
G01X163331Y642283D02*
Y646102D01*
G01X163739Y644646D02*
Y643465D01*
G01X163809Y642283D02*
Y661575D01*
G01X165159Y646024D02*
Y645236D01*
G01Y642874D02*
Y642087D01*
G01Y639724D02*
Y638937D01*
G01Y636575D02*
Y635787D01*
G01Y633425D02*
Y632638D01*
G01X165354Y640217D02*
Y638642D01*
G01Y635217D02*
Y633642D01*
G01X166339Y641004D02*
Y637854D01*
G01Y636004D02*
Y632854D01*
G01X166888Y644646D02*
Y643465D01*
G01X167165Y642283D02*
Y661575D01*
G01X167323Y641004D02*
Y637854D01*
G01Y636004D02*
Y632854D01*
G01X167872Y642776D02*
Y661083D01*
G01X168082Y661575D02*
Y642283D01*
G01X168307Y640217D02*
Y638642D01*
G01Y635217D02*
Y633642D01*
G01X168521Y635787D02*
Y636575D01*
G01Y632638D02*
Y633425D01*
G01Y638937D02*
Y639724D01*
G01Y645236D02*
Y646024D01*
G01Y642087D02*
Y642874D01*
G01X168583Y661575D02*
Y642283D01*
G01X168857Y645236D02*
Y642874D01*
G01X168898Y635787D02*
Y636575D01*
G01Y632638D02*
Y633425D01*
G01Y638937D02*
Y639724D01*
G01Y645236D02*
Y646024D01*
G01Y642087D02*
Y642874D01*
G01X168924Y635787D02*
Y636575D01*
G01Y632638D02*
Y633425D01*
G01Y638937D02*
Y639724D01*
G01Y645236D02*
Y646024D01*
G01Y642087D02*
Y642874D01*
G01X169370Y642283D02*
Y661575D01*
G01X169685D02*
Y642283D01*
G01X162205Y630217D02*
X169370D01*
G01X170866Y630276D02*
X158857D01*
G01X158710D02*
X151378D01*
G01X167323Y630413D02*
X166339D01*
G01X167323Y630807D02*
X166339D01*
G01X167323Y631004D02*
X166339D01*
G01X151378Y632638D02*
X158710D01*
G01X158857D02*
X170866D01*
G01X167323Y632854D02*
X166339D01*
G01X167323Y633051D02*
X166339D01*
G01X170866Y633425D02*
X158857D01*
G01X158710D02*
X151378D01*
G01X167323Y633445D02*
X166339D01*
G01X162205Y633642D02*
X169370D01*
G01X162205Y635217D02*
X169370D01*
G01X167323Y635413D02*
X166339D01*
G01X151378Y635787D02*
X158710D01*
G01X158857D02*
X170866D01*
G01X167323Y635807D02*
X166339D01*
G01X167323Y636004D02*
X166339D01*
G01X170866Y636575D02*
X158857D01*
G01X158710D02*
X151378D01*
G01X167323Y637854D02*
X166339D01*
G01X167323Y638051D02*
X166339D01*
G01X167323Y638445D02*
X166339D01*
G01X162205Y638642D02*
X169370D01*
G01X151378Y638937D02*
X158710D01*
G01X158857D02*
X170866D01*
G01Y639724D02*
X158857D01*
G01X158710D02*
X151378D01*
G01X162205Y640217D02*
X169370D01*
G01X167323Y640413D02*
X166339D01*
G01X167323Y640807D02*
X166339D01*
G01X167323Y641004D02*
X166339D01*
G01X151378Y642087D02*
X158710D01*
G01X158857D02*
X170866D01*
G01Y642165D02*
X169764D01*
G01X163331Y642283D02*
X170866D01*
G01X167872Y642776D02*
X165748D01*
G01X170866Y642874D02*
X158857D01*
G01X158710D02*
X151378D01*
G01X168857Y643071D02*
X167872D01*
G01X168857Y643268D02*
X167872D01*
G01X169764Y643465D02*
X163739D01*
G01X169764Y644646D02*
X163739D01*
G01X168857Y644843D02*
X167872D01*
G01X168857Y645039D02*
X167872D01*
G01X151378Y645236D02*
X158710D01*
G01X158857D02*
X170866D01*
G01X169370Y630217D02*
G03X169764Y630610I0J394D01*
G01Y633248D02*
G03X169370Y633642I-394J0D01*
G01Y635217D02*
G03X169764Y635610I0J394D01*
G01Y638248D02*
G03X169370Y638642I-394J0D01*
G01Y640217D02*
G03X169764Y640610I0J394D01*
G01X149606Y751516D02*
Y737638D01*
G01X149924Y743169D02*
Y737638D01*
G01X150399Y740413D02*
Y737638D01*
G01X149606D02*
X169764D01*
G01X150399Y740413D02*
X170866D01*
G01X149606Y741398D02*
X173228D01*
G01X199606Y743169D02*
X149606D01*
G01X173228Y743799D02*
X149606D01*
G01X173228Y745768D02*
X149606D01*
G01X173228Y749547D02*
X149606D01*
G01Y751516D02*
X203543D01*
G01X173228Y743799D02*
Y741398D01*
G01X174882Y720531D02*
Y738051D01*
G01X177165Y751516D02*
Y743169D01*
G01X179134Y739232D02*
Y737461D01*
G01X179449Y738051D02*
Y764449D01*
G01X199606Y718169D02*
X172913D01*
G01X199606Y720531D02*
X172913D01*
G01X179449Y738051D02*
X172913D01*
G01X199606Y738248D02*
X181102D01*
G01X163962Y744016D02*
X163980Y743960D01*
X164032Y743794D01*
X164111Y743536D01*
X164207Y743208D01*
X164311Y742835D01*
G01X151378Y711378D02*
Y712165D01*
G01Y708228D02*
Y709016D01*
G01Y714528D02*
Y715315D01*
G01Y720827D02*
Y721614D01*
G01Y717677D02*
Y718465D01*
G01Y723976D02*
Y724764D01*
G01Y730276D02*
Y731063D01*
G01Y727126D02*
Y727913D01*
G01Y733425D02*
Y734213D01*
G01X153151Y711378D02*
Y712165D01*
G01Y708228D02*
Y709016D01*
G01Y714528D02*
Y715315D01*
G01Y720827D02*
Y721614D01*
G01Y717677D02*
Y718465D01*
G01Y723976D02*
Y724764D01*
G01Y730276D02*
Y731063D01*
G01Y727126D02*
Y727913D01*
G01Y733425D02*
Y734213D01*
G01X153340D02*
Y733425D01*
G01Y731063D02*
Y730276D01*
G01Y727913D02*
Y727126D01*
G01Y724764D02*
Y723976D01*
G01Y721614D02*
Y720827D01*
G01Y718465D02*
Y717677D01*
G01Y715315D02*
Y714528D01*
G01Y712165D02*
Y711378D01*
G01Y709016D02*
Y708228D01*
G01X156176Y734213D02*
Y733425D01*
G01Y731063D02*
Y730276D01*
G01Y727913D02*
Y727126D01*
G01Y724764D02*
Y723976D01*
G01Y721614D02*
Y720827D01*
G01Y718465D02*
Y717677D01*
G01Y715315D02*
Y714528D01*
G01Y712165D02*
Y711378D01*
G01Y709016D02*
Y708228D01*
G01X156253Y740413D02*
Y743169D01*
G01X157118Y711378D02*
Y712165D01*
G01Y708228D02*
Y709016D01*
G01Y714528D02*
Y715315D01*
G01Y720827D02*
Y721614D01*
G01Y717677D02*
Y718465D01*
G01Y723976D02*
Y724764D01*
G01Y730276D02*
Y731063D01*
G01Y727126D02*
Y727913D01*
G01Y733425D02*
Y734213D01*
G01X158710Y711378D02*
Y712165D01*
G01Y708228D02*
Y709016D01*
G01Y714528D02*
Y715315D01*
G01Y720827D02*
Y721614D01*
G01Y717677D02*
Y718465D01*
G01Y723976D02*
Y724764D01*
G01Y730276D02*
Y731063D01*
G01Y727126D02*
Y727913D01*
G01Y733425D02*
Y734213D01*
G01X158857Y711378D02*
Y712165D01*
G01Y708228D02*
Y709016D01*
G01Y714528D02*
Y715315D01*
G01Y720827D02*
Y721614D01*
G01Y717677D02*
Y718465D01*
G01Y723976D02*
Y724764D01*
G01Y730276D02*
Y731063D01*
G01Y727126D02*
Y727913D01*
G01Y733425D02*
Y734213D01*
G01X159796Y735886D02*
Y734213D01*
G01Y733425D02*
Y731063D01*
G01Y730276D02*
Y727913D01*
G01Y727126D02*
Y724764D01*
G01Y723976D02*
Y721614D01*
G01Y720827D02*
Y718465D01*
G01Y717677D02*
Y715315D01*
G01Y714528D02*
Y712165D01*
G01Y711378D02*
Y709016D01*
G01Y708228D02*
Y705866D01*
G01X161012Y750114D02*
Y744360D01*
G01X161524Y711378D02*
Y712165D01*
G01Y708228D02*
Y709016D01*
G01Y714528D02*
Y715315D01*
G01Y720827D02*
Y721614D01*
G01Y717677D02*
Y718465D01*
G01Y723976D02*
Y724764D01*
G01Y730276D02*
Y731063D01*
G01Y727126D02*
Y727913D01*
G01Y733425D02*
Y734213D01*
G01X162205Y735217D02*
Y733642D01*
G01Y730217D02*
Y728642D01*
G01Y725217D02*
Y723642D01*
G01Y715217D02*
Y713642D01*
G01Y710217D02*
Y708642D01*
G01X162472Y750114D02*
Y744360D01*
G01X163176Y734213D02*
Y733425D01*
G01Y731063D02*
Y730276D01*
G01Y727913D02*
Y727126D01*
G01Y724764D02*
Y723976D01*
G01Y721614D02*
Y720827D01*
G01Y718465D02*
Y717677D01*
G01Y715315D02*
Y714528D01*
G01Y712165D02*
Y711378D01*
G01Y709016D02*
Y708228D01*
G01X164127Y740413D02*
Y743169D01*
G01X164173Y720217D02*
Y718642D01*
G01X164766Y740866D02*
Y740807D01*
G01X165159Y734213D02*
Y733425D01*
G01Y731063D02*
Y730276D01*
G01Y727913D02*
Y727126D01*
G01Y724764D02*
Y723976D01*
G01Y721614D02*
Y720827D01*
G01Y718465D02*
Y717677D01*
G01Y715315D02*
Y714528D01*
G01Y712165D02*
Y711378D01*
G01Y709016D02*
Y708228D01*
G01X165354Y735217D02*
Y733642D01*
G01Y730217D02*
Y728642D01*
G01Y725217D02*
Y723642D01*
G01Y715217D02*
Y713642D01*
G01Y710217D02*
Y708642D01*
G01X166339Y736004D02*
Y732854D01*
G01Y731004D02*
Y727854D01*
G01Y726004D02*
Y722854D01*
G01Y716004D02*
Y712854D01*
G01Y711004D02*
Y707854D01*
G01X167323Y743169D02*
Y740866D01*
G01Y736004D02*
Y732854D01*
G01Y731004D02*
Y727854D01*
G01Y726004D02*
Y722854D01*
G01Y720217D02*
Y718642D01*
G01Y716004D02*
Y712854D01*
G01Y711004D02*
Y707854D01*
G01X168307Y735217D02*
Y733642D01*
G01Y730217D02*
Y728642D01*
G01Y725217D02*
Y723642D01*
G01Y721004D02*
Y717854D01*
G01Y715217D02*
Y713642D01*
G01Y710217D02*
Y708642D01*
G01X168521Y711378D02*
Y712165D01*
G01Y708228D02*
Y709016D01*
G01Y714528D02*
Y715315D01*
G01Y720827D02*
Y721614D01*
G01Y717677D02*
Y718465D01*
G01Y723976D02*
Y724764D01*
G01Y730276D02*
Y731063D01*
G01Y727126D02*
Y727913D01*
G01Y733425D02*
Y734213D01*
G01X168898Y711378D02*
Y712165D01*
G01Y708228D02*
Y709016D01*
G01Y714528D02*
Y715315D01*
G01Y720827D02*
Y721614D01*
G01Y717677D02*
Y718465D01*
G01Y723976D02*
Y724764D01*
G01Y730276D02*
Y731063D01*
G01Y727126D02*
Y727913D01*
G01Y733425D02*
Y734213D01*
G01X168924Y711378D02*
Y712165D01*
G01Y708228D02*
Y709016D01*
G01Y714528D02*
Y715315D01*
G01Y720827D02*
Y721614D01*
G01Y717677D02*
Y718465D01*
G01Y723976D02*
Y724764D01*
G01Y730276D02*
Y731063D01*
G01Y727126D02*
Y727913D01*
G01Y733425D02*
Y734213D01*
G01X169291Y721004D02*
Y717854D01*
G01X160054Y744016D02*
X160035Y743960D01*
X159983Y743794D01*
X159905Y743536D01*
X159809Y743209D01*
X159704Y742835D01*
G01X167323Y705413D02*
X166339D01*
G01X167323Y705807D02*
X166339D01*
G01X170866Y705866D02*
X158857D01*
G01X158710D02*
X151378D01*
G01X167323Y706004D02*
X166339D01*
G01X167323Y707854D02*
X166339D01*
G01X167323Y708051D02*
X166339D01*
G01X151378Y708228D02*
X158710D01*
G01X158857D02*
X170866D01*
G01X167323Y708445D02*
X166339D01*
G01X162205Y708642D02*
X169370D01*
G01X170866Y709016D02*
X158857D01*
G01X158710D02*
X151378D01*
G01X162205Y710217D02*
X169370D01*
G01X167323Y710413D02*
X166339D01*
G01X167323Y710807D02*
X166339D01*
G01X167323Y711004D02*
X166339D01*
G01X151378Y711378D02*
X158710D01*
G01X158857D02*
X170866D01*
G01Y712165D02*
X158857D01*
G01X158710D02*
X151378D01*
G01X167323Y712854D02*
X166339D01*
G01X167323Y713051D02*
X166339D01*
G01X167323Y713445D02*
X166339D01*
G01X162205Y713642D02*
X169370D01*
G01X151378Y714528D02*
X158710D01*
G01X158857D02*
X170866D01*
G01X162205Y715217D02*
X169370D01*
G01X170866Y715315D02*
X158857D01*
G01X158710D02*
X151378D01*
G01X167323Y715413D02*
X166339D01*
G01X167323Y715807D02*
X166339D01*
G01X167323Y716004D02*
X166339D01*
G01X170866Y717224D02*
X169764D01*
G01X151378Y717677D02*
X158710D01*
G01X158857D02*
X170866D01*
G01X169291Y717854D02*
X168307D01*
G01X169291Y718051D02*
X168307D01*
G01X169291Y718445D02*
X168307D01*
G01X170866Y718465D02*
X158857D01*
G01X158710D02*
X151378D01*
G01X169764Y718642D02*
X164173D01*
G01X169764Y720217D02*
X164173D01*
G01X169291Y720413D02*
X168307D01*
G01X169291Y720807D02*
X168307D01*
G01X151378Y720827D02*
X158710D01*
G01X158857D02*
X170866D01*
G01X169291Y721004D02*
X168307D01*
G01X170866Y721614D02*
X158857D01*
G01X158710D02*
X151378D01*
G01X170866Y721634D02*
X169764D01*
G01X167323Y722854D02*
X166339D01*
G01X167323Y723051D02*
X166339D01*
G01X167323Y723445D02*
X166339D01*
G01X162205Y723642D02*
X169370D01*
G01X151378Y723976D02*
X158710D01*
G01X158857D02*
X170866D01*
G01Y724764D02*
X158857D01*
G01X158710D02*
X151378D01*
G01X162205Y725217D02*
X169370D01*
G01X167323Y725413D02*
X166339D01*
G01X167323Y725807D02*
X166339D01*
G01X167323Y726004D02*
X166339D01*
G01X151378Y727126D02*
X158710D01*
G01X158857D02*
X170866D01*
G01X167323Y727854D02*
X166339D01*
G01X170866Y727913D02*
X158857D01*
G01X158710D02*
X151378D01*
G01X167323Y728051D02*
X166339D01*
G01X167323Y728445D02*
X166339D01*
G01X162205Y728642D02*
X169370D01*
G01X162205Y730217D02*
X169370D01*
G01X151378Y730276D02*
X158710D01*
G01X158857D02*
X170866D01*
G01X167323Y730413D02*
X166339D01*
G01X167323Y730807D02*
X166339D01*
G01X167323Y731004D02*
X166339D01*
G01X170866Y731063D02*
X158857D01*
G01X158710D02*
X151378D01*
G01X167323Y732854D02*
X166339D01*
G01X167323Y733051D02*
X166339D01*
G01X151378Y733425D02*
X158710D01*
G01X158857D02*
X170866D01*
G01X167323Y733445D02*
X166339D01*
G01X162205Y733642D02*
X169370D01*
G01X170866Y734213D02*
X158857D01*
G01X158710D02*
X151378D01*
G01X162205Y735217D02*
X169370D01*
G01X167323Y735413D02*
X166339D01*
G01X167323Y735807D02*
X166339D01*
G01X165748Y735886D02*
X156763D01*
G01X167323Y736004D02*
X166339D01*
G01X169764Y737461D02*
X179134D01*
G01X201575Y738642D02*
X170866D01*
G01X169764Y739232D02*
X179134D01*
G01X164766Y740807D02*
X170866D01*
G01X164766Y740866D02*
X170866D01*
G01X159704Y742835D02*
X164311D01*
G01X163962Y744016D02*
X160054D01*
G01X162472Y744360D02*
X161012D01*
G01X164766Y740807D02*
X164511Y740413D01*
G01X159704Y750630D02*
G03Y742835I2304J-3898D01*
G01X164311D02*
G03Y750630I-2304J3897D01*
G01X165512Y746732D02*
G03I-3504J0D01*
G01X163962Y744016D02*
G03Y749449I-1954J2717D01*
G01X160054D02*
G03Y744016I1954J-2717D01*
G01X164173Y746732D02*
G03I-2165J0D01*
G01X169764Y708248D02*
G03X169370Y708642I-394J0D01*
G01Y710217D02*
G03X169764Y710610I0J394D01*
G01Y728248D02*
G03X169370Y728642I-394J0D01*
G01Y730217D02*
G03X169764Y730610I0J394D01*
G01Y723248D02*
G03X169370Y723642I-394J0D01*
G01Y725217D02*
G03X169764Y725610I0J394D01*
G01Y733248D02*
G03X169370Y733642I-394J0D01*
G01Y735217D02*
G03X169764Y735610I0J394D01*
G01Y713248D02*
G03X169370Y713642I-394J0D01*
G01Y715217D02*
G03X169764Y715610I0J394D01*
G01X172298Y759331D02*
Y757756D01*
G01X172554Y750114D02*
Y747589D01*
G01X172669Y757756D02*
Y759331D01*
G01X173228Y749547D02*
Y745768D01*
G01X173982Y746664D02*
Y746107D01*
G01X173984Y747589D02*
Y750114D01*
G01X173991Y759331D02*
Y757756D01*
G01X174016Y759331D02*
Y757756D01*
G01X174050D02*
Y759331D01*
G01X175424Y750114D02*
Y746107D01*
G01D02*
X173982D01*
G01X175424Y750114D02*
X173984D01*
G01X203543Y750335D02*
X177165D01*
G01X171201Y746658D02*
G03X173982Y746664I1388J1207D01*
G01X173425Y756969D02*
G03Y760118I0J1575D01*
G01X172554Y747589D02*
G03X173984I715J0D01*
G01X154398Y747967D02*
X155667Y746107D01*
G01X153444Y747093D02*
X154050Y746107D01*
G01X151347Y750114D02*
X152668Y747958D01*
G01X152896Y750114D02*
X153641Y748836D01*
G01X160054Y749449D02*
X160035Y749505D01*
X159983Y749670D01*
X159904Y749929D01*
X159809Y750256D01*
X159704Y750630D01*
G01X163071Y764449D02*
Y751516D01*
G01X168271Y750114D02*
Y747185D01*
G01X168469Y759331D02*
Y757756D01*
G01X168504D02*
Y759331D01*
G01X168528Y757756D02*
Y759331D01*
G01X169664Y750114D02*
Y747589D01*
G01X169851Y759331D02*
Y757756D01*
G01X170221D02*
Y759331D01*
G01X171094Y747589D02*
Y750114D01*
G01X164311Y750630D02*
X164208Y750261D01*
X164112Y749931D01*
X164032Y749669D01*
X163980Y749503D01*
X163962Y749449D01*
G01X155667Y746107D02*
X154050D01*
G01X152755D02*
X151373D01*
G01X158865Y747689D02*
X157440D01*
G01X158866Y748515D02*
X155867D01*
G01X157500Y748958D02*
X155997D01*
G01X160054Y749449D02*
X163962D01*
G01X169664Y750114D02*
X168271D01*
G01X172554D02*
X171094D01*
G01X162472D02*
X161012D01*
G01X155840D02*
X154432D01*
G01X152896D02*
X151347D01*
G01X164311Y750630D02*
X159704D01*
G01X179449Y754272D02*
X163071D01*
G01X173425Y756969D02*
X169094D01*
G01X174050Y757756D02*
X168469D01*
G01Y759331D02*
X174050D01*
G01X169094Y760118D02*
X173425D01*
G01X179449Y764449D02*
X163071D01*
G01X154432Y750114D02*
X153641Y748836D01*
G01X155840Y750114D02*
X154398Y747967D01*
G01X153444Y747093D02*
X152755Y746107D01*
G01X152668Y747958D02*
X151373Y746107D01*
G01X158425Y750313D02*
G03X156840Y750027I-264J-3073D01*
G01X157440Y747689D02*
G03X158865I713J-83D01*
G01X160247Y747280D02*
G03X160421Y747941I-4018J1411D01*
G01D02*
G03Y748438I-3524J249D01*
G01X155867Y748515D02*
G03X156206Y747072I3014J-53D01*
G01X160421Y748436D02*
G03X160159Y749299I-2971J-431D01*
G01X157440Y746098D02*
G03X159082Y746142I755J2476D01*
G01X160161Y749296D02*
G03X158422Y750314I-1807J-1093D01*
G01X159082Y746142D02*
G03X160247Y747280I-729J1911D01*
G01X156205Y747072D02*
G03X157439Y746098I1736J930D01*
G01X156840Y750027D02*
G03X155997Y748958I704J-1422D01*
G01X158865Y748515D02*
G03X158091Y749323I-792J16D01*
G01D02*
G03X157500Y748958I-9J-646D01*
G01X163771Y746460D02*
G03X166817Y746461I1522J2362D01*
G01X166816Y749905D02*
G03X163770Y749904I-1522J-2362D01*
G01X163249Y749338D02*
G03X163250Y747026I2163J-1155D01*
G01X167338D02*
G03X167337Y749340I-2163J1156D01*
G01X166065Y747320D02*
G03Y749005I-2236J842D01*
G01X166817Y746461D02*
G03X167338Y747026I-830J1288D01*
G01X163250D02*
G03X163771Y746461I1351J723D01*
G01X163770Y749903D02*
G03X163249Y749338I830J-1288D01*
G01X167337Y749340D02*
G03X166816Y749905I-1351J-723D01*
G01X164592Y747320D02*
G03X166065I737J278D01*
G01Y749005D02*
G03X164592I-737J-277D01*
G01D02*
G03Y747320I2236J-842D01*
G01X169094Y760118D02*
G03Y756969I0J-1574D01*
G01X168271Y747185D02*
G03X168565Y746514I913J0D01*
G01D02*
G03X171201Y746658I1248J1351D01*
G01X169664Y747589D02*
G03X171094I715J0D01*
G01X151378Y705079D02*
Y705866D01*
G01X153151Y705079D02*
Y705866D01*
G01X153340D02*
Y705079D01*
G01X156176Y705866D02*
Y705079D01*
G01X157118D02*
Y705866D01*
G01X158710Y705079D02*
Y705866D01*
G01X158857Y705079D02*
Y705866D01*
G01X159796Y705079D02*
Y702717D01*
G01X161524Y705079D02*
Y705866D01*
G01X162205Y705217D02*
Y703642D01*
G01X163176Y705866D02*
Y705079D01*
G01X165159Y705866D02*
Y705079D01*
G01X165354Y705217D02*
Y703642D01*
G01X166339Y706004D02*
Y702854D01*
G01X167323Y706004D02*
Y702854D01*
G01X168307Y705217D02*
Y703642D01*
G01X168521Y705079D02*
Y705866D01*
G01X168898Y705079D02*
Y705866D01*
G01X168924Y705079D02*
Y705866D01*
G01X170866Y702717D02*
X158857D01*
G01X158710D02*
X151378D01*
G01X167323Y702854D02*
X166339D01*
G01X167323Y703051D02*
X166339D01*
G01X167323Y703445D02*
X166339D01*
G01X162205Y703642D02*
X169370D01*
G01X151378Y705079D02*
X158710D01*
G01X158857D02*
X170866D01*
G01X162205Y705217D02*
X169370D01*
G01X169764Y703248D02*
G03X169370Y703642I-394J0D01*
G01Y705217D02*
G03X169764Y705610I0J394D01*
G01X172835Y972539D02*
Y970571D01*
G01Y973130D02*
Y975098D01*
G01X173228Y975394D02*
Y970276D01*
G01X173425D02*
Y975394D01*
G01X174409Y970276D02*
Y970866D01*
G01Y972047D02*
Y973622D01*
G01Y974803D02*
Y975394D01*
G01X175984Y975098D02*
Y973130D01*
G01Y970571D02*
Y972539D01*
G01X179449Y984921D02*
Y1011319D01*
G01X172835Y970571D02*
X175984D01*
G01Y972539D02*
X172835D01*
G01X175984Y973130D02*
X172835D01*
G01Y975098D02*
X175984D01*
G01X174409Y974803D02*
G03Y973622I0J-591D01*
G01Y972047D02*
G03Y970866I0J-590D01*
G01X163071Y997854D02*
Y984921D01*
G01X166535Y975098D02*
Y973130D01*
G01Y970571D02*
Y972539D01*
G01X168028Y971556D02*
Y971684D01*
G01X168110Y975394D02*
Y974803D01*
G01Y973622D02*
Y972047D01*
G01Y970866D02*
Y970276D01*
G01X168121Y971047D02*
Y971668D01*
G01X168215Y971795D02*
Y971047D01*
G01X169094Y970276D02*
Y975394D01*
G01X169291D02*
Y970276D01*
G01X169685Y972539D02*
Y970571D01*
G01Y973130D02*
Y975098D01*
G01X168028Y971684D02*
X168121Y971795D01*
G01Y971668D02*
X168028Y971556D01*
G01X168110Y970276D02*
X174409D01*
G01X169685Y970571D02*
X166535D01*
G01X168215Y971047D02*
X168121D01*
G01Y971795D02*
X168215D01*
G01X166535Y972539D02*
X169685D01*
G01X166535Y973130D02*
X169685D01*
G01Y975098D02*
X166535D01*
G01X174409Y975394D02*
X168110D01*
G01X179449Y984921D02*
X163071D01*
G01X168110Y973622D02*
G03Y974803I0J591D01*
G01Y970866D02*
G03Y972047I0J591D01*
G01X172298Y991614D02*
Y990039D01*
G01X172669D02*
Y991614D01*
G01X173991D02*
Y990039D01*
G01X174016Y991614D02*
Y990039D01*
G01X174050D02*
Y991614D01*
G01X173425Y989252D02*
G03Y992402I0J1575D01*
G01X168469Y991614D02*
Y990039D01*
G01X168504D02*
Y991614D01*
G01X168528Y990039D02*
Y991614D01*
G01X169851D02*
Y990039D01*
G01X170221D02*
Y991614D01*
G01X173425Y989252D02*
X169094D01*
G01X174050Y990039D02*
X168469D01*
G01Y991614D02*
X174050D01*
G01X169094Y992402D02*
X173425D01*
G01X169094D02*
G03Y989252I0J-1575D01*
G01X169764Y1065906D02*
X163739D01*
G01X168857Y1066102D02*
X167872D01*
G01X149924Y1011535D02*
Y1006201D01*
G01X150399Y1011535D02*
Y1008957D01*
G01X149606Y1005571D02*
X173228D01*
G01X199606Y1006201D02*
X149606D01*
G01X173228Y1008012D02*
X149606D01*
G01X150399Y1008957D02*
X170866D01*
G01X169764Y1011535D02*
X149606D01*
G01D02*
Y997854D01*
G01X203543D02*
X149606D01*
G01X173228Y999823D02*
X149606D01*
G01X173228Y1003602D02*
X149606D01*
G01X171831Y1014232D02*
Y1013806D01*
G01Y1016791D02*
Y1017303D01*
G01X172353Y1013806D02*
Y1014317D01*
G01X172789Y1014829D02*
Y1015341D01*
G01X172913Y1011319D02*
Y1143563D01*
G01X173228Y1008012D02*
Y1005571D01*
G01X173573Y1014317D02*
Y1013806D01*
G01X174096D02*
Y1014317D01*
G01X174793Y1012953D02*
Y1012441D01*
G01X174882Y1067185D02*
Y1047697D01*
G01Y1045335D02*
Y1030098D01*
G01Y1027736D02*
Y1011319D01*
G01X175402Y1014317D02*
Y1013635D01*
G01X175925Y1017303D02*
Y1016791D01*
G01Y1013635D02*
Y1014317D01*
G01X179134Y1011909D02*
Y1010138D01*
G01X181102Y1143760D02*
Y1011122D01*
G01X171918Y1014659D02*
X171831Y1014232D01*
G01X173660Y1014744D02*
X173573Y1014317D01*
G01X175838Y1013209D02*
X175925Y1013635D01*
G01X174096Y1014317D02*
X174183Y1014659D01*
G01X174009Y1013465D02*
X174096Y1013806D01*
G01X175402Y1013635D02*
X175315Y1013294D01*
G01X172353Y1014317D02*
X172441Y1014573D01*
G01X173573Y1013806D02*
X173486Y1013550D01*
G01X173834Y1015085D02*
X173660Y1014744D01*
G01X173834Y1013123D02*
X174009Y1013465D01*
G01X172441Y1013550D02*
X172353Y1013806D01*
G01X171831D02*
X171918Y1013465D01*
G01X175315Y1014659D02*
X175402Y1014317D01*
G01X175925D02*
X175838Y1014744D01*
G01X175577Y1012782D02*
X175838Y1013209D01*
G01X174183Y1014659D02*
X174357Y1014915D01*
G01X173486Y1013550D02*
X173311Y1013294D01*
G01X172179Y1015000D02*
X171918Y1014659D01*
G01X172441Y1014573D02*
X172615Y1014744D01*
G01X174183Y1015426D02*
X173834Y1015085D01*
G01X173486Y1012782D02*
X173834Y1013123D01*
G01X175315Y1013294D02*
X175054Y1013038D01*
G01X172092Y1013123D02*
X172441Y1012782D01*
G01X175664Y1015085D02*
X175315Y1015426D01*
G01X172615Y1013294D02*
X172441Y1013550D01*
G01X175141Y1014915D02*
X175315Y1014659D01*
G01X171918Y1013465D02*
X172092Y1013123D01*
G01X175838Y1014744D02*
X175664Y1015085D01*
G01X172528Y1015256D02*
X172179Y1015000D01*
G01X174357Y1014915D02*
X174618Y1015085D01*
G01X175141Y1012526D02*
X175577Y1012782D01*
G01X172615Y1014744D02*
X172789Y1014829D01*
G01X174531Y1015597D02*
X174183Y1015426D01*
G01X174880Y1015085D02*
X175141Y1014915D01*
G01X172441Y1016280D02*
X171831Y1016791D01*
G01X172528D02*
X173137Y1016280D01*
G01X172789Y1015341D02*
X172528Y1015256D01*
G01X173311Y1013294D02*
X173050Y1013209D01*
G01X175054Y1013038D02*
X174793Y1012953D01*
G01X172876Y1013209D02*
X172615Y1013294D01*
G01X175315Y1015426D02*
X174967Y1015597D01*
G01X172441Y1012782D02*
X172789Y1012697D01*
G01X199606Y1011122D02*
X181102D01*
G01X179449Y1011319D02*
X172913D01*
G01X172789Y1012697D02*
X173137D01*
G01X173050Y1013209D02*
X172876D01*
G01X174618Y1015085D02*
X174880D01*
G01X174967Y1015597D02*
X174531D01*
G01X173137Y1016280D02*
X172441D01*
G01X175925Y1016791D02*
X172528D01*
G01X171831Y1017303D02*
X175925D01*
G01X199606Y1027736D02*
X172913D01*
G01X199606Y1030098D02*
X172913D01*
G01X200563Y1041339D02*
X181102D01*
G01X199606Y1045335D02*
X172913D01*
G01X199606Y1047677D02*
X181102D01*
G01X195106Y1047697D02*
X172913D01*
G01X174793Y1012441D02*
X175141Y1012526D01*
G01X173137Y1012697D02*
X173486Y1012782D01*
G01X171690Y1004980D02*
Y1004242D01*
G01X173228Y1003602D02*
Y999823D01*
G01X175529Y1004316D02*
Y1004980D01*
G01X177165Y997854D02*
Y1006201D01*
G01Y999035D02*
X203543D01*
G01X172428Y999075D02*
X173314D01*
G01X171690Y1004242D02*
X174643D01*
G01X175529Y1004980D02*
X171690D01*
G01X175529Y1004316D02*
G03X173314Y999075I7141J-6107D01*
G01X174643Y1004242D02*
G03X172428Y999075I6937J-6032D01*
G01X151378Y1019252D02*
Y1020039D01*
G01Y1016102D02*
Y1016890D01*
G01Y1022402D02*
Y1023189D01*
G01Y1028701D02*
Y1029488D01*
G01Y1025551D02*
Y1026339D01*
G01Y1031850D02*
Y1032638D01*
G01Y1038150D02*
Y1038937D01*
G01Y1035000D02*
Y1035787D01*
G01Y1041299D02*
Y1042087D01*
G01Y1047598D02*
Y1048386D01*
G01Y1044449D02*
Y1045236D01*
G01Y1050748D02*
Y1051535D01*
G01Y1057047D02*
Y1057835D01*
G01Y1053898D02*
Y1054685D01*
G01Y1060197D02*
Y1060984D01*
G01Y1063346D02*
Y1064134D01*
G01X153151Y1019252D02*
Y1020039D01*
G01Y1016102D02*
Y1016890D01*
G01Y1022402D02*
Y1023189D01*
G01Y1028701D02*
Y1029488D01*
G01Y1025551D02*
Y1026339D01*
G01Y1031850D02*
Y1032638D01*
G01Y1038150D02*
Y1038937D01*
G01Y1035000D02*
Y1035787D01*
G01Y1041299D02*
Y1042087D01*
G01Y1047598D02*
Y1048386D01*
G01Y1044449D02*
Y1045236D01*
G01Y1050748D02*
Y1051535D01*
G01Y1057047D02*
Y1057835D01*
G01Y1053898D02*
Y1054685D01*
G01Y1060197D02*
Y1060984D01*
G01Y1063346D02*
Y1064134D01*
G01X153340D02*
Y1063346D01*
G01Y1060984D02*
Y1060197D01*
G01Y1057835D02*
Y1057047D01*
G01Y1054685D02*
Y1053898D01*
G01Y1051535D02*
Y1050748D01*
G01Y1048386D02*
Y1047598D01*
G01Y1045236D02*
Y1044449D01*
G01Y1042087D02*
Y1041299D01*
G01Y1038937D02*
Y1038150D01*
G01Y1035787D02*
Y1035000D01*
G01Y1032638D02*
Y1031850D01*
G01Y1029488D02*
Y1028701D01*
G01Y1026339D02*
Y1025551D01*
G01Y1023189D02*
Y1022402D01*
G01Y1020039D02*
Y1019252D01*
G01Y1016890D02*
Y1016102D01*
G01X156176Y1064134D02*
Y1063346D01*
G01Y1060984D02*
Y1060197D01*
G01Y1057835D02*
Y1057047D01*
G01Y1054685D02*
Y1053898D01*
G01Y1051535D02*
Y1050748D01*
G01Y1048386D02*
Y1047598D01*
G01Y1045236D02*
Y1044449D01*
G01Y1042087D02*
Y1041299D01*
G01Y1038937D02*
Y1038150D01*
G01Y1035787D02*
Y1035000D01*
G01Y1032638D02*
Y1031850D01*
G01Y1029488D02*
Y1028701D01*
G01Y1026339D02*
Y1025551D01*
G01Y1023189D02*
Y1022402D01*
G01Y1020039D02*
Y1019252D01*
G01Y1016890D02*
Y1016102D01*
G01X156253Y1006201D02*
Y1008957D01*
G01X156763Y1145925D02*
Y1008957D01*
G01X157118Y1019252D02*
Y1020039D01*
G01Y1016102D02*
Y1016890D01*
G01Y1022402D02*
Y1023189D01*
G01Y1028701D02*
Y1029488D01*
G01Y1025551D02*
Y1026339D01*
G01Y1031850D02*
Y1032638D01*
G01Y1038150D02*
Y1038937D01*
G01Y1035000D02*
Y1035787D01*
G01Y1041299D02*
Y1042087D01*
G01Y1047598D02*
Y1048386D01*
G01Y1044449D02*
Y1045236D01*
G01Y1050748D02*
Y1051535D01*
G01Y1057047D02*
Y1057835D01*
G01Y1053898D02*
Y1054685D01*
G01Y1060197D02*
Y1060984D01*
G01Y1063346D02*
Y1064134D01*
G01X158710Y1019252D02*
Y1020039D01*
G01Y1016102D02*
Y1016890D01*
G01Y1022402D02*
Y1023189D01*
G01Y1028701D02*
Y1029488D01*
G01Y1025551D02*
Y1026339D01*
G01Y1031850D02*
Y1032638D01*
G01Y1038150D02*
Y1038937D01*
G01Y1035000D02*
Y1035787D01*
G01Y1041299D02*
Y1042087D01*
G01Y1047598D02*
Y1048386D01*
G01Y1044449D02*
Y1045236D01*
G01Y1050748D02*
Y1051535D01*
G01Y1057047D02*
Y1057835D01*
G01Y1053898D02*
Y1054685D01*
G01Y1060197D02*
Y1060984D01*
G01Y1063346D02*
Y1064134D01*
G01X158857Y1019252D02*
Y1020039D01*
G01Y1016102D02*
Y1016890D01*
G01Y1022402D02*
Y1023189D01*
G01Y1028701D02*
Y1029488D01*
G01Y1025551D02*
Y1026339D01*
G01Y1031850D02*
Y1032638D01*
G01Y1038150D02*
Y1038937D01*
G01Y1035000D02*
Y1035787D01*
G01Y1041299D02*
Y1042087D01*
G01Y1047598D02*
Y1048386D01*
G01Y1044449D02*
Y1045236D01*
G01Y1050748D02*
Y1051535D01*
G01Y1057047D02*
Y1057835D01*
G01Y1053898D02*
Y1054685D01*
G01Y1060197D02*
Y1060984D01*
G01Y1063346D02*
Y1064134D01*
G01X159796Y1066496D02*
Y1064134D01*
G01Y1063346D02*
Y1060984D01*
G01Y1060197D02*
Y1057835D01*
G01Y1057047D02*
Y1054685D01*
G01Y1053898D02*
Y1051535D01*
G01Y1050748D02*
Y1048386D01*
G01Y1047598D02*
Y1045236D01*
G01Y1044449D02*
Y1042087D01*
G01Y1041299D02*
Y1038937D01*
G01Y1038150D02*
Y1035787D01*
G01Y1035000D02*
Y1032638D01*
G01Y1031850D02*
Y1029488D01*
G01Y1028701D02*
Y1026339D01*
G01Y1025551D02*
Y1023189D01*
G01Y1022402D02*
Y1020039D01*
G01Y1019252D02*
Y1016890D01*
G01Y1016102D02*
Y1013524D01*
G01X161240Y1015945D02*
Y1013976D01*
G01X161524Y1019252D02*
Y1020039D01*
G01Y1016102D02*
Y1016890D01*
G01Y1022402D02*
Y1023189D01*
G01Y1028701D02*
Y1029488D01*
G01Y1025551D02*
Y1026339D01*
G01Y1031850D02*
Y1032638D01*
G01Y1038150D02*
Y1038937D01*
G01Y1035000D02*
Y1035787D01*
G01Y1041299D02*
Y1042087D01*
G01Y1047598D02*
Y1048386D01*
G01Y1044449D02*
Y1045236D01*
G01Y1050748D02*
Y1051535D01*
G01Y1057047D02*
Y1057835D01*
G01Y1053898D02*
Y1054685D01*
G01Y1060197D02*
Y1060984D01*
G01Y1063346D02*
Y1064134D01*
G01X161874Y1051614D02*
Y1053819D01*
G01Y1061063D02*
Y1063268D01*
G01X162205Y1045728D02*
Y1044154D01*
G01Y1040728D02*
Y1039154D01*
G01Y1035728D02*
Y1034154D01*
G01Y1030728D02*
Y1029154D01*
G01Y1025728D02*
Y1024154D01*
G01Y1020728D02*
Y1019154D01*
G01Y1015728D02*
Y1014154D01*
G01X163176Y1064134D02*
Y1063346D01*
G01Y1060984D02*
Y1060197D01*
G01Y1057835D02*
Y1057047D01*
G01Y1054685D02*
Y1053898D01*
G01Y1051535D02*
Y1050748D01*
G01Y1048386D02*
Y1047598D01*
G01Y1045236D02*
Y1044449D01*
G01Y1042087D02*
Y1041299D01*
G01Y1038937D02*
Y1038150D01*
G01Y1035787D02*
Y1035000D01*
G01Y1032638D02*
Y1031850D01*
G01Y1029488D02*
Y1028701D01*
G01Y1026339D02*
Y1025551D01*
G01Y1023189D02*
Y1022402D01*
G01Y1020039D02*
Y1019252D01*
G01Y1016890D02*
Y1016102D01*
G01X163331Y1047795D02*
Y1051614D01*
G01Y1053819D02*
Y1061063D01*
G01Y1063268D02*
Y1067087D01*
G01X163739Y1065906D02*
Y1064724D01*
G01Y1062756D02*
Y1061575D01*
G01Y1059606D02*
Y1058425D01*
G01Y1056457D02*
Y1055276D01*
G01Y1053307D02*
Y1052126D01*
G01Y1050157D02*
Y1048976D01*
G01X163757Y1063268D02*
Y1061063D01*
G01Y1053819D02*
Y1051614D01*
G01X163809Y1047795D02*
Y1067087D01*
G01X164127Y1006201D02*
Y1008957D01*
G01X164766Y1008563D02*
Y1008504D01*
G01X165159Y1064134D02*
Y1063346D01*
G01Y1060984D02*
Y1060197D01*
G01Y1057835D02*
Y1057047D01*
G01Y1054685D02*
Y1053898D01*
G01Y1051535D02*
Y1050748D01*
G01Y1048386D02*
Y1047598D01*
G01Y1045236D02*
Y1044449D01*
G01Y1042087D02*
Y1041299D01*
G01Y1038937D02*
Y1038150D01*
G01Y1035787D02*
Y1035000D01*
G01Y1032638D02*
Y1031850D01*
G01Y1029488D02*
Y1028701D01*
G01Y1026339D02*
Y1025551D01*
G01Y1023189D02*
Y1022402D01*
G01Y1020039D02*
Y1019252D01*
G01Y1016890D02*
Y1016102D01*
G01X165293Y1011535D02*
Y1143150D01*
G01X165354Y1045728D02*
Y1044154D01*
G01Y1040728D02*
Y1039154D01*
G01Y1035728D02*
Y1034154D01*
G01Y1030728D02*
Y1029154D01*
G01Y1025728D02*
Y1024154D01*
G01Y1020728D02*
Y1019154D01*
G01Y1015728D02*
Y1014154D01*
G01X165748Y1008957D02*
Y1145925D01*
G01X166339Y1046516D02*
Y1043366D01*
G01Y1041516D02*
Y1038366D01*
G01Y1036516D02*
Y1033366D01*
G01Y1031516D02*
Y1028366D01*
G01Y1026516D02*
Y1023366D01*
G01Y1021516D02*
Y1018366D01*
G01Y1016516D02*
Y1013366D01*
G01X166888Y1065906D02*
Y1064724D01*
G01Y1062756D02*
Y1061575D01*
G01Y1059606D02*
Y1058425D01*
G01Y1056457D02*
Y1055276D01*
G01Y1053307D02*
Y1052126D01*
G01Y1050157D02*
Y1048976D01*
G01X167165Y1047795D02*
Y1067087D01*
G01X167323Y1046516D02*
Y1043366D01*
G01Y1041516D02*
Y1038366D01*
G01Y1036516D02*
Y1033366D01*
G01Y1031516D02*
Y1028366D01*
G01Y1026516D02*
Y1023366D01*
G01Y1021516D02*
Y1018366D01*
G01Y1016516D02*
Y1013366D01*
G01Y1008504D02*
Y1006201D01*
G01X167872Y1048287D02*
Y1066594D01*
G01X168082Y1067087D02*
Y1047795D01*
G01X168307Y1045728D02*
Y1044154D01*
G01Y1040728D02*
Y1039154D01*
G01Y1035728D02*
Y1034154D01*
G01Y1030728D02*
Y1029154D01*
G01Y1025728D02*
Y1024154D01*
G01Y1020728D02*
Y1019154D01*
G01Y1015728D02*
Y1014154D01*
G01X168521Y1019252D02*
Y1020039D01*
G01Y1016102D02*
Y1016890D01*
G01Y1022402D02*
Y1023189D01*
G01Y1028701D02*
Y1029488D01*
G01Y1025551D02*
Y1026339D01*
G01Y1031850D02*
Y1032638D01*
G01Y1038150D02*
Y1038937D01*
G01Y1035000D02*
Y1035787D01*
G01Y1041299D02*
Y1042087D01*
G01Y1047598D02*
Y1048386D01*
G01Y1044449D02*
Y1045236D01*
G01Y1050748D02*
Y1051535D01*
G01Y1057047D02*
Y1057835D01*
G01Y1053898D02*
Y1054685D01*
G01Y1060197D02*
Y1060984D01*
G01Y1063346D02*
Y1064134D01*
G01X168583Y1067087D02*
Y1047795D01*
G01X168857Y1066496D02*
Y1064134D01*
G01Y1063346D02*
Y1060984D01*
G01Y1060197D02*
Y1057835D01*
G01Y1057047D02*
Y1054685D01*
G01Y1053898D02*
Y1051535D01*
G01Y1050748D02*
Y1048386D01*
G01X168898Y1019252D02*
Y1020039D01*
G01Y1016102D02*
Y1016890D01*
G01Y1022402D02*
Y1023189D01*
G01Y1028701D02*
Y1029488D01*
G01Y1025551D02*
Y1026339D01*
G01Y1031850D02*
Y1032638D01*
G01Y1038150D02*
Y1038937D01*
G01Y1035000D02*
Y1035787D01*
G01Y1041299D02*
Y1042087D01*
G01Y1047598D02*
Y1048386D01*
G01Y1044449D02*
Y1045236D01*
G01Y1050748D02*
Y1051535D01*
G01Y1057047D02*
Y1057835D01*
G01Y1053898D02*
Y1054685D01*
G01Y1060197D02*
Y1060984D01*
G01Y1063346D02*
Y1064134D01*
G01X168924Y1019252D02*
Y1020039D01*
G01Y1016102D02*
Y1016890D01*
G01Y1022402D02*
Y1023189D01*
G01Y1028701D02*
Y1029488D01*
G01Y1025551D02*
Y1026339D01*
G01Y1031850D02*
Y1032638D01*
G01Y1038150D02*
Y1038937D01*
G01Y1035000D02*
Y1035787D01*
G01Y1041299D02*
Y1042087D01*
G01Y1047598D02*
Y1048386D01*
G01Y1044449D02*
Y1045236D01*
G01Y1050748D02*
Y1051535D01*
G01Y1057047D02*
Y1057835D01*
G01Y1053898D02*
Y1054685D01*
G01Y1060197D02*
Y1060984D01*
G01Y1063346D02*
Y1064134D01*
G01X169311Y1013976D02*
Y1015945D01*
G01X169370Y1047795D02*
Y1067087D01*
G01X169685D02*
Y1047795D01*
G01X169764Y1008957D02*
Y1145925D01*
G01X170866Y1146378D02*
Y1008504D01*
G01X164511Y1008957D02*
X164766Y1008563D01*
G01X170866Y1008504D02*
X164766D01*
G01Y1008563D02*
X170866D01*
G01X169764Y1010138D02*
X179134D01*
G01X170866Y1010728D02*
X201575D01*
G01X169764Y1011909D02*
X179134D01*
G01X167323Y1013366D02*
X166339D01*
G01X165748Y1013524D02*
X156763D01*
G01X167323Y1013563D02*
X166339D01*
G01X167323Y1013957D02*
X166339D01*
G01X161240Y1013976D02*
X169311D01*
G01X162205Y1014154D02*
X169370D01*
G01X162205Y1015728D02*
X169370D01*
G01X167323Y1015925D02*
X166339D01*
G01X169311Y1015945D02*
X161240D01*
G01X151378Y1016102D02*
X158710D01*
G01X158857D02*
X170866D01*
G01X167323Y1016319D02*
X166339D01*
G01X167323Y1016516D02*
X166339D01*
G01X170866Y1016890D02*
X158857D01*
G01X158710D02*
X151378D01*
G01X167323Y1018366D02*
X166339D01*
G01X167323Y1018563D02*
X166339D01*
G01X167323Y1018957D02*
X166339D01*
G01X162205Y1019154D02*
X169370D01*
G01X151378Y1019252D02*
X158710D01*
G01X158857D02*
X170866D01*
G01Y1020039D02*
X158857D01*
G01X158710D02*
X151378D01*
G01X162205Y1020728D02*
X169370D01*
G01X167323Y1020925D02*
X166339D01*
G01X167323Y1021319D02*
X166339D01*
G01X167323Y1021516D02*
X166339D01*
G01X151378Y1022402D02*
X158710D01*
G01X158857D02*
X170866D01*
G01Y1023189D02*
X158857D01*
G01X158710D02*
X151378D01*
G01X167323Y1023366D02*
X166339D01*
G01X167323Y1023563D02*
X166339D01*
G01X167323Y1023957D02*
X166339D01*
G01X162205Y1024154D02*
X169370D01*
G01X151378Y1025551D02*
X158710D01*
G01X158857D02*
X170866D01*
G01X162205Y1025728D02*
X169370D01*
G01X167323Y1025925D02*
X166339D01*
G01X167323Y1026319D02*
X166339D01*
G01X170866Y1026339D02*
X158857D01*
G01X158710D02*
X151378D01*
G01X167323Y1026516D02*
X166339D01*
G01X167323Y1028366D02*
X166339D01*
G01X167323Y1028563D02*
X166339D01*
G01X151378Y1028701D02*
X158710D01*
G01X158857D02*
X170866D01*
G01X167323Y1028957D02*
X166339D01*
G01X162205Y1029154D02*
X169370D01*
G01X170866Y1029488D02*
X158857D01*
G01X158710D02*
X151378D01*
G01X162205Y1030728D02*
X169370D01*
G01X167323Y1030925D02*
X166339D01*
G01X167323Y1031319D02*
X166339D01*
G01X167323Y1031516D02*
X166339D01*
G01X151378Y1031850D02*
X158710D01*
G01X158857D02*
X170866D01*
G01Y1032638D02*
X158857D01*
G01X158710D02*
X151378D01*
G01X167323Y1033366D02*
X166339D01*
G01X167323Y1033563D02*
X166339D01*
G01X167323Y1033957D02*
X166339D01*
G01X162205Y1034154D02*
X169370D01*
G01X151378Y1035000D02*
X158710D01*
G01X158857D02*
X170866D01*
G01X162205Y1035728D02*
X169370D01*
G01X170866Y1035787D02*
X158857D01*
G01X158710D02*
X151378D01*
G01X167323Y1035925D02*
X166339D01*
G01X167323Y1036319D02*
X166339D01*
G01X167323Y1036516D02*
X166339D01*
G01X151378Y1038150D02*
X158710D01*
G01X158857D02*
X170866D01*
G01X167323Y1038366D02*
X166339D01*
G01X167323Y1038563D02*
X166339D01*
G01X170866Y1038937D02*
X158857D01*
G01X158710D02*
X151378D01*
G01X167323Y1038957D02*
X166339D01*
G01X162205Y1039154D02*
X169370D01*
G01X162205Y1040728D02*
X169370D01*
G01X167323Y1040925D02*
X166339D01*
G01X151378Y1041299D02*
X158710D01*
G01X158857D02*
X170866D01*
G01X167323Y1041319D02*
X166339D01*
G01X167323Y1041516D02*
X166339D01*
G01X170866Y1042087D02*
X158857D01*
G01X158710D02*
X151378D01*
G01X167323Y1043366D02*
X166339D01*
G01X167323Y1043563D02*
X166339D01*
G01X167323Y1043957D02*
X166339D01*
G01X162205Y1044154D02*
X169370D01*
G01X151378Y1044449D02*
X158710D01*
G01X158857D02*
X170866D01*
G01Y1045236D02*
X158857D01*
G01X158710D02*
X151378D01*
G01X162205Y1045728D02*
X169370D01*
G01X167323Y1045925D02*
X166339D01*
G01X167323Y1046319D02*
X166339D01*
G01X167323Y1046516D02*
X166339D01*
G01X151378Y1047598D02*
X158710D01*
G01X158857D02*
X170866D01*
G01Y1047677D02*
X169764D01*
G01X163331Y1047795D02*
X170866D01*
G01X167872Y1048287D02*
X165748D01*
G01X170866Y1048386D02*
X158857D01*
G01X158710D02*
X151378D01*
G01X168857Y1048583D02*
X167872D01*
G01X168857Y1048780D02*
X167872D01*
G01X169764Y1048976D02*
X163739D01*
G01X169764Y1050157D02*
X163739D01*
G01X168857Y1050354D02*
X167872D01*
G01X168857Y1050551D02*
X167872D01*
G01X151378Y1050748D02*
X158710D01*
G01X158857D02*
X170866D01*
G01Y1051535D02*
X158857D01*
G01X158710D02*
X151378D01*
G01X161874Y1051614D02*
X163757D01*
G01X168857Y1051732D02*
X167872D01*
G01X168857Y1051929D02*
X167872D01*
G01X169764Y1052126D02*
X163739D01*
G01X169764Y1053307D02*
X163739D01*
G01X168857Y1053504D02*
X167872D01*
G01X168857Y1053701D02*
X167872D01*
G01X163757Y1053819D02*
X161874D01*
G01X151378Y1053898D02*
X158710D01*
G01X158857D02*
X170866D01*
G01Y1054685D02*
X158857D01*
G01X158710D02*
X151378D01*
G01X168857Y1054882D02*
X167872D01*
G01X168857Y1055079D02*
X167872D01*
G01X169764Y1055276D02*
X163739D01*
G01X169764Y1056457D02*
X163739D01*
G01X168857Y1056654D02*
X167872D01*
G01X168857Y1056850D02*
X167872D01*
G01X151378Y1057047D02*
X158710D01*
G01X158857D02*
X170866D01*
G01Y1057835D02*
X158857D01*
G01X158710D02*
X151378D01*
G01X168857Y1058031D02*
X167872D01*
G01X168857Y1058228D02*
X167872D01*
G01X169764Y1058425D02*
X163739D01*
G01X169764Y1059606D02*
X163739D01*
G01X168857Y1059803D02*
X167872D01*
G01X168857Y1060000D02*
X167872D01*
G01X151378Y1060197D02*
X158710D01*
G01X158857D02*
X170866D01*
G01Y1060984D02*
X158857D01*
G01X158710D02*
X151378D01*
G01X161874Y1061063D02*
X163757D01*
G01X168857Y1061181D02*
X167872D01*
G01X168857Y1061378D02*
X167872D01*
G01X169764Y1061575D02*
X163739D01*
G01X169764Y1062756D02*
X163739D01*
G01X168857Y1062953D02*
X167872D01*
G01X168857Y1063150D02*
X167872D01*
G01X163757Y1063268D02*
X161874D01*
G01X151378Y1063346D02*
X158710D01*
G01X158857D02*
X170866D01*
G01Y1064134D02*
X158857D01*
G01X158710D02*
X151378D01*
G01X168857Y1064331D02*
X167872D01*
G01X168857Y1064528D02*
X167872D01*
G01X169764Y1064724D02*
X163739D01*
G01X169764Y1018760D02*
G03X169370Y1019154I-394J0D01*
G01Y1020728D02*
G03X169764Y1021122I0J394D01*
G01Y1028760D02*
G03X169370Y1029154I-394J0D01*
G01Y1030728D02*
G03X169764Y1031122I0J394D01*
G01Y1023760D02*
G03X169370Y1024154I-394J0D01*
G01Y1025728D02*
G03X169764Y1026122I0J394D01*
G01Y1033760D02*
G03X169370Y1034154I-394J0D01*
G01Y1035728D02*
G03X169764Y1036122I0J394D01*
G01Y1038760D02*
G03X169370Y1039154I-394J0D01*
G01X169764Y1013760D02*
G03X169370Y1014154I-394J0D01*
G01Y1015728D02*
G03X169764Y1016122I0J394D01*
G01X169370Y1040728D02*
G03X169764Y1041122I0J394D01*
G01Y1043760D02*
G03X169370Y1044154I-394J0D01*
G01Y1045728D02*
G03X169764Y1046122I0J394D01*
G01X151243Y1004980D02*
Y1004242D01*
G01X155081Y1004316D02*
Y1004980D01*
G01X166597Y999518D02*
Y999075D01*
G01X166892Y1003430D02*
Y1003282D01*
G01X167704D02*
Y1003430D01*
G01X170509Y999075D02*
Y999813D01*
G01X166892Y1003430D02*
X166979Y1003907D01*
X167226Y1004349D01*
X167615Y1004701D01*
X168121Y1004921D01*
X168699Y1004977D01*
X169263Y1004855D01*
X169739Y1004572D01*
X170078Y1004168D01*
X170257Y1003711D01*
X170272Y1003231D01*
X170115Y1002760D01*
X169801Y1002343D01*
G01X167772Y1003735D02*
X167704Y1003430D01*
G01X169229Y1002868D02*
X169412Y1003134D01*
X169476Y1003431D01*
X169411Y1003729D01*
G01X167961Y1004002D02*
X167771Y1003734D01*
G01X169801Y1002343D02*
X170138Y1002805D01*
X170283Y1003324D01*
X170223Y1003841D01*
X169972Y1004325D01*
X169535Y1004720D01*
X168962Y1004943D01*
X168328Y1004962D01*
X167743Y1004776D01*
X167288Y1004423D01*
X166996Y1003951D01*
X166892Y1003430D01*
G01X159453Y1002331D02*
X159776Y1002751D01*
X159938Y1003234D01*
X159917Y1003739D01*
X159713Y1004216D01*
X159347Y1004619D01*
X158841Y1004886D01*
X158250Y1004980D01*
X157660Y1004883D01*
X157158Y1004614D01*
X156794Y1004210D01*
X156593Y1003732D01*
X156573Y1003228D01*
X156737Y1002746D01*
X157057Y1002331D01*
G01X164620D02*
X164943Y1002751D01*
X165106Y1003234D01*
X165084Y1003739D01*
X164881Y1004216D01*
X164514Y1004619D01*
X164008Y1004886D01*
X163417Y1004980D01*
X162828Y1004883D01*
X162325Y1004614D01*
X161961Y1004210D01*
X161760Y1003732D01*
X161741Y1003228D01*
X161904Y1002746D01*
X162225Y1002331D01*
G01X169229Y1002868D02*
X167667Y1001341D01*
G01X157057Y1002331D02*
X156606Y1001891D01*
X156336Y1001355D01*
X156265Y1000785D01*
X156407Y1000221D01*
X156754Y999696D01*
X157281Y999303D01*
X157924Y999100D01*
X158603Y999102D01*
X159243Y999310D01*
X159766Y999706D01*
X160107Y1000230D01*
X160245Y1000791D01*
X160174Y1001359D01*
X159904Y1001893D01*
G01X162225Y1002331D02*
X161773Y1001891D01*
X161503Y1001355D01*
X161433Y1000785D01*
X161574Y1000221D01*
X161921Y999696D01*
X162448Y999303D01*
X163091Y999100D01*
X163770Y999102D01*
X164411Y999310D01*
X164933Y999706D01*
X165275Y1000230D01*
X165413Y1000791D01*
X165341Y1001359D01*
X165071Y1001893D01*
G01X169801Y1002343D02*
X168172Y1000797D01*
G01X159453Y1002331D02*
X159905Y1001891D01*
X160175Y1001355D01*
X160245Y1000785D01*
X160104Y1000221D01*
X159757Y999696D01*
X159230Y999303D01*
X158587Y999100D01*
X157907Y999102D01*
X157267Y999310D01*
X156744Y999706D01*
X156403Y1000230D01*
X156265Y1000791D01*
X156337Y1001359D01*
X156607Y1001893D01*
G01X164620Y1002331D02*
X165072Y1001891D01*
X165342Y1001355D01*
X165413Y1000785D01*
X165271Y1000221D01*
X164924Y999696D01*
X164397Y999303D01*
X163754Y999100D01*
X163075Y999102D01*
X162435Y999310D01*
X161912Y999706D01*
X161570Y1000230D01*
X161432Y1000791D01*
X161504Y1001359D01*
X161774Y1001893D01*
G01X157057Y1002331D02*
X156735Y1002751D01*
X156572Y1003234D01*
X156594Y1003739D01*
X156797Y1004216D01*
X157164Y1004619D01*
X157670Y1004886D01*
X158261Y1004980D01*
X158850Y1004883D01*
X159353Y1004614D01*
X159717Y1004210D01*
X159918Y1003732D01*
X159937Y1003228D01*
X159774Y1002746D01*
X159453Y1002331D01*
G01X162225D02*
X161902Y1002751D01*
X161739Y1003234D01*
X161761Y1003739D01*
X161964Y1004216D01*
X162331Y1004619D01*
X162837Y1004886D01*
X163428Y1004980D01*
X164018Y1004883D01*
X164520Y1004614D01*
X164884Y1004210D01*
X165085Y1003732D01*
X165105Y1003228D01*
X164941Y1002746D01*
X164620Y1002331D01*
G01X169229Y1003993D02*
X169411Y1003728D01*
X169476Y1003429D01*
X169411Y1003132D01*
G01X157832Y1001876D02*
X157472Y1001640D01*
X157233Y1001290D01*
X157148Y1000886D01*
X157231Y1000484D01*
X157467Y1000131D01*
X157830Y999892D01*
X158255Y999807D01*
G01X158678Y999891D02*
X159039Y1000127D01*
X159277Y1000477D01*
X159363Y1000881D01*
X159280Y1001283D01*
X159043Y1001635D01*
X158680Y1001875D01*
X158255Y1001960D01*
G01X163000Y1001876D02*
X162639Y1001640D01*
X162401Y1001290D01*
X162315Y1000886D01*
X162398Y1000484D01*
X162634Y1000131D01*
X162998Y999892D01*
X163422Y999807D01*
G01X163846Y999891D02*
X164206Y1000127D01*
X164444Y1000477D01*
X164530Y1000881D01*
X164447Y1001283D01*
X164211Y1001635D01*
X163847Y1001875D01*
X163422Y1001960D01*
G01X157906Y1004177D02*
X157624Y1003999D01*
X157437Y1003734D01*
X157370Y1003432D01*
X157434Y1003132D01*
X157619Y1002865D01*
X157905Y1002683D01*
X158255Y1002618D01*
G01X158604Y1002683D02*
X158887Y1002861D01*
X159074Y1003126D01*
X159141Y1003428D01*
X159076Y1003728D01*
X158891Y1003995D01*
X158606Y1004176D01*
X158255Y1004242D01*
G01X163074Y1004177D02*
X162791Y1003999D01*
X162604Y1003734D01*
X162537Y1003432D01*
X162601Y1003132D01*
X162787Y1002865D01*
X163072Y1002683D01*
X163422Y1002618D01*
G01X163772Y1002683D02*
X164054Y1002861D01*
X164241Y1003126D01*
X164308Y1003428D01*
X164244Y1003728D01*
X164058Y1003995D01*
X163773Y1004176D01*
X163422Y1004242D01*
G01X167961Y1004002D02*
X168248Y1004180D01*
X168602Y1004242D01*
G01X157906Y1002683D02*
X157624Y1002861D01*
X157437Y1003126D01*
X157370Y1003428D01*
X157434Y1003728D01*
X157619Y1003995D01*
X157905Y1004176D01*
X158255Y1004242D01*
G01X158604Y1004177D02*
X158887Y1003999D01*
X159074Y1003734D01*
X159141Y1003432D01*
X159076Y1003132D01*
X158891Y1002865D01*
X158606Y1002683D01*
X158255Y1002618D01*
G01X163074Y1002683D02*
X162791Y1002861D01*
X162604Y1003126D01*
X162537Y1003428D01*
X162601Y1003728D01*
X162787Y1003995D01*
X163072Y1004176D01*
X163422Y1004242D01*
G01X163772Y1004177D02*
X164054Y1003999D01*
X164241Y1003734D01*
X164308Y1003432D01*
X164244Y1003132D01*
X164058Y1002865D01*
X163773Y1002683D01*
X163422Y1002618D01*
G01X168949Y1004173D02*
X169229Y1003992D01*
G01X157832Y999891D02*
X157472Y1000127D01*
X157233Y1000477D01*
X157148Y1000881D01*
X157231Y1001283D01*
X157467Y1001635D01*
X157830Y1001875D01*
X158255Y1001960D01*
G01X158678Y1001876D02*
X159039Y1001640D01*
X159277Y1001290D01*
X159363Y1000886D01*
X159280Y1000484D01*
X159043Y1000131D01*
X158680Y999892D01*
X158255Y999807D01*
G01X163000Y999891D02*
X162639Y1000127D01*
X162401Y1000477D01*
X162315Y1000881D01*
X162398Y1001283D01*
X162634Y1001635D01*
X162998Y1001875D01*
X163422Y1001960D01*
G01X163846Y1001876D02*
X164206Y1001640D01*
X164444Y1001290D01*
X164530Y1000886D01*
X164447Y1000484D01*
X164211Y1000131D01*
X163847Y999892D01*
X163422Y999807D01*
G01X179449Y995098D02*
X163071D01*
G01X151981Y999075D02*
X152867D01*
G01X166597D02*
X170509D01*
G01Y999813D02*
X167630D01*
G01X166892Y1003282D02*
X167704D01*
G01X151243Y1004242D02*
X154195D01*
G01X155081Y1004980D02*
X151243D01*
G01X168602Y1004242D02*
X168950Y1004173D01*
G01X155081Y1004316D02*
G03X152866Y999075I7142J-6107D01*
G01X154195Y1004242D02*
G03X151981Y999075I6938J-6031D01*
G01X166535Y1002638D02*
G03I-4527J0D01*
G01X165512D02*
G03I-3504J0D01*
G01X165354D02*
G03I-3346J0D01*
G01X164173D02*
G03I-2165J0D01*
G01X168172Y1000797D02*
G03X167630Y999813I1276J-1344D01*
G01X167667Y1001341D02*
G03X166597Y999518I2809J-2874D01*
G01X174882Y1069547D02*
Y1085886D01*
G01Y1088248D02*
Y1104783D01*
G01X195106Y1067185D02*
X172913D01*
G01X181102Y1067205D02*
X199606D01*
G01Y1069547D02*
X172913D01*
G01X200563Y1073642D02*
X181102D01*
G01X199606Y1085886D02*
X172913D01*
G01X199606Y1088248D02*
X172913D01*
G01X199606Y1104783D02*
X172913D01*
G01X151378Y1066496D02*
Y1067283D01*
G01Y1069646D02*
Y1070433D01*
G01Y1075945D02*
Y1076732D01*
G01Y1072795D02*
Y1073583D01*
G01Y1079094D02*
Y1079882D01*
G01Y1085394D02*
Y1086181D01*
G01Y1082244D02*
Y1083031D01*
G01Y1088543D02*
Y1089331D01*
G01Y1094843D02*
Y1095630D01*
G01Y1091693D02*
Y1092480D01*
G01Y1097992D02*
Y1098780D01*
G01Y1104291D02*
Y1105079D01*
G01Y1101142D02*
Y1101929D01*
G01X153151Y1066496D02*
Y1067283D01*
G01Y1069646D02*
Y1070433D01*
G01Y1075945D02*
Y1076732D01*
G01Y1072795D02*
Y1073583D01*
G01Y1079094D02*
Y1079882D01*
G01Y1085394D02*
Y1086181D01*
G01Y1082244D02*
Y1083031D01*
G01Y1088543D02*
Y1089331D01*
G01Y1094843D02*
Y1095630D01*
G01Y1091693D02*
Y1092480D01*
G01Y1097992D02*
Y1098780D01*
G01Y1104291D02*
Y1105079D01*
G01Y1101142D02*
Y1101929D01*
G01X153340Y1105079D02*
Y1104291D01*
G01Y1101929D02*
Y1101142D01*
G01Y1098780D02*
Y1097992D01*
G01Y1095630D02*
Y1094843D01*
G01Y1092480D02*
Y1091693D01*
G01Y1089331D02*
Y1088543D01*
G01Y1086181D02*
Y1085394D01*
G01Y1083031D02*
Y1082244D01*
G01Y1079882D02*
Y1079094D01*
G01Y1076732D02*
Y1075945D01*
G01Y1073583D02*
Y1072795D01*
G01Y1070433D02*
Y1069646D01*
G01Y1067283D02*
Y1066496D01*
G01X156176Y1105079D02*
Y1104291D01*
G01Y1101929D02*
Y1101142D01*
G01Y1098780D02*
Y1097992D01*
G01Y1095630D02*
Y1094843D01*
G01Y1092480D02*
Y1091693D01*
G01Y1089331D02*
Y1088543D01*
G01Y1086181D02*
Y1085394D01*
G01Y1083031D02*
Y1082244D01*
G01Y1079882D02*
Y1079094D01*
G01Y1076732D02*
Y1075945D01*
G01Y1073583D02*
Y1072795D01*
G01Y1070433D02*
Y1069646D01*
G01Y1067283D02*
Y1066496D01*
G01X157118D02*
Y1067283D01*
G01Y1069646D02*
Y1070433D01*
G01Y1075945D02*
Y1076732D01*
G01Y1072795D02*
Y1073583D01*
G01Y1079094D02*
Y1079882D01*
G01Y1085394D02*
Y1086181D01*
G01Y1082244D02*
Y1083031D01*
G01Y1088543D02*
Y1089331D01*
G01Y1094843D02*
Y1095630D01*
G01Y1091693D02*
Y1092480D01*
G01Y1097992D02*
Y1098780D01*
G01Y1104291D02*
Y1105079D01*
G01Y1101142D02*
Y1101929D01*
G01X158710Y1066496D02*
Y1067283D01*
G01Y1069646D02*
Y1070433D01*
G01Y1075945D02*
Y1076732D01*
G01Y1072795D02*
Y1073583D01*
G01Y1079094D02*
Y1079882D01*
G01Y1085394D02*
Y1086181D01*
G01Y1082244D02*
Y1083031D01*
G01Y1088543D02*
Y1089331D01*
G01Y1094843D02*
Y1095630D01*
G01Y1091693D02*
Y1092480D01*
G01Y1097992D02*
Y1098780D01*
G01Y1104291D02*
Y1105079D01*
G01Y1101142D02*
Y1101929D01*
G01X158857Y1066496D02*
Y1067283D01*
G01Y1069646D02*
Y1070433D01*
G01Y1075945D02*
Y1076732D01*
G01Y1072795D02*
Y1073583D01*
G01Y1079094D02*
Y1079882D01*
G01Y1085394D02*
Y1086181D01*
G01Y1082244D02*
Y1083031D01*
G01Y1088543D02*
Y1089331D01*
G01Y1094843D02*
Y1095630D01*
G01Y1091693D02*
Y1092480D01*
G01Y1097992D02*
Y1098780D01*
G01Y1104291D02*
Y1105079D01*
G01Y1101142D02*
Y1101929D01*
G01X159796Y1107441D02*
Y1105079D01*
G01Y1104291D02*
Y1101929D01*
G01Y1101142D02*
Y1098780D01*
G01Y1097992D02*
Y1095630D01*
G01Y1094843D02*
Y1092480D01*
G01Y1091693D02*
Y1089331D01*
G01Y1088543D02*
Y1086181D01*
G01Y1085394D02*
Y1083031D01*
G01Y1082244D02*
Y1079882D01*
G01Y1079094D02*
Y1076732D01*
G01Y1075945D02*
Y1073583D01*
G01Y1072795D02*
Y1070433D01*
G01Y1069646D02*
Y1067283D01*
G01X161524Y1066496D02*
Y1067283D01*
G01Y1069646D02*
Y1070433D01*
G01Y1075945D02*
Y1076732D01*
G01Y1072795D02*
Y1073583D01*
G01Y1079094D02*
Y1079882D01*
G01Y1085394D02*
Y1086181D01*
G01Y1082244D02*
Y1083031D01*
G01Y1088543D02*
Y1089331D01*
G01Y1094843D02*
Y1095630D01*
G01Y1091693D02*
Y1092480D01*
G01Y1097992D02*
Y1098780D01*
G01Y1104291D02*
Y1105079D01*
G01Y1101142D02*
Y1101929D01*
G01X162205Y1105728D02*
Y1104154D01*
G01Y1100728D02*
Y1099154D01*
G01Y1095728D02*
Y1094154D01*
G01Y1090728D02*
Y1089154D01*
G01Y1080728D02*
Y1079154D01*
G01Y1075728D02*
Y1074154D01*
G01Y1070728D02*
Y1069154D01*
G01X163176Y1105079D02*
Y1104291D01*
G01Y1101929D02*
Y1101142D01*
G01Y1098780D02*
Y1097992D01*
G01Y1095630D02*
Y1094843D01*
G01Y1092480D02*
Y1091693D01*
G01Y1089331D02*
Y1088543D01*
G01Y1086181D02*
Y1085394D01*
G01Y1083031D02*
Y1082244D01*
G01Y1079882D02*
Y1079094D01*
G01Y1076732D02*
Y1075945D01*
G01Y1073583D02*
Y1072795D01*
G01Y1070433D02*
Y1069646D01*
G01Y1067283D02*
Y1066496D01*
G01X164173Y1085728D02*
Y1084154D01*
G01X165159Y1105079D02*
Y1104291D01*
G01Y1101929D02*
Y1101142D01*
G01Y1098780D02*
Y1097992D01*
G01Y1095630D02*
Y1094843D01*
G01Y1092480D02*
Y1091693D01*
G01Y1089331D02*
Y1088543D01*
G01Y1086181D02*
Y1085394D01*
G01Y1083031D02*
Y1082244D01*
G01Y1079882D02*
Y1079094D01*
G01Y1076732D02*
Y1075945D01*
G01Y1073583D02*
Y1072795D01*
G01Y1070433D02*
Y1069646D01*
G01Y1067283D02*
Y1066496D01*
G01X165354Y1105728D02*
Y1104154D01*
G01Y1100728D02*
Y1099154D01*
G01Y1095728D02*
Y1094154D01*
G01Y1090728D02*
Y1089154D01*
G01Y1080728D02*
Y1079154D01*
G01Y1075728D02*
Y1074154D01*
G01Y1070728D02*
Y1069154D01*
G01X166339Y1106516D02*
Y1103366D01*
G01Y1101516D02*
Y1098366D01*
G01Y1096516D02*
Y1093366D01*
G01Y1091516D02*
Y1088366D01*
G01Y1081516D02*
Y1078366D01*
G01Y1076516D02*
Y1073366D01*
G01Y1071516D02*
Y1068366D01*
G01X167323Y1106516D02*
Y1103366D01*
G01Y1101516D02*
Y1098366D01*
G01Y1096516D02*
Y1093366D01*
G01Y1091516D02*
Y1088366D01*
G01Y1085728D02*
Y1084154D01*
G01Y1081516D02*
Y1078366D01*
G01Y1076516D02*
Y1073366D01*
G01Y1071516D02*
Y1068366D01*
G01X168307Y1105728D02*
Y1104154D01*
G01Y1100728D02*
Y1099154D01*
G01Y1095728D02*
Y1094154D01*
G01Y1090728D02*
Y1089154D01*
G01Y1086516D02*
Y1083366D01*
G01Y1080728D02*
Y1079154D01*
G01Y1075728D02*
Y1074154D01*
G01Y1070728D02*
Y1069154D01*
G01X168521Y1066496D02*
Y1067283D01*
G01Y1069646D02*
Y1070433D01*
G01Y1075945D02*
Y1076732D01*
G01Y1072795D02*
Y1073583D01*
G01Y1079094D02*
Y1079882D01*
G01Y1085394D02*
Y1086181D01*
G01Y1082244D02*
Y1083031D01*
G01Y1088543D02*
Y1089331D01*
G01Y1094843D02*
Y1095630D01*
G01Y1091693D02*
Y1092480D01*
G01Y1097992D02*
Y1098780D01*
G01Y1104291D02*
Y1105079D01*
G01Y1101142D02*
Y1101929D01*
G01X168898Y1066496D02*
Y1067283D01*
G01Y1069646D02*
Y1070433D01*
G01Y1075945D02*
Y1076732D01*
G01Y1072795D02*
Y1073583D01*
G01Y1079094D02*
Y1079882D01*
G01Y1085394D02*
Y1086181D01*
G01Y1082244D02*
Y1083031D01*
G01Y1088543D02*
Y1089331D01*
G01Y1094843D02*
Y1095630D01*
G01Y1091693D02*
Y1092480D01*
G01Y1097992D02*
Y1098780D01*
G01Y1104291D02*
Y1105079D01*
G01Y1101142D02*
Y1101929D01*
G01X168924Y1066496D02*
Y1067283D01*
G01Y1069646D02*
Y1070433D01*
G01Y1075945D02*
Y1076732D01*
G01Y1072795D02*
Y1073583D01*
G01Y1079094D02*
Y1079882D01*
G01Y1085394D02*
Y1086181D01*
G01Y1082244D02*
Y1083031D01*
G01Y1088543D02*
Y1089331D01*
G01Y1094843D02*
Y1095630D01*
G01Y1091693D02*
Y1092480D01*
G01Y1097992D02*
Y1098780D01*
G01Y1104291D02*
Y1105079D01*
G01Y1101142D02*
Y1101929D01*
G01X169291Y1086516D02*
Y1083366D01*
G01X168857Y1066299D02*
X167872D01*
G01X151378Y1066496D02*
X158710D01*
G01X158857D02*
X170866D01*
G01X167872Y1066594D02*
X165748D01*
G01X170866Y1067087D02*
X163331D01*
G01X170866Y1067205D02*
X169764D01*
G01X170866Y1067283D02*
X158857D01*
G01X158710D02*
X151378D01*
G01X167323Y1068366D02*
X166339D01*
G01X167323Y1068563D02*
X166339D01*
G01X167323Y1068957D02*
X166339D01*
G01X162205Y1069154D02*
X169370D01*
G01X151378Y1069646D02*
X158710D01*
G01X158857D02*
X170866D01*
G01Y1070433D02*
X158857D01*
G01X158710D02*
X151378D01*
G01X162205Y1070728D02*
X169370D01*
G01X167323Y1070925D02*
X166339D01*
G01X167323Y1071319D02*
X166339D01*
G01X167323Y1071516D02*
X166339D01*
G01X151378Y1072795D02*
X158710D01*
G01X158857D02*
X170866D01*
G01X167323Y1073366D02*
X166339D01*
G01X167323Y1073563D02*
X166339D01*
G01X170866Y1073583D02*
X158857D01*
G01X158710D02*
X151378D01*
G01X167323Y1073957D02*
X166339D01*
G01X162205Y1074154D02*
X169370D01*
G01X162205Y1075728D02*
X169370D01*
G01X167323Y1075925D02*
X166339D01*
G01X151378Y1075945D02*
X158710D01*
G01X158857D02*
X170866D01*
G01X167323Y1076319D02*
X166339D01*
G01X167323Y1076516D02*
X166339D01*
G01X170866Y1076732D02*
X158857D01*
G01X158710D02*
X151378D01*
G01X167323Y1078366D02*
X166339D01*
G01X167323Y1078563D02*
X166339D01*
G01X167323Y1078957D02*
X166339D01*
G01X151378Y1079094D02*
X158710D01*
G01X158857D02*
X170866D01*
G01X162205Y1079154D02*
X169370D01*
G01X170866Y1079882D02*
X158857D01*
G01X158710D02*
X151378D01*
G01X162205Y1080728D02*
X169370D01*
G01X167323Y1080925D02*
X166339D01*
G01X167323Y1081319D02*
X166339D01*
G01X167323Y1081516D02*
X166339D01*
G01X151378Y1082244D02*
X158710D01*
G01X158857D02*
X170866D01*
G01Y1082736D02*
X169764D01*
G01X170866Y1083031D02*
X158857D01*
G01X158710D02*
X151378D01*
G01X169291Y1083366D02*
X168307D01*
G01X169291Y1083563D02*
X168307D01*
G01X169291Y1083957D02*
X168307D01*
G01X169764Y1084154D02*
X164173D01*
G01X151378Y1085394D02*
X158710D01*
G01X158857D02*
X170866D01*
G01X169764Y1085728D02*
X164173D01*
G01X169291Y1085925D02*
X168307D01*
G01X170866Y1086181D02*
X158857D01*
G01X158710D02*
X151378D01*
G01X169291Y1086319D02*
X168307D01*
G01X169291Y1086516D02*
X168307D01*
G01X169764Y1087146D02*
X170866D01*
G01X167323Y1088366D02*
X166339D01*
G01X151378Y1088543D02*
X158710D01*
G01X158857D02*
X170866D01*
G01X167323Y1088563D02*
X166339D01*
G01X167323Y1088957D02*
X166339D01*
G01X162205Y1089154D02*
X169370D01*
G01X170866Y1089331D02*
X158857D01*
G01X158710D02*
X151378D01*
G01X162205Y1090728D02*
X169370D01*
G01X167323Y1090925D02*
X166339D01*
G01X167323Y1091319D02*
X166339D01*
G01X167323Y1091516D02*
X166339D01*
G01X151378Y1091693D02*
X158710D01*
G01X158857D02*
X170866D01*
G01Y1092480D02*
X158857D01*
G01X158710D02*
X151378D01*
G01X167323Y1093366D02*
X166339D01*
G01X167323Y1093563D02*
X166339D01*
G01X167323Y1093957D02*
X166339D01*
G01X162205Y1094154D02*
X169370D01*
G01X151378Y1094843D02*
X158710D01*
G01X158857D02*
X170866D01*
G01Y1095630D02*
X158857D01*
G01X158710D02*
X151378D01*
G01X162205Y1095728D02*
X169370D01*
G01X167323Y1095925D02*
X166339D01*
G01X167323Y1096319D02*
X166339D01*
G01X167323Y1096516D02*
X166339D01*
G01X151378Y1097992D02*
X158710D01*
G01X158857D02*
X170866D01*
G01X167323Y1098366D02*
X166339D01*
G01X167323Y1098563D02*
X166339D01*
G01X170866Y1098780D02*
X158857D01*
G01X158710D02*
X151378D01*
G01X167323Y1098957D02*
X166339D01*
G01X162205Y1099154D02*
X169370D01*
G01X162205Y1100728D02*
X169370D01*
G01X167323Y1100925D02*
X166339D01*
G01X151378Y1101142D02*
X158710D01*
G01X158857D02*
X170866D01*
G01X167323Y1101319D02*
X166339D01*
G01X167323Y1101516D02*
X166339D01*
G01X170866Y1101929D02*
X158857D01*
G01X158710D02*
X151378D01*
G01X167323Y1103366D02*
X166339D01*
G01X167323Y1103563D02*
X166339D01*
G01X167323Y1103957D02*
X166339D01*
G01X162205Y1104154D02*
X169370D01*
G01X151378Y1104291D02*
X158710D01*
G01X158857D02*
X170866D01*
G01Y1105079D02*
X158857D01*
G01X158710D02*
X151378D01*
G01X169764Y1068760D02*
G03X169370Y1069154I-394J0D01*
G01Y1070728D02*
G03X169764Y1071122I0J394D01*
G01Y1078760D02*
G03X169370Y1079154I-394J0D01*
G01Y1080728D02*
G03X169764Y1081122I0J394D01*
G01Y1073760D02*
G03X169370Y1074154I-394J0D01*
G01Y1075728D02*
G03X169764Y1076122I0J394D01*
G01Y1093760D02*
G03X169370Y1094154I-394J0D01*
G01Y1095728D02*
G03X169764Y1096122I0J394D01*
G01Y1103760D02*
G03X169370Y1104154I-394J0D01*
G01X169764Y1098760D02*
G03X169370Y1099154I-394J0D01*
G01Y1100728D02*
G03X169764Y1101122I0J394D01*
G01Y1088760D02*
G03X169370Y1089154I-394J0D01*
G01Y1090728D02*
G03X169764Y1091122I0J394D01*
G01X174882Y1126043D02*
Y1143563D01*
G01X199606Y1126043D02*
X172913D01*
G01X174882Y1107146D02*
Y1123681D01*
G01X199606Y1107146D02*
X172913D01*
G01X199606Y1123681D02*
X172913D01*
G01X151378Y1126339D02*
Y1127126D01*
G01Y1132638D02*
Y1133425D01*
G01Y1129488D02*
Y1130276D01*
G01Y1135787D02*
Y1136575D01*
G01X153151Y1126339D02*
Y1127126D01*
G01Y1132638D02*
Y1133425D01*
G01Y1129488D02*
Y1130276D01*
G01Y1135787D02*
Y1136575D01*
G01X153340D02*
Y1135787D01*
G01Y1133425D02*
Y1132638D01*
G01Y1130276D02*
Y1129488D01*
G01Y1127126D02*
Y1126339D01*
G01X156176Y1136575D02*
Y1135787D01*
G01Y1133425D02*
Y1132638D01*
G01Y1130276D02*
Y1129488D01*
G01Y1127126D02*
Y1126339D01*
G01X157118D02*
Y1127126D01*
G01Y1132638D02*
Y1133425D01*
G01Y1129488D02*
Y1130276D01*
G01Y1135787D02*
Y1136575D01*
G01X158710Y1126339D02*
Y1127126D01*
G01Y1132638D02*
Y1133425D01*
G01Y1129488D02*
Y1130276D01*
G01Y1135787D02*
Y1136575D01*
G01X158857Y1126339D02*
Y1127126D01*
G01Y1132638D02*
Y1133425D01*
G01Y1129488D02*
Y1130276D01*
G01Y1135787D02*
Y1136575D01*
G01X159796Y1138937D02*
Y1136575D01*
G01Y1135787D02*
Y1133425D01*
G01Y1132638D02*
Y1130276D01*
G01Y1129488D02*
Y1127126D01*
G01X161524Y1126339D02*
Y1127126D01*
G01Y1132638D02*
Y1133425D01*
G01Y1129488D02*
Y1130276D01*
G01Y1135787D02*
Y1136575D01*
G01X162205Y1135728D02*
Y1134154D01*
G01Y1130728D02*
Y1129154D01*
G01X163176Y1136575D02*
Y1135787D01*
G01Y1133425D02*
Y1132638D01*
G01Y1130276D02*
Y1129488D01*
G01Y1127126D02*
Y1126339D01*
G01X165159Y1136575D02*
Y1135787D01*
G01Y1133425D02*
Y1132638D01*
G01Y1130276D02*
Y1129488D01*
G01Y1127126D02*
Y1126339D01*
G01X165354Y1135728D02*
Y1134154D01*
G01Y1130728D02*
Y1129154D01*
G01X166339Y1141516D02*
Y1138366D01*
G01Y1136516D02*
Y1133366D01*
G01Y1131516D02*
Y1128366D01*
G01X167323Y1141516D02*
Y1138366D01*
G01Y1136516D02*
Y1133366D01*
G01Y1131516D02*
Y1128366D01*
G01X168307Y1135728D02*
Y1134154D01*
G01Y1130728D02*
Y1129154D01*
G01X168521Y1126339D02*
Y1127126D01*
G01Y1132638D02*
Y1133425D01*
G01Y1129488D02*
Y1130276D01*
G01Y1135787D02*
Y1136575D01*
G01X168898Y1126339D02*
Y1127126D01*
G01Y1132638D02*
Y1133425D01*
G01Y1129488D02*
Y1130276D01*
G01Y1135787D02*
Y1136575D01*
G01X168924Y1126339D02*
Y1127126D01*
G01Y1132638D02*
Y1133425D01*
G01Y1129488D02*
Y1130276D01*
G01Y1135787D02*
Y1136575D01*
G01X169764Y1125728D02*
X164173D01*
G01X169291Y1125925D02*
X168307D01*
G01X169291Y1126319D02*
X168307D01*
G01X151378Y1126339D02*
X158710D01*
G01X158857D02*
X170866D01*
G01X169291Y1126516D02*
X168307D01*
G01X170866Y1127126D02*
X158857D01*
G01X158710D02*
X151378D01*
G01X170866Y1127146D02*
X169764D01*
G01X167323Y1128366D02*
X166339D01*
G01X167323Y1128563D02*
X166339D01*
G01X167323Y1128957D02*
X166339D01*
G01X162205Y1129154D02*
X169370D01*
G01X151378Y1129488D02*
X158710D01*
G01X158857D02*
X170866D01*
G01Y1130276D02*
X158857D01*
G01X158710D02*
X151378D01*
G01X162205Y1130728D02*
X169370D01*
G01X167323Y1130925D02*
X166339D01*
G01X167323Y1131319D02*
X166339D01*
G01X167323Y1131516D02*
X166339D01*
G01X151378Y1132638D02*
X158710D01*
G01X158857D02*
X170866D01*
G01X167323Y1133366D02*
X166339D01*
G01X170866Y1133425D02*
X158857D01*
G01X158710D02*
X151378D01*
G01X167323Y1133563D02*
X166339D01*
G01X167323Y1133957D02*
X166339D01*
G01X162205Y1134154D02*
X169370D01*
G01X162205Y1135728D02*
X169370D01*
G01X151378Y1135787D02*
X158710D01*
G01X158857D02*
X170866D01*
G01X167323Y1135925D02*
X166339D01*
G01X167323Y1136319D02*
X166339D01*
G01X167323Y1136516D02*
X166339D01*
G01X170866Y1136575D02*
X158857D01*
G01X158710D02*
X151378D01*
G01X167323Y1138366D02*
X166339D01*
G01X167323Y1138563D02*
X166339D01*
G01X169764Y1133760D02*
G03X169370Y1134154I-394J0D01*
G01Y1135728D02*
G03X169764Y1136122I0J394D01*
G01Y1128760D02*
G03X169370Y1129154I-394J0D01*
G01Y1130728D02*
G03X169764Y1131122I0J394D01*
G01Y1138760D02*
G03X169370Y1139154I-394J0D01*
G01X151378Y1107441D02*
Y1108228D01*
G01Y1113740D02*
Y1114528D01*
G01Y1110591D02*
Y1111378D01*
G01Y1116890D02*
Y1117677D01*
G01Y1123189D02*
Y1123976D01*
G01Y1120039D02*
Y1120827D01*
G01X153151Y1107441D02*
Y1108228D01*
G01Y1113740D02*
Y1114528D01*
G01Y1110591D02*
Y1111378D01*
G01Y1116890D02*
Y1117677D01*
G01Y1123189D02*
Y1123976D01*
G01Y1120039D02*
Y1120827D01*
G01X153340Y1123976D02*
Y1123189D01*
G01Y1120827D02*
Y1120039D01*
G01Y1117677D02*
Y1116890D01*
G01Y1114528D02*
Y1113740D01*
G01Y1111378D02*
Y1110591D01*
G01Y1108228D02*
Y1107441D01*
G01X156176Y1123976D02*
Y1123189D01*
G01Y1120827D02*
Y1120039D01*
G01Y1117677D02*
Y1116890D01*
G01Y1114528D02*
Y1113740D01*
G01Y1111378D02*
Y1110591D01*
G01Y1108228D02*
Y1107441D01*
G01X157118D02*
Y1108228D01*
G01Y1113740D02*
Y1114528D01*
G01Y1110591D02*
Y1111378D01*
G01Y1116890D02*
Y1117677D01*
G01Y1123189D02*
Y1123976D01*
G01Y1120039D02*
Y1120827D01*
G01X158710Y1107441D02*
Y1108228D01*
G01Y1113740D02*
Y1114528D01*
G01Y1110591D02*
Y1111378D01*
G01Y1116890D02*
Y1117677D01*
G01Y1123189D02*
Y1123976D01*
G01Y1120039D02*
Y1120827D01*
G01X158857Y1107441D02*
Y1108228D01*
G01Y1113740D02*
Y1114528D01*
G01Y1110591D02*
Y1111378D01*
G01Y1116890D02*
Y1117677D01*
G01Y1123189D02*
Y1123976D01*
G01Y1120039D02*
Y1120827D01*
G01X159796Y1126339D02*
Y1123976D01*
G01Y1123189D02*
Y1120827D01*
G01Y1120039D02*
Y1117677D01*
G01Y1116890D02*
Y1114528D01*
G01Y1113740D02*
Y1111378D01*
G01Y1110591D02*
Y1108228D01*
G01X161524Y1107441D02*
Y1108228D01*
G01Y1113740D02*
Y1114528D01*
G01Y1110591D02*
Y1111378D01*
G01Y1116890D02*
Y1117677D01*
G01Y1123189D02*
Y1123976D01*
G01Y1120039D02*
Y1120827D01*
G01X162205Y1120728D02*
Y1119154D01*
G01Y1115728D02*
Y1114154D01*
G01Y1110728D02*
Y1109154D01*
G01X163176Y1123976D02*
Y1123189D01*
G01Y1120827D02*
Y1120039D01*
G01Y1117677D02*
Y1116890D01*
G01Y1114528D02*
Y1113740D01*
G01Y1111378D02*
Y1110591D01*
G01Y1108228D02*
Y1107441D01*
G01X164173Y1125728D02*
Y1124154D01*
G01X165159Y1123976D02*
Y1123189D01*
G01Y1120827D02*
Y1120039D01*
G01Y1117677D02*
Y1116890D01*
G01Y1114528D02*
Y1113740D01*
G01Y1111378D02*
Y1110591D01*
G01Y1108228D02*
Y1107441D01*
G01X165354Y1120728D02*
Y1119154D01*
G01Y1115728D02*
Y1114154D01*
G01Y1110728D02*
Y1109154D01*
G01X166339Y1121516D02*
Y1118366D01*
G01Y1116516D02*
Y1113366D01*
G01Y1111516D02*
Y1108366D01*
G01X167323Y1125728D02*
Y1124154D01*
G01Y1121516D02*
Y1118366D01*
G01Y1116516D02*
Y1113366D01*
G01Y1111516D02*
Y1108366D01*
G01X168307Y1126516D02*
Y1123366D01*
G01Y1120728D02*
Y1119154D01*
G01Y1115728D02*
Y1114154D01*
G01Y1110728D02*
Y1109154D01*
G01X168521Y1107441D02*
Y1108228D01*
G01Y1113740D02*
Y1114528D01*
G01Y1110591D02*
Y1111378D01*
G01Y1116890D02*
Y1117677D01*
G01Y1123189D02*
Y1123976D01*
G01Y1120039D02*
Y1120827D01*
G01X168898Y1107441D02*
Y1108228D01*
G01Y1113740D02*
Y1114528D01*
G01Y1110591D02*
Y1111378D01*
G01Y1116890D02*
Y1117677D01*
G01Y1123189D02*
Y1123976D01*
G01Y1120039D02*
Y1120827D01*
G01X168924Y1107441D02*
Y1108228D01*
G01Y1113740D02*
Y1114528D01*
G01Y1110591D02*
Y1111378D01*
G01Y1116890D02*
Y1117677D01*
G01Y1123189D02*
Y1123976D01*
G01Y1120039D02*
Y1120827D01*
G01X169291Y1126516D02*
Y1123366D01*
G01X162205Y1105728D02*
X169370D01*
G01X167323Y1105925D02*
X166339D01*
G01X167323Y1106319D02*
X166339D01*
G01X167323Y1106516D02*
X166339D01*
G01X151378Y1107441D02*
X158710D01*
G01X158857D02*
X170866D01*
G01Y1108228D02*
X158857D01*
G01X158710D02*
X151378D01*
G01X167323Y1108366D02*
X166339D01*
G01X167323Y1108563D02*
X166339D01*
G01X167323Y1108957D02*
X166339D01*
G01X162205Y1109154D02*
X169370D01*
G01X151378Y1110591D02*
X158710D01*
G01X158857D02*
X170866D01*
G01X162205Y1110728D02*
X169370D01*
G01X167323Y1110925D02*
X166339D01*
G01X167323Y1111319D02*
X166339D01*
G01X170866Y1111378D02*
X158857D01*
G01X158710D02*
X151378D01*
G01X167323Y1111516D02*
X166339D01*
G01X167323Y1113366D02*
X166339D01*
G01X167323Y1113563D02*
X166339D01*
G01X151378Y1113740D02*
X158710D01*
G01X158857D02*
X170866D01*
G01X167323Y1113957D02*
X166339D01*
G01X162205Y1114154D02*
X169370D01*
G01X170866Y1114528D02*
X158857D01*
G01X158710D02*
X151378D01*
G01X162205Y1115728D02*
X169370D01*
G01X167323Y1115925D02*
X166339D01*
G01X167323Y1116319D02*
X166339D01*
G01X167323Y1116516D02*
X166339D01*
G01X151378Y1116890D02*
X158710D01*
G01X158857D02*
X170866D01*
G01Y1117677D02*
X158857D01*
G01X158710D02*
X151378D01*
G01X167323Y1118366D02*
X166339D01*
G01X167323Y1118563D02*
X166339D01*
G01X167323Y1118957D02*
X166339D01*
G01X162205Y1119154D02*
X169370D01*
G01X151378Y1120039D02*
X158710D01*
G01X158857D02*
X170866D01*
G01X162205Y1120728D02*
X169370D01*
G01X170866Y1120827D02*
X158857D01*
G01X158710D02*
X151378D01*
G01X167323Y1120925D02*
X166339D01*
G01X167323Y1121319D02*
X166339D01*
G01X167323Y1121516D02*
X166339D01*
G01X170866Y1122736D02*
X169764D01*
G01X151378Y1123189D02*
X158710D01*
G01X158857D02*
X170866D01*
G01X169291Y1123366D02*
X168307D01*
G01X169291Y1123563D02*
X168307D01*
G01X169291Y1123957D02*
X168307D01*
G01X170866Y1123976D02*
X158857D01*
G01X158710D02*
X151378D01*
G01X169764Y1124154D02*
X164173D01*
G01X169764Y1108760D02*
G03X169370Y1109154I-394J0D01*
G01Y1110728D02*
G03X169764Y1111122I0J394D01*
G01Y1113760D02*
G03X169370Y1114154I-394J0D01*
G01Y1115728D02*
G03X169764Y1116122I0J394D01*
G01Y1118760D02*
G03X169370Y1119154I-394J0D01*
G01Y1120728D02*
G03X169764Y1121122I0J394D01*
G01X169370Y1105728D02*
G03X169764Y1106122I0J394D01*
G01X149606Y1157028D02*
Y1143150D01*
G01X149924Y1148681D02*
Y1143150D01*
G01X150399Y1145925D02*
Y1143150D01*
G01X149606D02*
X169764D01*
G01X150399Y1145925D02*
X170866D01*
G01X149606Y1146909D02*
X173228D01*
G01X199606Y1148681D02*
X149606D01*
G01X173228Y1149311D02*
X149606D01*
G01X173228Y1151280D02*
X149606D01*
G01X173228Y1155059D02*
X149606D01*
G01Y1157028D02*
X203543D01*
G01X172298Y1164843D02*
Y1163268D01*
G01X172554Y1155626D02*
Y1153101D01*
G01X172669Y1163268D02*
Y1164843D01*
G01X173228Y1155059D02*
Y1151280D01*
G01Y1149311D02*
Y1146909D01*
G01X173982Y1152176D02*
Y1151619D01*
G01X173984Y1153101D02*
Y1155626D01*
G01X173991Y1164843D02*
Y1163268D01*
G01X174016Y1164843D02*
Y1163268D01*
G01X174050D02*
Y1164843D01*
G01X175424Y1155626D02*
Y1151619D01*
G01X177165Y1157028D02*
Y1148681D01*
G01X179134Y1144744D02*
Y1142972D01*
G01X179449Y1143563D02*
Y1169961D01*
G01Y1143563D02*
X172913D01*
G01X199606Y1143760D02*
X181102D01*
G01X175424Y1151619D02*
X173982D01*
G01X175424Y1155626D02*
X173984D01*
G01X203543Y1155846D02*
X177165D01*
G01X171201Y1152170D02*
G03X173982Y1152176I1388J1207D01*
G01X173425Y1162480D02*
G03Y1165630I0J1575D01*
G01X172554Y1153101D02*
G03X173984I715J0D01*
G01X164311Y1156142D02*
X164208Y1155773D01*
X164112Y1155443D01*
X164032Y1155181D01*
X163980Y1155015D01*
X163962Y1154961D01*
G01X160054Y1149528D02*
X160035Y1149472D01*
X159983Y1149306D01*
X159905Y1149048D01*
X159809Y1148721D01*
X159704Y1148346D01*
G01X154432Y1155626D02*
X153641Y1154348D01*
G01X155840Y1155626D02*
X154398Y1153479D01*
G01X153444Y1152605D02*
X152755Y1151619D01*
G01X152668Y1153470D02*
X151373Y1151619D01*
G01X151378Y1138937D02*
Y1139724D01*
G01X153151Y1138937D02*
Y1139724D01*
G01X153340D02*
Y1138937D01*
G01X156176Y1139724D02*
Y1138937D01*
G01X156253Y1145925D02*
Y1148681D01*
G01X157118Y1138937D02*
Y1139724D01*
G01X158710Y1138937D02*
Y1139724D01*
G01X158857Y1138937D02*
Y1139724D01*
G01X159796Y1141398D02*
Y1139724D01*
G01X161012Y1155626D02*
Y1149872D01*
G01X161524Y1138937D02*
Y1139724D01*
G01X162205Y1140728D02*
Y1139154D01*
G01X162472Y1155626D02*
Y1149872D01*
G01X163071Y1169961D02*
Y1157028D01*
G01X163176Y1139724D02*
Y1138937D01*
G01X164127Y1145925D02*
Y1148681D01*
G01X164766Y1146378D02*
Y1146319D01*
G01X165159Y1139724D02*
Y1138937D01*
G01X165354Y1140728D02*
Y1139154D01*
G01X167323Y1148681D02*
Y1146378D01*
G01X168271Y1155626D02*
Y1152696D01*
G01X168307Y1140728D02*
Y1139154D01*
G01X168469Y1164843D02*
Y1163268D01*
G01X168504D02*
Y1164843D01*
G01X168521Y1138937D02*
Y1139724D01*
G01X168528Y1163268D02*
Y1164843D01*
G01X168898Y1138937D02*
Y1139724D01*
G01X168924Y1138937D02*
Y1139724D01*
G01X169664Y1155626D02*
Y1153101D01*
G01X169851Y1164843D02*
Y1163268D01*
G01X170221D02*
Y1164843D01*
G01X171094Y1153101D02*
Y1155626D01*
G01X164766Y1146319D02*
X164511Y1145925D01*
G01X153444Y1152605D02*
X154050Y1151619D01*
G01X151347Y1155626D02*
X152668Y1153470D01*
G01X152896Y1155626D02*
X153641Y1154348D01*
G01X160054Y1154961D02*
X160035Y1155017D01*
X159983Y1155182D01*
X159904Y1155441D01*
X159809Y1155768D01*
X159704Y1156142D01*
G01X163962Y1149528D02*
X163980Y1149472D01*
X164032Y1149306D01*
X164111Y1149048D01*
X164207Y1148720D01*
X164311Y1148346D01*
G01X154398Y1153479D02*
X155667Y1151619D01*
G01X151378Y1138937D02*
X158710D01*
G01X158857D02*
X170866D01*
G01X167323Y1138957D02*
X166339D01*
G01X162205Y1139154D02*
X169370D01*
G01X170866Y1139724D02*
X158857D01*
G01X158710D02*
X151378D01*
G01X162205Y1140728D02*
X169370D01*
G01X167323Y1140925D02*
X166339D01*
G01X167323Y1141319D02*
X166339D01*
G01X165748Y1141398D02*
X156763D01*
G01X167323Y1141516D02*
X166339D01*
G01X169764Y1142972D02*
X179134D01*
G01X201575Y1144154D02*
X170866D01*
G01X169764Y1144744D02*
X179134D01*
G01X164766Y1146319D02*
X170866D01*
G01X164766Y1146378D02*
X170866D01*
G01X159704Y1148346D02*
X164311D01*
G01X163962Y1149528D02*
X160054D01*
G01X162472Y1149872D02*
X161012D01*
G01X155667Y1151619D02*
X154050D01*
G01X152755D02*
X151373D01*
G01X158865Y1153201D02*
X157440D01*
G01X158866Y1154026D02*
X155867D01*
G01X157500Y1154470D02*
X155997D01*
G01X160054Y1154961D02*
X163962D01*
G01X169664Y1155626D02*
X168271D01*
G01X172554D02*
X171094D01*
G01X162472D02*
X161012D01*
G01X155840D02*
X154432D01*
G01X152896D02*
X151347D01*
G01X164311Y1156142D02*
X159704D01*
G01X179449Y1159783D02*
X163071D01*
G01X173425Y1162480D02*
X169094D01*
G01X174050Y1163268D02*
X168469D01*
G01Y1164843D02*
X174050D01*
G01X169094Y1165630D02*
X173425D01*
G01X179449Y1169961D02*
X163071D01*
G01X158425Y1155825D02*
G03X156840Y1155539I-264J-3073D01*
G01X157440Y1153201D02*
G03X158865I713J-83D01*
G01X160247Y1152792D02*
G03X160421Y1153453I-4018J1411D01*
G01D02*
G03Y1153950I-3524J249D01*
G01X155867Y1154026D02*
G03X156206Y1152583I3015J-53D01*
G01X160421Y1153948D02*
G03X160159Y1154811I-2971J-431D01*
G01X157440Y1151610D02*
G03X159082Y1151654I755J2475D01*
G01X160161Y1154808D02*
G03X158422Y1155826I-1807J-1093D01*
G01X159082Y1151654D02*
G03X160247Y1152792I-728J1911D01*
G01X156205Y1152583D02*
G03X157439Y1151610I1735J931D01*
G01X156840Y1155539D02*
G03X155997Y1154470I704J-1422D01*
G01X158865Y1154026D02*
G03X158091Y1154835I-792J17D01*
G01D02*
G03X157500Y1154470I-9J-646D01*
G01X159704Y1156142D02*
G03Y1148346I2304J-3898D01*
G01X164311D02*
G03Y1156142I-2303J3898D01*
G01X165512Y1152244D02*
G03I-3504J0D01*
G01X163962Y1149528D02*
G03Y1154961I-1954J2716D01*
G01X160054D02*
G03Y1149528I1954J-2717D01*
G01X164173Y1152244D02*
G03I-2165J0D01*
G01X163771Y1151972D02*
G03X166817I1523J2362D01*
G01X166816Y1155417D02*
G03X163770Y1155415I-1521J-2363D01*
G01X163249Y1154850D02*
G03X163250Y1152537I2163J-1156D01*
G01X167338Y1152538D02*
G03X167337Y1154852I-2163J1156D01*
G01X166065Y1152832D02*
G03Y1154517I-2236J843D01*
G01X166817Y1151973D02*
G03X167338Y1152538I-830J1288D01*
G01X163250Y1152537D02*
G03X163771Y1151972I1351J723D01*
G01X163770Y1155415D02*
G03X163249Y1154850I830J-1288D01*
G01X167337Y1154852D02*
G03X166816Y1155417I-1351J-723D01*
G01X164592Y1152832D02*
G03X166065I737J277D01*
G01Y1154517D02*
G03X164592I-737J-278D01*
G01X169370Y1140728D02*
G03X169764Y1141122I0J394D01*
G01X164592Y1154517D02*
G03Y1152832I2236J-842D01*
G01X169094Y1165630D02*
G03Y1162480I0J-1575D01*
G01X168271Y1152696D02*
G03X168565Y1152026I913J1D01*
G01D02*
G03X171201Y1152170I1248J1351D01*
G01X169664Y1153101D02*
G03X171094I715J0D01*
G01X151378Y1427913D02*
Y1428701D01*
G01X153151Y1427913D02*
Y1428701D01*
G01X153340D02*
Y1427913D01*
G01X156176Y1428701D02*
Y1427913D01*
G01X157118D02*
Y1428701D01*
G01X158710Y1427913D02*
Y1428701D01*
G01X158857Y1427913D02*
Y1428701D01*
G01X159796Y1431063D02*
Y1428701D01*
G01Y1427913D02*
Y1425551D01*
G01X161524Y1427913D02*
Y1428701D01*
G01X162205Y1431240D02*
Y1429665D01*
G01X163176Y1428701D02*
Y1427913D01*
G01X165159Y1428701D02*
Y1427913D01*
G01X165354Y1431240D02*
Y1429665D01*
G01X166339Y1432028D02*
Y1428878D01*
G01X167323Y1432028D02*
Y1428878D01*
G01X168307Y1431240D02*
Y1429665D01*
G01X168521Y1427913D02*
Y1428701D01*
G01X168898Y1427913D02*
Y1428701D01*
G01X168924Y1427913D02*
Y1428701D01*
G01X170866Y1425551D02*
X158857D01*
G01X158710D02*
X151378D01*
G01X162205Y1426240D02*
X169370D01*
G01X167323Y1426437D02*
X166339D01*
G01X167323Y1426831D02*
X166339D01*
G01X167323Y1427028D02*
X166339D01*
G01X151378Y1427913D02*
X158710D01*
G01X158857D02*
X170866D01*
G01Y1428701D02*
X158857D01*
G01X158710D02*
X151378D01*
G01X167323Y1428878D02*
X166339D01*
G01X167323Y1429075D02*
X166339D01*
G01X167323Y1429469D02*
X166339D01*
G01X162205Y1429665D02*
X169370D01*
G01Y1426240D02*
G03X169764Y1426634I0J394D01*
G01Y1429272D02*
G03X169370Y1429665I-394J-1D01*
G01X149606Y1417047D02*
Y1403366D01*
G01X149924Y1417047D02*
Y1411713D01*
G01X150399Y1417047D02*
Y1414469D01*
G01X203543Y1403366D02*
X149606D01*
G01X173228Y1405335D02*
X149606D01*
G01X173228Y1409114D02*
X149606D01*
G01Y1411083D02*
X173228D01*
G01X199606Y1411713D02*
X149606D01*
G01X173228Y1413524D02*
X149606D01*
G01X150399Y1414469D02*
X170866D01*
G01X169764Y1417047D02*
X149606D01*
G01X172179Y1420512D02*
X171918Y1420170D01*
G01X172441Y1420085D02*
X172615Y1420256D01*
G01X174183Y1420938D02*
X173834Y1420597D01*
G01X173486Y1418294D02*
X173834Y1418635D01*
G01X175315Y1418806D02*
X175054Y1418550D01*
G01X172528Y1420768D02*
X172179Y1420512D01*
G01X174357Y1420426D02*
X174618Y1420597D01*
G01X175141Y1418038D02*
X175577Y1418294D01*
G01X172615Y1420256D02*
X172789Y1420341D01*
G01X174531Y1421109D02*
X174183Y1420938D01*
G01X172353Y1419829D02*
X172441Y1420085D01*
G01X173573Y1419317D02*
X173486Y1419061D01*
G01X173834Y1420597D02*
X173660Y1420256D01*
G01X173834Y1418635D02*
X174009Y1418976D01*
G01X175577Y1418294D02*
X175838Y1418720D01*
G01X174183Y1420170D02*
X174357Y1420426D01*
G01X173486Y1419061D02*
X173311Y1418806D01*
G01X172789Y1420853D02*
X172528Y1420768D01*
G01X173311Y1418806D02*
X173050Y1418720D01*
G01X175054Y1418550D02*
X174793Y1418465D01*
G01X171918Y1420170D02*
X171831Y1419744D01*
G01X173660Y1420256D02*
X173573Y1419829D01*
G01X175838Y1418720D02*
X175925Y1419147D01*
G01X174096Y1419829D02*
X174183Y1420170D01*
G01X174009Y1418976D02*
X174096Y1419317D01*
G01X175402Y1419147D02*
X175315Y1418806D01*
G01X171690Y1410492D02*
Y1409754D01*
G01X171831Y1419744D02*
Y1419317D01*
G01Y1422303D02*
Y1422815D01*
G01X172298Y1397126D02*
Y1395551D01*
G01X172353Y1419317D02*
Y1419829D01*
G01X172669Y1395551D02*
Y1397126D01*
G01X172789Y1420341D02*
Y1420853D01*
G01X172835Y1378051D02*
Y1376083D01*
G01Y1378642D02*
Y1380610D01*
G01X172913Y1416831D02*
Y1549075D01*
G01X173228Y1413524D02*
Y1411083D01*
G01Y1409114D02*
Y1405335D01*
G01Y1380906D02*
Y1375787D01*
G01X173425D02*
Y1380906D01*
G01X173573Y1419829D02*
Y1419317D01*
G01X173991Y1397126D02*
Y1395551D01*
G01X174016Y1397126D02*
Y1395551D01*
G01X174050D02*
Y1397126D01*
G01X174096Y1419317D02*
Y1419829D01*
G01X174409Y1375787D02*
Y1376378D01*
G01Y1380315D02*
Y1380906D01*
G01Y1377559D02*
Y1379134D01*
G01X174793Y1418465D02*
Y1417953D01*
G01X174882Y1433248D02*
Y1416831D01*
G01X175402Y1419829D02*
Y1419147D01*
G01X175529Y1409828D02*
Y1410492D01*
G01X175925Y1422815D02*
Y1422303D01*
G01Y1419147D02*
Y1419829D01*
G01X175984Y1380610D02*
Y1378642D01*
G01Y1376083D02*
Y1378051D01*
G01X177165Y1403366D02*
Y1411713D01*
G01X179134Y1417421D02*
Y1415650D01*
G01X179449Y1390433D02*
Y1416831D01*
G01X181102Y1549272D02*
Y1416634D01*
G01X171831Y1419317D02*
X171918Y1418976D01*
G01X175315Y1420170D02*
X175402Y1419829D01*
G01X175925D02*
X175838Y1420256D01*
G01X172441Y1419061D02*
X172353Y1419317D01*
G01X171918Y1418976D02*
X172092Y1418635D01*
G01X175838Y1420256D02*
X175664Y1420597D01*
G01X172615Y1418806D02*
X172441Y1419061D01*
G01X175141Y1420426D02*
X175315Y1420170D01*
G01X172092Y1418635D02*
X172441Y1418294D01*
G01X175664Y1420597D02*
X175315Y1420938D01*
G01X172441Y1421791D02*
X171831Y1422303D01*
G01X172528D02*
X173137Y1421791D01*
G01X175315Y1420938D02*
X174967Y1421109D01*
G01X174880Y1420597D02*
X175141Y1420426D01*
G01X172876Y1418720D02*
X172615Y1418806D01*
G01X172835Y1376083D02*
X175984D01*
G01Y1378051D02*
X172835D01*
G01X175984Y1378642D02*
X172835D01*
G01Y1380610D02*
X175984D01*
G01X172441Y1418294D02*
X172789Y1418209D01*
G01X177165Y1404547D02*
X203543D01*
G01X172428Y1404587D02*
X173314D01*
G01X171690Y1409754D02*
X174643D01*
G01X175529Y1410492D02*
X171690D01*
G01X199606Y1416634D02*
X181102D01*
G01X179449Y1416831D02*
X172913D01*
G01X172789Y1418209D02*
X173137D01*
G01X173050Y1418720D02*
X172876D01*
G01X174618Y1420597D02*
X174880D01*
G01X174967Y1421109D02*
X174531D01*
G01X173137Y1421791D02*
X172441D01*
G01X175925Y1422303D02*
X172528D01*
G01X171831Y1422815D02*
X175925D01*
G01X174793Y1417953D02*
X175141Y1418038D01*
G01X173137Y1418209D02*
X173486Y1418294D01*
G01X175529Y1409828D02*
G03X173314Y1404587I7142J-6107D01*
G01X174643Y1409754D02*
G03X172428Y1404587I6937J-6032D01*
G01X173425Y1394764D02*
G03Y1397913I0J1575D01*
G01X174409Y1380315D02*
G03Y1379134I0J-591D01*
G01Y1377559D02*
G03Y1376378I0J-591D01*
G01X159453Y1407843D02*
X159776Y1408263D01*
X159938Y1408746D01*
X159917Y1409250D01*
X159713Y1409728D01*
X159347Y1410131D01*
X158841Y1410398D01*
X158250Y1410492D01*
X157660Y1410395D01*
X157158Y1410126D01*
X156794Y1409722D01*
X156593Y1409244D01*
X156573Y1408739D01*
X156737Y1408258D01*
X157057Y1407843D01*
G01X169229Y1408380D02*
X167667Y1406853D01*
G01X157057Y1407843D02*
X156606Y1407403D01*
X156336Y1406867D01*
X156265Y1406297D01*
X156407Y1405733D01*
X156754Y1405208D01*
X157281Y1404815D01*
X157924Y1404611D01*
X158603Y1404614D01*
X159243Y1404822D01*
X159766Y1405218D01*
X160107Y1405741D01*
X160245Y1406303D01*
X160174Y1406870D01*
X159904Y1407404D01*
G01X162225Y1407843D02*
X161773Y1407403D01*
X161503Y1406867D01*
X161433Y1406297D01*
X161574Y1405733D01*
X161921Y1405208D01*
X162448Y1404815D01*
X163091Y1404611D01*
X163770Y1404614D01*
X164411Y1404822D01*
X164933Y1405218D01*
X165275Y1405741D01*
X165413Y1406303D01*
X165341Y1406870D01*
X165071Y1407404D01*
G01X169801Y1407855D02*
X168172Y1406309D01*
G01X157832Y1407387D02*
X157472Y1407152D01*
X157233Y1406802D01*
X157148Y1406398D01*
X157231Y1405996D01*
X157467Y1405643D01*
X157830Y1405404D01*
X158255Y1405319D01*
G01X158678Y1405403D02*
X159039Y1405639D01*
X159277Y1405989D01*
X159363Y1406393D01*
X159280Y1406794D01*
X159043Y1407147D01*
X158680Y1407387D01*
X158255Y1407472D01*
G01X163000Y1407387D02*
X162639Y1407152D01*
X162401Y1406802D01*
X162315Y1406398D01*
X162398Y1405996D01*
X162634Y1405643D01*
X162998Y1405404D01*
X163422Y1405319D01*
G01X163846Y1405403D02*
X164206Y1405639D01*
X164444Y1405989D01*
X164530Y1406393D01*
X164447Y1406794D01*
X164211Y1407147D01*
X163847Y1407387D01*
X163422Y1407472D01*
G01X157906Y1409689D02*
X157624Y1409511D01*
X157437Y1409246D01*
X157370Y1408944D01*
X157434Y1408644D01*
X157619Y1408377D01*
X157905Y1408195D01*
X158255Y1408130D01*
G01X158604Y1408195D02*
X158887Y1408372D01*
X159074Y1408638D01*
X159141Y1408940D01*
X159076Y1409240D01*
X158891Y1409507D01*
X158606Y1409688D01*
X158255Y1409754D01*
G01X163074Y1409689D02*
X162791Y1409511D01*
X162604Y1409246D01*
X162537Y1408944D01*
X162601Y1408644D01*
X162787Y1408377D01*
X163072Y1408195D01*
X163422Y1408130D01*
G01X163772Y1408195D02*
X164054Y1408372D01*
X164241Y1408638D01*
X164308Y1408940D01*
X164244Y1409240D01*
X164058Y1409507D01*
X163773Y1409688D01*
X163422Y1409754D01*
G01X167961Y1409513D02*
X168248Y1409692D01*
X168602Y1409754D01*
G01X169229Y1408380D02*
X169412Y1408646D01*
X169476Y1408943D01*
X169411Y1409241D01*
G01X167961Y1409514D02*
X167771Y1409246D01*
G01X169801Y1407855D02*
X170138Y1408317D01*
X170283Y1408835D01*
X170223Y1409353D01*
X169972Y1409837D01*
X169535Y1410231D01*
X168962Y1410455D01*
X168328Y1410474D01*
X167743Y1410288D01*
X167288Y1409935D01*
X166996Y1409463D01*
X166892Y1408942D01*
G01X164620Y1407843D02*
X164943Y1408263D01*
X165106Y1408746D01*
X165084Y1409250D01*
X164881Y1409728D01*
X164514Y1410131D01*
X164008Y1410398D01*
X163417Y1410492D01*
X162828Y1410395D01*
X162325Y1410126D01*
X161961Y1409722D01*
X161760Y1409244D01*
X161741Y1408739D01*
X161904Y1408258D01*
X162225Y1407843D01*
G01X168028Y1377196D02*
X168121Y1377307D01*
G01Y1377180D02*
X168028Y1377068D01*
G01X166892Y1408942D02*
X166979Y1409419D01*
X167226Y1409861D01*
X167615Y1410213D01*
X168121Y1410433D01*
X168699Y1410489D01*
X169263Y1410367D01*
X169739Y1410084D01*
X170078Y1409680D01*
X170257Y1409223D01*
X170272Y1408743D01*
X170115Y1408272D01*
X169801Y1407855D01*
G01X167772Y1409246D02*
X167704Y1408942D01*
G01X151243Y1410492D02*
Y1409754D01*
G01X151378Y1421614D02*
Y1422402D01*
G01Y1424764D02*
Y1425551D01*
G01X153151Y1421614D02*
Y1422402D01*
G01Y1424764D02*
Y1425551D01*
G01X153340D02*
Y1424764D01*
G01Y1422402D02*
Y1421614D01*
G01X155081Y1409828D02*
Y1410492D01*
G01X156176Y1425551D02*
Y1424764D01*
G01Y1422402D02*
Y1421614D01*
G01X156253Y1411713D02*
Y1414469D01*
G01X156763Y1551437D02*
Y1414469D01*
G01X157118Y1421614D02*
Y1422402D01*
G01Y1424764D02*
Y1425551D01*
G01X158710Y1421614D02*
Y1422402D01*
G01Y1424764D02*
Y1425551D01*
G01X158857Y1421614D02*
Y1422402D01*
G01Y1424764D02*
Y1425551D01*
G01X159796Y1424764D02*
Y1422402D01*
G01Y1421614D02*
Y1419035D01*
G01X161240Y1421457D02*
Y1419488D01*
G01X161524Y1421614D02*
Y1422402D01*
G01Y1424764D02*
Y1425551D01*
G01X162205Y1426240D02*
Y1424665D01*
G01Y1421240D02*
Y1419665D01*
G01X163071Y1403366D02*
Y1390433D01*
G01X163176Y1425551D02*
Y1424764D01*
G01Y1422402D02*
Y1421614D01*
G01X164127Y1411713D02*
Y1414469D01*
G01X164766Y1414075D02*
Y1414016D01*
G01X165159Y1425551D02*
Y1424764D01*
G01Y1422402D02*
Y1421614D01*
G01X165293Y1417047D02*
Y1548661D01*
G01X165354Y1426240D02*
Y1424665D01*
G01Y1421240D02*
Y1419665D01*
G01X165748Y1414469D02*
Y1551437D01*
G01X166339Y1427028D02*
Y1423878D01*
G01Y1422028D02*
Y1418878D01*
G01X166535Y1380610D02*
Y1378642D01*
G01Y1376083D02*
Y1378051D01*
G01X166597Y1405030D02*
Y1404587D01*
G01X166892Y1408942D02*
Y1408794D01*
G01X167323Y1427028D02*
Y1423878D01*
G01Y1422028D02*
Y1418878D01*
G01Y1414016D02*
Y1411713D01*
G01X167704Y1408794D02*
Y1408942D01*
G01X168028Y1377068D02*
Y1377196D01*
G01X168110Y1380906D02*
Y1380315D01*
G01Y1379134D02*
Y1377559D01*
G01Y1376378D02*
Y1375787D01*
G01X168121Y1376559D02*
Y1377180D01*
G01X168215Y1377307D02*
Y1376559D01*
G01X168307Y1426240D02*
Y1424665D01*
G01Y1421240D02*
Y1419665D01*
G01X168469Y1397126D02*
Y1395551D01*
G01X168504D02*
Y1397126D01*
G01X168521Y1421614D02*
Y1422402D01*
G01Y1424764D02*
Y1425551D01*
G01X168528Y1395551D02*
Y1397126D01*
G01X168898Y1421614D02*
Y1422402D01*
G01Y1424764D02*
Y1425551D01*
G01X168924Y1421614D02*
Y1422402D01*
G01Y1424764D02*
Y1425551D01*
G01X169094Y1375787D02*
Y1380906D01*
G01X169291D02*
Y1375787D01*
G01X169311Y1419488D02*
Y1421457D01*
G01X169685Y1378051D02*
Y1376083D01*
G01Y1378642D02*
Y1380610D01*
G01X169764Y1414469D02*
Y1551437D01*
G01X169851Y1397126D02*
Y1395551D01*
G01X170221D02*
Y1397126D01*
G01X170509Y1404587D02*
Y1405325D01*
G01X170866Y1551890D02*
Y1414016D01*
G01X157057Y1407843D02*
X156735Y1408263D01*
X156572Y1408746D01*
X156594Y1409250D01*
X156797Y1409728D01*
X157164Y1410131D01*
X157670Y1410398D01*
X158261Y1410492D01*
X158850Y1410395D01*
X159353Y1410126D01*
X159717Y1409722D01*
X159918Y1409244D01*
X159937Y1408739D01*
X159774Y1408258D01*
X159453Y1407843D01*
G01X162225D02*
X161902Y1408263D01*
X161739Y1408746D01*
X161761Y1409250D01*
X161964Y1409728D01*
X162331Y1410131D01*
X162837Y1410398D01*
X163428Y1410492D01*
X164018Y1410395D01*
X164520Y1410126D01*
X164884Y1409722D01*
X165085Y1409244D01*
X165105Y1408739D01*
X164941Y1408258D01*
X164620Y1407843D01*
G01X169229Y1409504D02*
X169411Y1409239D01*
X169476Y1408941D01*
X169411Y1408644D01*
G01X164511Y1414469D02*
X164766Y1414075D01*
G01X159453Y1407843D02*
X159905Y1407403D01*
X160175Y1406867D01*
X160245Y1406297D01*
X160104Y1405733D01*
X159757Y1405208D01*
X159230Y1404815D01*
X158587Y1404611D01*
X157907Y1404614D01*
X157267Y1404822D01*
X156744Y1405218D01*
X156403Y1405741D01*
X156265Y1406303D01*
X156337Y1406870D01*
X156607Y1407404D01*
G01X164620Y1407843D02*
X165072Y1407403D01*
X165342Y1406867D01*
X165413Y1406297D01*
X165271Y1405733D01*
X164924Y1405208D01*
X164397Y1404815D01*
X163754Y1404611D01*
X163075Y1404614D01*
X162435Y1404822D01*
X161912Y1405218D01*
X161570Y1405741D01*
X161432Y1406303D01*
X161504Y1406870D01*
X161774Y1407404D01*
G01X157906Y1408195D02*
X157624Y1408372D01*
X157437Y1408638D01*
X157370Y1408940D01*
X157434Y1409240D01*
X157619Y1409507D01*
X157905Y1409688D01*
X158255Y1409754D01*
G01X158604Y1409689D02*
X158887Y1409511D01*
X159074Y1409246D01*
X159141Y1408944D01*
X159076Y1408644D01*
X158891Y1408377D01*
X158606Y1408195D01*
X158255Y1408130D01*
G01X168949Y1409685D02*
X169229Y1409504D01*
G01X157832Y1405403D02*
X157472Y1405639D01*
X157233Y1405989D01*
X157148Y1406393D01*
X157231Y1406794D01*
X157467Y1407147D01*
X157830Y1407387D01*
X158255Y1407472D01*
G01X158678Y1407387D02*
X159039Y1407152D01*
X159277Y1406802D01*
X159363Y1406398D01*
X159280Y1405996D01*
X159043Y1405643D01*
X158680Y1405404D01*
X158255Y1405319D01*
G01X163000Y1405403D02*
X162639Y1405639D01*
X162401Y1405989D01*
X162315Y1406393D01*
X162398Y1406794D01*
X162634Y1407147D01*
X162998Y1407387D01*
X163422Y1407472D01*
G01X163846Y1407387D02*
X164206Y1407152D01*
X164444Y1406802D01*
X164530Y1406398D01*
X164447Y1405996D01*
X164211Y1405643D01*
X163847Y1405404D01*
X163422Y1405319D01*
G01X163074Y1408195D02*
X162791Y1408372D01*
X162604Y1408638D01*
X162537Y1408940D01*
X162601Y1409240D01*
X162787Y1409507D01*
X163072Y1409688D01*
X163422Y1409754D01*
G01X163772Y1409689D02*
X164054Y1409511D01*
X164241Y1409246D01*
X164308Y1408944D01*
X164244Y1408644D01*
X164058Y1408377D01*
X163773Y1408195D01*
X163422Y1408130D01*
G01X168110Y1375787D02*
X174409D01*
G01X169685Y1376083D02*
X166535D01*
G01X168215Y1376559D02*
X168121D01*
G01Y1377307D02*
X168215D01*
G01X166535Y1378051D02*
X169685D01*
G01X166535Y1378642D02*
X169685D01*
G01Y1380610D02*
X166535D01*
G01X174409Y1380906D02*
X168110D01*
G01X168602Y1409754D02*
X168950Y1409685D01*
G01X179449Y1390433D02*
X163071D01*
G01X173425Y1394764D02*
X169094D01*
G01X174050Y1395551D02*
X168469D01*
G01Y1397126D02*
X174050D01*
G01X169094Y1397913D02*
X173425D01*
G01X179449Y1400610D02*
X163071D01*
G01X151981Y1404587D02*
X152867D01*
G01X166597D02*
X170509D01*
G01Y1405325D02*
X167630D01*
G01X166892Y1408794D02*
X167704D01*
G01X151243Y1409754D02*
X154195D01*
G01X155081Y1410492D02*
X151243D01*
G01X170866Y1414016D02*
X164766D01*
G01Y1414075D02*
X170866D01*
G01X169764Y1415650D02*
X179134D01*
G01X170866Y1416240D02*
X201575D01*
G01X169764Y1417421D02*
X179134D01*
G01X167323Y1418878D02*
X166339D01*
G01X165748Y1419035D02*
X156763D01*
G01X167323Y1419075D02*
X166339D01*
G01X167323Y1419469D02*
X166339D01*
G01X161240Y1419488D02*
X169311D01*
G01X162205Y1419665D02*
X169370D01*
G01X162205Y1421240D02*
X169370D01*
G01X167323Y1421437D02*
X166339D01*
G01X169311Y1421457D02*
X161240D01*
G01X151378Y1421614D02*
X158710D01*
G01X158857D02*
X170866D01*
G01X167323Y1421831D02*
X166339D01*
G01X167323Y1422028D02*
X166339D01*
G01X170866Y1422402D02*
X158857D01*
G01X158710D02*
X151378D01*
G01X167323Y1423878D02*
X166339D01*
G01X167323Y1424075D02*
X166339D01*
G01X167323Y1424469D02*
X166339D01*
G01X162205Y1424665D02*
X169370D01*
G01X151378Y1424764D02*
X158710D01*
G01X158857D02*
X170866D01*
G01X155081Y1409828D02*
G03X152866Y1404587I7142J-6107D01*
G01X154195Y1409754D02*
G03X151981Y1404587I6938J-6031D01*
G01X166535Y1408149D02*
G03I-4527J0D01*
G01X165512D02*
G03I-3504J0D01*
G01X165354D02*
G03I-3346J0D01*
G01X164173D02*
G03I-2165J0D01*
G01X167667Y1406853D02*
G03X166597Y1405030I2809J-2874D01*
G01X169094Y1397913D02*
G03Y1394764I0J-1574D01*
G01X168110Y1379134D02*
G03Y1380315I0J591D01*
G01Y1376378D02*
G03Y1377559I0J590D01*
G01X168172Y1406309D02*
G03X167630Y1405325I1276J-1344D01*
G01X169764Y1424272D02*
G03X169370Y1424665I-394J-1D01*
G01X169764Y1419272D02*
G03X169370Y1419665I-394J-1D01*
G01Y1421240D02*
G03X169764Y1421634I0J394D01*
G01X131398Y1496457D02*
Y1495472D01*
G01Y1493898D02*
Y1492913D01*
G01Y1491339D02*
Y1490354D01*
G01Y1488780D02*
Y1487795D01*
G01X135335Y1502165D02*
Y1482087D01*
G01X174882Y1472697D02*
Y1453209D01*
G01Y1450846D02*
Y1435610D01*
G01X199606Y1433248D02*
X172913D01*
G01X199606Y1435610D02*
X172913D01*
G01X200563Y1446850D02*
X181102D01*
G01X199606Y1450846D02*
X172913D01*
G01X199606Y1453189D02*
X181102D01*
G01X195106Y1453209D02*
X172913D01*
G01X151378Y1431063D02*
Y1431850D01*
G01Y1434213D02*
Y1435000D01*
G01Y1440512D02*
Y1441299D01*
G01Y1437362D02*
Y1438150D01*
G01Y1443661D02*
Y1444449D01*
G01Y1449961D02*
Y1450748D01*
G01Y1446811D02*
Y1447598D01*
G01Y1453110D02*
Y1453898D01*
G01Y1459409D02*
Y1460197D01*
G01Y1456260D02*
Y1457047D01*
G01Y1462559D02*
Y1463346D01*
G01X153151Y1431063D02*
Y1431850D01*
G01Y1434213D02*
Y1435000D01*
G01Y1440512D02*
Y1441299D01*
G01Y1437362D02*
Y1438150D01*
G01Y1443661D02*
Y1444449D01*
G01Y1449961D02*
Y1450748D01*
G01Y1446811D02*
Y1447598D01*
G01Y1453110D02*
Y1453898D01*
G01Y1459409D02*
Y1460197D01*
G01Y1456260D02*
Y1457047D01*
G01Y1462559D02*
Y1463346D01*
G01X153340D02*
Y1462559D01*
G01Y1460197D02*
Y1459409D01*
G01Y1457047D02*
Y1456260D01*
G01Y1453898D02*
Y1453110D01*
G01Y1450748D02*
Y1449961D01*
G01Y1447598D02*
Y1446811D01*
G01Y1444449D02*
Y1443661D01*
G01Y1441299D02*
Y1440512D01*
G01Y1438150D02*
Y1437362D01*
G01Y1435000D02*
Y1434213D01*
G01Y1431850D02*
Y1431063D01*
G01X156176Y1463346D02*
Y1462559D01*
G01Y1460197D02*
Y1459409D01*
G01Y1457047D02*
Y1456260D01*
G01Y1453898D02*
Y1453110D01*
G01Y1450748D02*
Y1449961D01*
G01Y1447598D02*
Y1446811D01*
G01Y1444449D02*
Y1443661D01*
G01Y1441299D02*
Y1440512D01*
G01Y1438150D02*
Y1437362D01*
G01Y1435000D02*
Y1434213D01*
G01Y1431850D02*
Y1431063D01*
G01X157118D02*
Y1431850D01*
G01Y1434213D02*
Y1435000D01*
G01Y1440512D02*
Y1441299D01*
G01Y1437362D02*
Y1438150D01*
G01Y1443661D02*
Y1444449D01*
G01Y1449961D02*
Y1450748D01*
G01Y1446811D02*
Y1447598D01*
G01Y1453110D02*
Y1453898D01*
G01Y1459409D02*
Y1460197D01*
G01Y1456260D02*
Y1457047D01*
G01Y1462559D02*
Y1463346D01*
G01X158710Y1431063D02*
Y1431850D01*
G01Y1434213D02*
Y1435000D01*
G01Y1440512D02*
Y1441299D01*
G01Y1437362D02*
Y1438150D01*
G01Y1443661D02*
Y1444449D01*
G01Y1449961D02*
Y1450748D01*
G01Y1446811D02*
Y1447598D01*
G01Y1453110D02*
Y1453898D01*
G01Y1459409D02*
Y1460197D01*
G01Y1456260D02*
Y1457047D01*
G01Y1462559D02*
Y1463346D01*
G01X158857Y1431063D02*
Y1431850D01*
G01Y1434213D02*
Y1435000D01*
G01Y1440512D02*
Y1441299D01*
G01Y1437362D02*
Y1438150D01*
G01Y1443661D02*
Y1444449D01*
G01Y1449961D02*
Y1450748D01*
G01Y1446811D02*
Y1447598D01*
G01Y1453110D02*
Y1453898D01*
G01Y1459409D02*
Y1460197D01*
G01Y1456260D02*
Y1457047D01*
G01Y1462559D02*
Y1463346D01*
G01X159796Y1465709D02*
Y1463346D01*
G01Y1462559D02*
Y1460197D01*
G01Y1459409D02*
Y1457047D01*
G01Y1456260D02*
Y1453898D01*
G01Y1453110D02*
Y1450748D01*
G01Y1449961D02*
Y1447598D01*
G01Y1446811D02*
Y1444449D01*
G01Y1443661D02*
Y1441299D01*
G01Y1440512D02*
Y1438150D01*
G01Y1437362D02*
Y1435000D01*
G01Y1434213D02*
Y1431850D01*
G01X161524Y1431063D02*
Y1431850D01*
G01Y1434213D02*
Y1435000D01*
G01Y1440512D02*
Y1441299D01*
G01Y1437362D02*
Y1438150D01*
G01Y1443661D02*
Y1444449D01*
G01Y1449961D02*
Y1450748D01*
G01Y1446811D02*
Y1447598D01*
G01Y1453110D02*
Y1453898D01*
G01Y1459409D02*
Y1460197D01*
G01Y1456260D02*
Y1457047D01*
G01Y1462559D02*
Y1463346D01*
G01X161874Y1457126D02*
Y1459331D01*
G01X162205Y1451240D02*
Y1449665D01*
G01Y1446240D02*
Y1444665D01*
G01Y1441240D02*
Y1439665D01*
G01Y1436240D02*
Y1434665D01*
G01X163176Y1463346D02*
Y1462559D01*
G01Y1460197D02*
Y1459409D01*
G01Y1457047D02*
Y1456260D01*
G01Y1453898D02*
Y1453110D01*
G01Y1450748D02*
Y1449961D01*
G01Y1447598D02*
Y1446811D01*
G01Y1444449D02*
Y1443661D01*
G01Y1441299D02*
Y1440512D01*
G01Y1438150D02*
Y1437362D01*
G01Y1435000D02*
Y1434213D01*
G01Y1431850D02*
Y1431063D01*
G01X163331Y1453307D02*
Y1457126D01*
G01Y1459331D02*
Y1466575D01*
G01X163739Y1465118D02*
Y1463937D01*
G01Y1461969D02*
Y1460787D01*
G01Y1458819D02*
Y1457638D01*
G01Y1455669D02*
Y1454488D01*
G01X163757Y1459331D02*
Y1457126D01*
G01X163809Y1453307D02*
Y1472598D01*
G01X165159Y1463346D02*
Y1462559D01*
G01Y1460197D02*
Y1459409D01*
G01Y1457047D02*
Y1456260D01*
G01Y1453898D02*
Y1453110D01*
G01Y1450748D02*
Y1449961D01*
G01Y1447598D02*
Y1446811D01*
G01Y1444449D02*
Y1443661D01*
G01Y1441299D02*
Y1440512D01*
G01Y1438150D02*
Y1437362D01*
G01Y1435000D02*
Y1434213D01*
G01Y1431850D02*
Y1431063D01*
G01X165354Y1451240D02*
Y1449665D01*
G01Y1446240D02*
Y1444665D01*
G01Y1441240D02*
Y1439665D01*
G01Y1436240D02*
Y1434665D01*
G01X166339Y1452028D02*
Y1448878D01*
G01Y1447028D02*
Y1443878D01*
G01Y1442028D02*
Y1438878D01*
G01Y1437028D02*
Y1433878D01*
G01X166888Y1465118D02*
Y1463937D01*
G01Y1461969D02*
Y1460787D01*
G01Y1458819D02*
Y1457638D01*
G01Y1455669D02*
Y1454488D01*
G01X167165Y1453307D02*
Y1472598D01*
G01X167323Y1452028D02*
Y1448878D01*
G01Y1447028D02*
Y1443878D01*
G01Y1442028D02*
Y1438878D01*
G01Y1437028D02*
Y1433878D01*
G01X167872Y1453799D02*
Y1472106D01*
G01X168082Y1472598D02*
Y1453307D01*
G01X168307Y1451240D02*
Y1449665D01*
G01Y1446240D02*
Y1444665D01*
G01Y1441240D02*
Y1439665D01*
G01Y1436240D02*
Y1434665D01*
G01X168521Y1431063D02*
Y1431850D01*
G01Y1434213D02*
Y1435000D01*
G01Y1440512D02*
Y1441299D01*
G01Y1437362D02*
Y1438150D01*
G01Y1443661D02*
Y1444449D01*
G01Y1449961D02*
Y1450748D01*
G01Y1446811D02*
Y1447598D01*
G01Y1453110D02*
Y1453898D01*
G01Y1459409D02*
Y1460197D01*
G01Y1456260D02*
Y1457047D01*
G01Y1462559D02*
Y1463346D01*
G01X168583Y1472598D02*
Y1453307D01*
G01X168857Y1465709D02*
Y1463346D01*
G01Y1462559D02*
Y1460197D01*
G01Y1459409D02*
Y1457047D01*
G01Y1456260D02*
Y1453898D01*
G01X168898Y1431063D02*
Y1431850D01*
G01Y1434213D02*
Y1435000D01*
G01Y1440512D02*
Y1441299D01*
G01Y1437362D02*
Y1438150D01*
G01Y1443661D02*
Y1444449D01*
G01Y1449961D02*
Y1450748D01*
G01Y1446811D02*
Y1447598D01*
G01Y1453110D02*
Y1453898D01*
G01Y1459409D02*
Y1460197D01*
G01Y1456260D02*
Y1457047D01*
G01Y1462559D02*
Y1463346D01*
G01X168924Y1431063D02*
Y1431850D01*
G01Y1434213D02*
Y1435000D01*
G01Y1440512D02*
Y1441299D01*
G01Y1437362D02*
Y1438150D01*
G01Y1443661D02*
Y1444449D01*
G01Y1449961D02*
Y1450748D01*
G01Y1446811D02*
Y1447598D01*
G01Y1453110D02*
Y1453898D01*
G01Y1459409D02*
Y1460197D01*
G01Y1456260D02*
Y1457047D01*
G01Y1462559D02*
Y1463346D01*
G01X169370Y1453307D02*
Y1472598D01*
G01X169685D02*
Y1453307D01*
G01X151378Y1431063D02*
X158710D01*
G01X158857D02*
X170866D01*
G01X162205Y1431240D02*
X169370D01*
G01X167323Y1431437D02*
X166339D01*
G01X167323Y1431831D02*
X166339D01*
G01X170866Y1431850D02*
X158857D01*
G01X158710D02*
X151378D01*
G01X167323Y1432028D02*
X166339D01*
G01X167323Y1433878D02*
X166339D01*
G01X167323Y1434075D02*
X166339D01*
G01X151378Y1434213D02*
X158710D01*
G01X158857D02*
X170866D01*
G01X167323Y1434469D02*
X166339D01*
G01X162205Y1434665D02*
X169370D01*
G01X170866Y1435000D02*
X158857D01*
G01X158710D02*
X151378D01*
G01X162205Y1436240D02*
X169370D01*
G01X167323Y1436437D02*
X166339D01*
G01X167323Y1436831D02*
X166339D01*
G01X167323Y1437028D02*
X166339D01*
G01X151378Y1437362D02*
X158710D01*
G01X158857D02*
X170866D01*
G01Y1438150D02*
X158857D01*
G01X158710D02*
X151378D01*
G01X167323Y1438878D02*
X166339D01*
G01X167323Y1439075D02*
X166339D01*
G01X167323Y1439469D02*
X166339D01*
G01X162205Y1439665D02*
X169370D01*
G01X151378Y1440512D02*
X158710D01*
G01X158857D02*
X170866D01*
G01X162205Y1441240D02*
X169370D01*
G01X170866Y1441299D02*
X158857D01*
G01X158710D02*
X151378D01*
G01X167323Y1441437D02*
X166339D01*
G01X167323Y1441831D02*
X166339D01*
G01X167323Y1442028D02*
X166339D01*
G01X151378Y1443661D02*
X158710D01*
G01X158857D02*
X170866D01*
G01X167323Y1443878D02*
X166339D01*
G01X167323Y1444075D02*
X166339D01*
G01X170866Y1444449D02*
X158857D01*
G01X158710D02*
X151378D01*
G01X167323Y1444469D02*
X166339D01*
G01X162205Y1444665D02*
X169370D01*
G01X162205Y1446240D02*
X169370D01*
G01X167323Y1446437D02*
X166339D01*
G01X151378Y1446811D02*
X158710D01*
G01X158857D02*
X170866D01*
G01X167323Y1446831D02*
X166339D01*
G01X167323Y1447028D02*
X166339D01*
G01X170866Y1447598D02*
X158857D01*
G01X158710D02*
X151378D01*
G01X167323Y1448878D02*
X166339D01*
G01X167323Y1449075D02*
X166339D01*
G01X167323Y1449469D02*
X166339D01*
G01X162205Y1449665D02*
X169370D01*
G01X151378Y1449961D02*
X158710D01*
G01X158857D02*
X170866D01*
G01Y1450748D02*
X158857D01*
G01X158710D02*
X151378D01*
G01X162205Y1451240D02*
X169370D01*
G01X167323Y1451437D02*
X166339D01*
G01X167323Y1451831D02*
X166339D01*
G01X167323Y1452028D02*
X166339D01*
G01X151378Y1453110D02*
X158710D01*
G01X158857D02*
X170866D01*
G01Y1453189D02*
X169764D01*
G01X163331Y1453307D02*
X170866D01*
G01X167872Y1453799D02*
X165748D01*
G01X170866Y1453898D02*
X158857D01*
G01X158710D02*
X151378D01*
G01X168857Y1454094D02*
X167872D01*
G01X168857Y1454291D02*
X167872D01*
G01X169764Y1454488D02*
X163739D01*
G01X169764Y1455669D02*
X163739D01*
G01X168857Y1455866D02*
X167872D01*
G01X168857Y1456063D02*
X167872D01*
G01X151378Y1456260D02*
X158710D01*
G01X158857D02*
X170866D01*
G01Y1457047D02*
X158857D01*
G01X158710D02*
X151378D01*
G01X161874Y1457126D02*
X163757D01*
G01X168857Y1457244D02*
X167872D01*
G01X168857Y1457441D02*
X167872D01*
G01X169764Y1457638D02*
X163739D01*
G01X169764Y1458819D02*
X163739D01*
G01X168857Y1459016D02*
X167872D01*
G01X168857Y1459213D02*
X167872D01*
G01X163757Y1459331D02*
X161874D01*
G01X151378Y1459409D02*
X158710D01*
G01X158857D02*
X170866D01*
G01Y1460197D02*
X158857D01*
G01X158710D02*
X151378D01*
G01X168857Y1460394D02*
X167872D01*
G01X168857Y1460591D02*
X167872D01*
G01X169764Y1460787D02*
X163739D01*
G01X169764Y1461969D02*
X163739D01*
G01X168857Y1462165D02*
X167872D01*
G01X168857Y1462362D02*
X167872D01*
G01X151378Y1462559D02*
X158710D01*
G01X158857D02*
X170866D01*
G01Y1463346D02*
X158857D01*
G01X158710D02*
X151378D01*
G01X168857Y1463543D02*
X167872D01*
G01X168857Y1463740D02*
X167872D01*
G01X169764Y1463937D02*
X163739D01*
G01X169764Y1465118D02*
X163739D01*
G01X169370Y1431240D02*
G03X169764Y1431634I0J394D01*
G01Y1434272D02*
G03X169370Y1434665I-394J-1D01*
G01Y1436240D02*
G03X169764Y1436634I0J394D01*
G01Y1439272D02*
G03X169370Y1439665I-394J-1D01*
G01Y1441240D02*
G03X169764Y1441634I0J394D01*
G01Y1444272D02*
G03X169370Y1444665I-394J-1D01*
G01Y1446240D02*
G03X169764Y1446634I0J394D01*
G01Y1449272D02*
G03X169370Y1449665I-394J-1D01*
G01Y1451240D02*
G03X169764Y1451634I0J394D01*
G01X174882Y1493760D02*
Y1510295D01*
G01X199606Y1491398D02*
X172913D01*
G01X199606Y1493760D02*
X172913D01*
G01X174882Y1475059D02*
Y1491398D01*
G01X195106Y1472697D02*
X172913D01*
G01X181102Y1472717D02*
X199606D01*
G01Y1475059D02*
X172913D01*
G01X200563Y1479154D02*
X181102D01*
G01X151378Y1487756D02*
Y1488543D01*
G01Y1490906D02*
Y1491693D01*
G01Y1497205D02*
Y1497992D01*
G01Y1494055D02*
Y1494843D01*
G01Y1500354D02*
Y1501142D01*
G01X153151Y1487756D02*
Y1488543D01*
G01Y1490906D02*
Y1491693D01*
G01Y1497205D02*
Y1497992D01*
G01Y1494055D02*
Y1494843D01*
G01Y1500354D02*
Y1501142D01*
G01X153340D02*
Y1500354D01*
G01Y1497992D02*
Y1497205D01*
G01Y1494843D02*
Y1494055D01*
G01Y1491693D02*
Y1490906D01*
G01Y1488543D02*
Y1487756D01*
G01X156176Y1501142D02*
Y1500354D01*
G01Y1497992D02*
Y1497205D01*
G01Y1494843D02*
Y1494055D01*
G01Y1491693D02*
Y1490906D01*
G01Y1488543D02*
Y1487756D01*
G01X157118D02*
Y1488543D01*
G01Y1490906D02*
Y1491693D01*
G01Y1497205D02*
Y1497992D01*
G01Y1494055D02*
Y1494843D01*
G01Y1500354D02*
Y1501142D01*
G01X158710Y1487756D02*
Y1488543D01*
G01Y1490906D02*
Y1491693D01*
G01Y1497205D02*
Y1497992D01*
G01Y1494055D02*
Y1494843D01*
G01Y1500354D02*
Y1501142D01*
G01X158857Y1487756D02*
Y1488543D01*
G01Y1490906D02*
Y1491693D01*
G01Y1497205D02*
Y1497992D01*
G01Y1494055D02*
Y1494843D01*
G01Y1500354D02*
Y1501142D01*
G01X159796Y1503504D02*
Y1501142D01*
G01Y1500354D02*
Y1497992D01*
G01Y1497205D02*
Y1494843D01*
G01Y1494055D02*
Y1491693D01*
G01Y1490906D02*
Y1488543D01*
G01Y1487756D02*
Y1485394D01*
G01X161524Y1487756D02*
Y1488543D01*
G01Y1490906D02*
Y1491693D01*
G01Y1497205D02*
Y1497992D01*
G01Y1494055D02*
Y1494843D01*
G01Y1500354D02*
Y1501142D01*
G01X162205Y1501240D02*
Y1499665D01*
G01Y1496240D02*
Y1494665D01*
G01X163176Y1501142D02*
Y1500354D01*
G01Y1497992D02*
Y1497205D01*
G01Y1494843D02*
Y1494055D01*
G01Y1491693D02*
Y1490906D01*
G01Y1488543D02*
Y1487756D01*
G01X164173Y1491240D02*
Y1489665D01*
G01X165159Y1501142D02*
Y1500354D01*
G01Y1497992D02*
Y1497205D01*
G01Y1494843D02*
Y1494055D01*
G01Y1491693D02*
Y1490906D01*
G01Y1488543D02*
Y1487756D01*
G01X165354Y1501240D02*
Y1499665D01*
G01Y1496240D02*
Y1494665D01*
G01X166339Y1502028D02*
Y1498878D01*
G01Y1497028D02*
Y1493878D01*
G01X167323Y1502028D02*
Y1498878D01*
G01Y1497028D02*
Y1493878D01*
G01Y1491240D02*
Y1489665D01*
G01X168307Y1501240D02*
Y1499665D01*
G01Y1496240D02*
Y1494665D01*
G01Y1492028D02*
Y1488878D01*
G01X168521Y1487756D02*
Y1488543D01*
G01Y1490906D02*
Y1491693D01*
G01Y1497205D02*
Y1497992D01*
G01Y1494055D02*
Y1494843D01*
G01Y1500354D02*
Y1501142D01*
G01X168898Y1487756D02*
Y1488543D01*
G01Y1490906D02*
Y1491693D01*
G01Y1497205D02*
Y1497992D01*
G01Y1494055D02*
Y1494843D01*
G01Y1500354D02*
Y1501142D01*
G01X168924Y1487756D02*
Y1488543D01*
G01Y1490906D02*
Y1491693D01*
G01Y1497205D02*
Y1497992D01*
G01Y1494055D02*
Y1494843D01*
G01Y1500354D02*
Y1501142D01*
G01X169291Y1492028D02*
Y1488878D01*
G01X170866Y1485394D02*
X158857D01*
G01X158710D02*
X151378D01*
G01X162205Y1486240D02*
X169370D01*
G01X167323Y1486437D02*
X166339D01*
G01X167323Y1486831D02*
X166339D01*
G01X167323Y1487028D02*
X166339D01*
G01X151378Y1487756D02*
X158710D01*
G01X158857D02*
X170866D01*
G01Y1488248D02*
X169764D01*
G01X170866Y1488543D02*
X158857D01*
G01X158710D02*
X151378D01*
G01X169291Y1488878D02*
X168307D01*
G01X169291Y1489075D02*
X168307D01*
G01X169291Y1489469D02*
X168307D01*
G01X169764Y1489665D02*
X164173D01*
G01X151378Y1490906D02*
X158710D01*
G01X158857D02*
X170866D01*
G01X169764Y1491240D02*
X164173D01*
G01X169291Y1491437D02*
X168307D01*
G01X170866Y1491693D02*
X158857D01*
G01X158710D02*
X151378D01*
G01X169291Y1491831D02*
X168307D01*
G01X169291Y1492028D02*
X168307D01*
G01X169764Y1492657D02*
X170866D01*
G01X167323Y1493878D02*
X166339D01*
G01X151378Y1494055D02*
X158710D01*
G01X158857D02*
X170866D01*
G01X167323Y1494075D02*
X166339D01*
G01X167323Y1494469D02*
X166339D01*
G01X162205Y1494665D02*
X169370D01*
G01X170866Y1494843D02*
X158857D01*
G01X158710D02*
X151378D01*
G01X162205Y1496240D02*
X169370D01*
G01X167323Y1496437D02*
X166339D01*
G01X167323Y1496831D02*
X166339D01*
G01X167323Y1497028D02*
X166339D01*
G01X151378Y1497205D02*
X158710D01*
G01X158857D02*
X170866D01*
G01Y1497992D02*
X158857D01*
G01X158710D02*
X151378D01*
G01X167323Y1498878D02*
X166339D01*
G01X167323Y1499075D02*
X166339D01*
G01X167323Y1499469D02*
X166339D01*
G01X162205Y1499665D02*
X169370D01*
G01X151378Y1500354D02*
X158710D01*
G01X158857D02*
X170866D01*
G01Y1501142D02*
X158857D01*
G01X158710D02*
X151378D01*
G01X162205Y1501240D02*
X169370D01*
G01X167323Y1501437D02*
X166339D01*
G01X167323Y1501831D02*
X166339D01*
G01X167323Y1502028D02*
X166339D01*
G01X169370Y1486240D02*
G03X169764Y1486634I0J394D01*
G01Y1499272D02*
G03X169370Y1499665I-394J-1D01*
G01Y1501240D02*
G03X169764Y1501634I0J394D01*
G01Y1494272D02*
G03X169370Y1494665I-394J-1D01*
G01Y1496240D02*
G03X169764Y1496634I0J394D01*
G01X151378Y1468858D02*
Y1469646D01*
G01Y1465709D02*
Y1466496D01*
G01Y1472008D02*
Y1472795D01*
G01Y1478307D02*
Y1479094D01*
G01Y1475157D02*
Y1475945D01*
G01Y1481457D02*
Y1482244D01*
G01Y1484606D02*
Y1485394D01*
G01X153151Y1468858D02*
Y1469646D01*
G01Y1465709D02*
Y1466496D01*
G01Y1472008D02*
Y1472795D01*
G01Y1478307D02*
Y1479094D01*
G01Y1475157D02*
Y1475945D01*
G01Y1481457D02*
Y1482244D01*
G01Y1484606D02*
Y1485394D01*
G01X153340D02*
Y1484606D01*
G01Y1482244D02*
Y1481457D01*
G01Y1479094D02*
Y1478307D01*
G01Y1475945D02*
Y1475157D01*
G01Y1472795D02*
Y1472008D01*
G01Y1469646D02*
Y1468858D01*
G01Y1466496D02*
Y1465709D01*
G01X156176Y1485394D02*
Y1484606D01*
G01Y1482244D02*
Y1481457D01*
G01Y1479094D02*
Y1478307D01*
G01Y1475945D02*
Y1475157D01*
G01Y1472795D02*
Y1472008D01*
G01Y1469646D02*
Y1468858D01*
G01Y1466496D02*
Y1465709D01*
G01X157118Y1468858D02*
Y1469646D01*
G01Y1465709D02*
Y1466496D01*
G01Y1472008D02*
Y1472795D01*
G01Y1478307D02*
Y1479094D01*
G01Y1475157D02*
Y1475945D01*
G01Y1481457D02*
Y1482244D01*
G01Y1484606D02*
Y1485394D01*
G01X158710Y1468858D02*
Y1469646D01*
G01Y1465709D02*
Y1466496D01*
G01Y1472008D02*
Y1472795D01*
G01Y1478307D02*
Y1479094D01*
G01Y1475157D02*
Y1475945D01*
G01Y1481457D02*
Y1482244D01*
G01Y1484606D02*
Y1485394D01*
G01X158857Y1468858D02*
Y1469646D01*
G01Y1465709D02*
Y1466496D01*
G01Y1472008D02*
Y1472795D01*
G01Y1478307D02*
Y1479094D01*
G01Y1475157D02*
Y1475945D01*
G01Y1481457D02*
Y1482244D01*
G01Y1484606D02*
Y1485394D01*
G01X159796Y1484606D02*
Y1482244D01*
G01Y1481457D02*
Y1479094D01*
G01Y1478307D02*
Y1475945D01*
G01Y1475157D02*
Y1472795D01*
G01Y1472008D02*
Y1469646D01*
G01Y1468858D02*
Y1466496D01*
G01X161524Y1468858D02*
Y1469646D01*
G01Y1465709D02*
Y1466496D01*
G01Y1472008D02*
Y1472795D01*
G01Y1478307D02*
Y1479094D01*
G01Y1475157D02*
Y1475945D01*
G01Y1481457D02*
Y1482244D01*
G01Y1484606D02*
Y1485394D01*
G01X161874Y1466575D02*
Y1468780D01*
G01X162205Y1486240D02*
Y1484665D01*
G01Y1481240D02*
Y1479665D01*
G01Y1476240D02*
Y1474665D01*
G01X163176Y1485394D02*
Y1484606D01*
G01Y1482244D02*
Y1481457D01*
G01Y1479094D02*
Y1478307D01*
G01Y1475945D02*
Y1475157D01*
G01Y1472795D02*
Y1472008D01*
G01Y1469646D02*
Y1468858D01*
G01Y1466496D02*
Y1465709D01*
G01X163331Y1468780D02*
Y1472598D01*
G01X163739Y1471417D02*
Y1470236D01*
G01Y1468268D02*
Y1467087D01*
G01X163757Y1468780D02*
Y1466575D01*
G01X165159Y1485394D02*
Y1484606D01*
G01Y1482244D02*
Y1481457D01*
G01Y1479094D02*
Y1478307D01*
G01Y1475945D02*
Y1475157D01*
G01Y1472795D02*
Y1472008D01*
G01Y1469646D02*
Y1468858D01*
G01Y1466496D02*
Y1465709D01*
G01X165354Y1486240D02*
Y1484665D01*
G01Y1481240D02*
Y1479665D01*
G01Y1476240D02*
Y1474665D01*
G01X166339Y1487028D02*
Y1483878D01*
G01Y1482028D02*
Y1478878D01*
G01Y1477028D02*
Y1473878D01*
G01X166888Y1471417D02*
Y1470236D01*
G01Y1468268D02*
Y1467087D01*
G01X167323Y1487028D02*
Y1483878D01*
G01Y1482028D02*
Y1478878D01*
G01Y1477028D02*
Y1473878D01*
G01X168307Y1486240D02*
Y1484665D01*
G01Y1481240D02*
Y1479665D01*
G01Y1476240D02*
Y1474665D01*
G01X168521Y1468858D02*
Y1469646D01*
G01Y1465709D02*
Y1466496D01*
G01Y1472008D02*
Y1472795D01*
G01Y1478307D02*
Y1479094D01*
G01Y1475157D02*
Y1475945D01*
G01Y1481457D02*
Y1482244D01*
G01Y1484606D02*
Y1485394D01*
G01X168857Y1472008D02*
Y1469646D01*
G01Y1468858D02*
Y1466496D01*
G01X168898Y1468858D02*
Y1469646D01*
G01Y1465709D02*
Y1466496D01*
G01Y1472008D02*
Y1472795D01*
G01Y1478307D02*
Y1479094D01*
G01Y1475157D02*
Y1475945D01*
G01Y1481457D02*
Y1482244D01*
G01Y1484606D02*
Y1485394D01*
G01X168924Y1468858D02*
Y1469646D01*
G01Y1465709D02*
Y1466496D01*
G01Y1472008D02*
Y1472795D01*
G01Y1478307D02*
Y1479094D01*
G01Y1475157D02*
Y1475945D01*
G01Y1481457D02*
Y1482244D01*
G01Y1484606D02*
Y1485394D01*
G01X168857Y1465315D02*
X167872D01*
G01X168857Y1465512D02*
X167872D01*
G01X151378Y1465709D02*
X158710D01*
G01X158857D02*
X170866D01*
G01Y1466496D02*
X158857D01*
G01X158710D02*
X151378D01*
G01X161874Y1466575D02*
X163757D01*
G01X168857Y1466693D02*
X167872D01*
G01X168857Y1466890D02*
X167872D01*
G01X169764Y1467087D02*
X163739D01*
G01X169764Y1468268D02*
X163739D01*
G01X168857Y1468465D02*
X167872D01*
G01X168857Y1468661D02*
X167872D01*
G01X163757Y1468780D02*
X161874D01*
G01X151378Y1468858D02*
X158710D01*
G01X158857D02*
X170866D01*
G01Y1469646D02*
X158857D01*
G01X158710D02*
X151378D01*
G01X168857Y1469843D02*
X167872D01*
G01X168857Y1470039D02*
X167872D01*
G01X169764Y1470236D02*
X163739D01*
G01X169764Y1471417D02*
X163739D01*
G01X168857Y1471614D02*
X167872D01*
G01X168857Y1471811D02*
X167872D01*
G01X151378Y1472008D02*
X158710D01*
G01X158857D02*
X170866D01*
G01X167872Y1472106D02*
X165748D01*
G01X170866Y1472598D02*
X163331D01*
G01X170866Y1472717D02*
X169764D01*
G01X170866Y1472795D02*
X158857D01*
G01X158710D02*
X151378D01*
G01X167323Y1473878D02*
X166339D01*
G01X167323Y1474075D02*
X166339D01*
G01X167323Y1474469D02*
X166339D01*
G01X162205Y1474665D02*
X169370D01*
G01X151378Y1475157D02*
X158710D01*
G01X158857D02*
X170866D01*
G01Y1475945D02*
X158857D01*
G01X158710D02*
X151378D01*
G01X162205Y1476240D02*
X169370D01*
G01X167323Y1476437D02*
X166339D01*
G01X167323Y1476831D02*
X166339D01*
G01X167323Y1477028D02*
X166339D01*
G01X151378Y1478307D02*
X158710D01*
G01X158857D02*
X170866D01*
G01X167323Y1478878D02*
X166339D01*
G01X167323Y1479075D02*
X166339D01*
G01X170866Y1479094D02*
X158857D01*
G01X158710D02*
X151378D01*
G01X167323Y1479469D02*
X166339D01*
G01X162205Y1479665D02*
X169370D01*
G01X162205Y1481240D02*
X169370D01*
G01X167323Y1481437D02*
X166339D01*
G01X151378Y1481457D02*
X158710D01*
G01X158857D02*
X170866D01*
G01X167323Y1481831D02*
X166339D01*
G01X167323Y1482028D02*
X166339D01*
G01X170866Y1482244D02*
X158857D01*
G01X158710D02*
X151378D01*
G01X167323Y1483878D02*
X166339D01*
G01X167323Y1484075D02*
X166339D01*
G01X167323Y1484469D02*
X166339D01*
G01X151378Y1484606D02*
X158710D01*
G01X158857D02*
X170866D01*
G01X162205Y1484665D02*
X169370D01*
G01X169764Y1474272D02*
G03X169370Y1474665I-394J-1D01*
G01Y1476240D02*
G03X169764Y1476634I0J394D01*
G01Y1484272D02*
G03X169370Y1484665I-394J-1D01*
G01X169764Y1479272D02*
G03X169370Y1479665I-394J-1D01*
G01Y1481240D02*
G03X169764Y1481634I0J394D01*
G01X111811Y1496267D02*
X111904Y1496378D01*
G01Y1496250D02*
X111811Y1496139D01*
G01D02*
Y1496267D01*
G01X111904Y1495630D02*
Y1496250D01*
G01X111998Y1496378D02*
Y1495630D01*
G01X112697Y1496457D02*
Y1495472D01*
G01Y1493898D02*
Y1492913D01*
G01Y1491339D02*
Y1490354D01*
G01Y1488780D02*
Y1487795D01*
G01X114584Y1496457D02*
Y1495472D01*
G01Y1493898D02*
Y1492913D01*
G01Y1491339D02*
Y1490354D01*
G01Y1488780D02*
Y1487795D01*
G01X114665Y1496457D02*
Y1495472D01*
G01Y1493898D02*
Y1492913D01*
G01Y1491339D02*
Y1490354D01*
G01Y1488780D02*
Y1487795D01*
G01X116060Y1496457D02*
Y1495472D01*
G01Y1493898D02*
Y1492913D01*
G01Y1491339D02*
Y1490354D01*
G01Y1488780D02*
Y1487795D01*
G01X116142Y1496457D02*
Y1495472D01*
G01Y1493898D02*
Y1492913D01*
G01Y1491339D02*
Y1490354D01*
G01Y1488780D02*
Y1487795D01*
G01X116339Y1498228D02*
Y1486024D01*
G01X127756D02*
Y1498228D01*
G01X127953Y1496457D02*
Y1495472D01*
G01Y1493898D02*
Y1492913D01*
G01Y1491339D02*
Y1490354D01*
G01Y1488780D02*
Y1487795D01*
G01X128034Y1496457D02*
Y1495472D01*
G01Y1493898D02*
Y1492913D01*
G01Y1491339D02*
Y1490354D01*
G01Y1488780D02*
Y1487795D01*
G01X129429Y1496457D02*
Y1495472D01*
G01Y1493898D02*
Y1492913D01*
G01Y1491339D02*
Y1490354D01*
G01Y1488780D02*
Y1487795D01*
G01X129511Y1496457D02*
Y1495472D01*
G01Y1493898D02*
Y1492913D01*
G01Y1491339D02*
Y1490354D01*
G01Y1488780D02*
Y1487795D01*
G01X116339Y1486024D02*
X127756D01*
G01X131398Y1487795D02*
X127756D01*
G01X116339D02*
X112697D01*
G01X131398Y1488780D02*
X127756D01*
G01X116339D02*
X112697D01*
G01X131398Y1490354D02*
X127756D01*
G01X116339D02*
X112697D01*
G01X131398Y1491339D02*
X127756D01*
G01X116339D02*
X112697D01*
G01X131398Y1492913D02*
X127756D01*
G01X116339D02*
X112697D01*
G01X131398Y1493898D02*
X127756D01*
G01X116339D02*
X112697D01*
G01X131398Y1495472D02*
X127756D01*
G01X116339D02*
X112697D01*
G01X111998Y1495630D02*
X111904D01*
G01Y1496378D02*
X111998D01*
G01X131398Y1496457D02*
X127756D01*
G01X116339D02*
X112697D01*
G01X127756Y1498228D02*
X116339D01*
G01X118701Y1496063D02*
G03I-591J0D01*
G01X149606Y1562539D02*
Y1548661D01*
G01X149924Y1554193D02*
Y1548661D01*
G01X150399Y1551437D02*
Y1548661D01*
G01X149606D02*
X169764D01*
G01X150399Y1551437D02*
X170866D01*
G01X149606Y1552421D02*
X173228D01*
G01X199606Y1554193D02*
X149606D01*
G01X173228Y1554823D02*
X149606D01*
G01X173228Y1556791D02*
X149606D01*
G01X173228Y1560571D02*
X149606D01*
G01Y1562539D02*
X203543D01*
G01X172298Y1570354D02*
Y1568780D01*
G01X172554Y1561137D02*
Y1558613D01*
G01X172669Y1568780D02*
Y1570354D01*
G01X173228Y1560571D02*
Y1556791D01*
G01Y1554823D02*
Y1552421D01*
G01X173982Y1557687D02*
Y1557131D01*
G01X173984Y1558613D02*
Y1561137D01*
G01X173991Y1570354D02*
Y1568780D01*
G01X174016Y1570354D02*
Y1568780D01*
G01X174050D02*
Y1570354D01*
G01X175424Y1561137D02*
Y1557131D01*
G01X177165Y1562539D02*
Y1554193D01*
G01X179134Y1550256D02*
Y1548484D01*
G01X179449Y1549075D02*
Y1575472D01*
G01Y1549075D02*
X172913D01*
G01X199606Y1549272D02*
X181102D01*
G01X175424Y1557131D02*
X173982D01*
G01X175424Y1561137D02*
X173984D01*
G01X203543Y1561358D02*
X177165D01*
G01X171201Y1557682D02*
G03X173982Y1557687I1388J1207D01*
G01X173425Y1567992D02*
G03Y1571142I0J1575D01*
G01X172554Y1558613D02*
G03X173984I715J0D01*
G01X155840Y1561137D02*
X154398Y1558991D01*
G01X153444Y1558117D02*
X152755Y1557131D01*
G01X152668Y1558982D02*
X151373Y1557131D01*
G01X154432Y1561137D02*
X153641Y1559860D01*
G01X164766Y1551831D02*
X164511Y1551437D01*
G01X164311Y1561654D02*
X164208Y1561285D01*
X164112Y1560955D01*
X164032Y1560693D01*
X163980Y1560527D01*
X163962Y1560472D01*
G01X160054Y1555039D02*
X160035Y1554983D01*
X159983Y1554818D01*
X159905Y1554560D01*
X159809Y1554233D01*
X159704Y1553858D01*
G01X156253Y1551437D02*
Y1554193D01*
G01X161012Y1561137D02*
Y1555383D01*
G01X162472Y1561137D02*
Y1555383D01*
G01X163071Y1575472D02*
Y1562539D01*
G01X164127Y1551437D02*
Y1554193D01*
G01X164766Y1551890D02*
Y1551831D01*
G01X167323Y1554193D02*
Y1551890D01*
G01X168271Y1561137D02*
Y1558208D01*
G01X168469Y1570354D02*
Y1568780D01*
G01X168504D02*
Y1570354D01*
G01X168528Y1568780D02*
Y1570354D01*
G01X169664Y1561137D02*
Y1558613D01*
G01X169851Y1570354D02*
Y1568780D01*
G01X170221D02*
Y1570354D01*
G01X171094Y1558613D02*
Y1561137D01*
G01X160054Y1560472D02*
X160035Y1560528D01*
X159983Y1560694D01*
X159904Y1560952D01*
X159809Y1561280D01*
X159704Y1561654D01*
G01X163962Y1555039D02*
X163980Y1554983D01*
X164032Y1554818D01*
X164111Y1554559D01*
X164207Y1554232D01*
X164311Y1553858D01*
G01X153444Y1558117D02*
X154050Y1557131D01*
G01X151347Y1561137D02*
X152668Y1558982D01*
G01X152896Y1561137D02*
X153641Y1559860D01*
G01X154398Y1558991D02*
X155667Y1557131D01*
G01X162205Y1546240D02*
X169370D01*
G01X167323Y1546437D02*
X166339D01*
G01X167323Y1546831D02*
X166339D01*
G01X165748Y1546909D02*
X156763D01*
G01X167323Y1547028D02*
X166339D01*
G01X169764Y1548484D02*
X179134D01*
G01X201575Y1549665D02*
X170866D01*
G01X169764Y1550256D02*
X179134D01*
G01X164766Y1551831D02*
X170866D01*
G01X164766Y1551890D02*
X170866D01*
G01X159704Y1553858D02*
X164311D01*
G01X163962Y1555039D02*
X160054D01*
G01X162472Y1555383D02*
X161012D01*
G01X155667Y1557131D02*
X154050D01*
G01X152755D02*
X151373D01*
G01X158865Y1558713D02*
X157440D01*
G01X158866Y1559538D02*
X155867D01*
G01X157500Y1559981D02*
X155997D01*
G01X160054Y1560472D02*
X163962D01*
G01X169664Y1561137D02*
X168271D01*
G01X172554D02*
X171094D01*
G01X162472D02*
X161012D01*
G01X155840D02*
X154432D01*
G01X152896D02*
X151347D01*
G01X164311Y1561654D02*
X159704D01*
G01X179449Y1565295D02*
X163071D01*
G01X173425Y1567992D02*
X169094D01*
G01X174050Y1568780D02*
X168469D01*
G01Y1570354D02*
X174050D01*
G01X169094Y1571142D02*
X173425D01*
G01X158425Y1561337D02*
G03X156840Y1561051I-264J-3073D01*
G01X157440Y1558713D02*
G03X158865I713J-83D01*
G01X160247Y1558304D02*
G03X160421Y1558965I-4018J1411D01*
G01D02*
G03Y1559462I-3524J249D01*
G01X155867Y1559538D02*
G03X156206Y1558095I3015J-53D01*
G01X160421Y1559460D02*
G03X160159Y1560322I-2971J-432D01*
G01X157440Y1557122D02*
G03X159082Y1557165I757J2475D01*
G01X160161Y1560320D02*
G03X158422Y1561337I-1807J-1094D01*
G01X159082Y1557165D02*
G03X160247Y1558304I-729J1911D01*
G01X156205Y1558095D02*
G03X157439Y1557122I1735J931D01*
G01X156840Y1561051D02*
G03X155997Y1559981I704J-1422D01*
G01X158865Y1559538D02*
G03X158091Y1560346I-791J17D01*
G01D02*
G03X157500Y1559981I-9J-646D01*
G01X159704Y1561654D02*
G03Y1553858I2304J-3898D01*
G01X164311D02*
G03Y1561654I-2303J3898D01*
G01X165512Y1557756D02*
G03I-3504J0D01*
G01X163962Y1555039D02*
G03Y1560472I-1954J2717D01*
G01X160054D02*
G03Y1555039I1954J-2717D01*
G01X164173Y1557756D02*
G03I-2165J0D01*
G01X166065Y1558344D02*
G03Y1560028I-2237J842D01*
G01X163250Y1558049D02*
G03X163771Y1557484I1351J723D01*
G01X163770Y1560927D02*
G03X163249Y1560361I831J-1288D01*
G01X163771Y1557484D02*
G03X166817I1523J2362D01*
G01X166816Y1560929D02*
G03X163770Y1560927I-1521J-2363D01*
G01X163249Y1560361D02*
G03X163250Y1558049I2163J-1155D01*
G01X167338Y1558050D02*
G03X167337Y1560363I-2163J1156D01*
G01X164592Y1560028D02*
G03Y1558344I2236J-842D01*
G01X169094Y1571142D02*
G03Y1567992I0J-1575D01*
G01X166817Y1557485D02*
G03X167338Y1558050I-830J1288D01*
G01X167337Y1560363D02*
G03X166816Y1560928I-1351J-723D01*
G01X168271Y1558208D02*
G03X168565Y1557537I914J0D01*
G01X164592Y1558344D02*
G03X166065I737J277D01*
G01Y1560028D02*
G03X164592I-737J-277D01*
G01X169370Y1546240D02*
G03X169764Y1546634I0J394D01*
G01X168565Y1557537D02*
G03X171201Y1557682I1248J1352D01*
G01X169664Y1558613D02*
G03X171094I715J0D01*
G01X174882Y1512657D02*
Y1529193D01*
G01Y1531555D02*
Y1549075D01*
G01X199606Y1510295D02*
X172913D01*
G01X199606Y1512657D02*
X172913D01*
G01X199606Y1529193D02*
X172913D01*
G01X199606Y1531555D02*
X172913D01*
G01X151378Y1506654D02*
Y1507441D01*
G01Y1503504D02*
Y1504291D01*
G01Y1509803D02*
Y1510591D01*
G01Y1516102D02*
Y1516890D01*
G01Y1512953D02*
Y1513740D01*
G01Y1519252D02*
Y1520039D01*
G01Y1525551D02*
Y1526339D01*
G01Y1522402D02*
Y1523189D01*
G01Y1528701D02*
Y1529488D01*
G01Y1535000D02*
Y1535787D01*
G01Y1531850D02*
Y1532638D01*
G01Y1538150D02*
Y1538937D01*
G01Y1544449D02*
Y1545236D01*
G01Y1541299D02*
Y1542087D01*
G01X153151Y1506654D02*
Y1507441D01*
G01Y1503504D02*
Y1504291D01*
G01Y1509803D02*
Y1510591D01*
G01Y1516102D02*
Y1516890D01*
G01Y1512953D02*
Y1513740D01*
G01Y1519252D02*
Y1520039D01*
G01Y1525551D02*
Y1526339D01*
G01Y1522402D02*
Y1523189D01*
G01Y1528701D02*
Y1529488D01*
G01Y1535000D02*
Y1535787D01*
G01Y1531850D02*
Y1532638D01*
G01Y1538150D02*
Y1538937D01*
G01Y1544449D02*
Y1545236D01*
G01Y1541299D02*
Y1542087D01*
G01X153340Y1545236D02*
Y1544449D01*
G01Y1542087D02*
Y1541299D01*
G01Y1538937D02*
Y1538150D01*
G01Y1535787D02*
Y1535000D01*
G01Y1532638D02*
Y1531850D01*
G01Y1529488D02*
Y1528701D01*
G01Y1526339D02*
Y1525551D01*
G01Y1523189D02*
Y1522402D01*
G01Y1520039D02*
Y1519252D01*
G01Y1516890D02*
Y1516102D01*
G01Y1513740D02*
Y1512953D01*
G01Y1510591D02*
Y1509803D01*
G01Y1507441D02*
Y1506654D01*
G01Y1504291D02*
Y1503504D01*
G01X156176Y1545236D02*
Y1544449D01*
G01Y1542087D02*
Y1541299D01*
G01Y1538937D02*
Y1538150D01*
G01Y1535787D02*
Y1535000D01*
G01Y1532638D02*
Y1531850D01*
G01Y1529488D02*
Y1528701D01*
G01Y1526339D02*
Y1525551D01*
G01Y1523189D02*
Y1522402D01*
G01Y1520039D02*
Y1519252D01*
G01Y1516890D02*
Y1516102D01*
G01Y1513740D02*
Y1512953D01*
G01Y1510591D02*
Y1509803D01*
G01Y1507441D02*
Y1506654D01*
G01Y1504291D02*
Y1503504D01*
G01X157118Y1506654D02*
Y1507441D01*
G01Y1503504D02*
Y1504291D01*
G01Y1509803D02*
Y1510591D01*
G01Y1516102D02*
Y1516890D01*
G01Y1512953D02*
Y1513740D01*
G01Y1519252D02*
Y1520039D01*
G01Y1525551D02*
Y1526339D01*
G01Y1522402D02*
Y1523189D01*
G01Y1528701D02*
Y1529488D01*
G01Y1535000D02*
Y1535787D01*
G01Y1531850D02*
Y1532638D01*
G01Y1538150D02*
Y1538937D01*
G01Y1544449D02*
Y1545236D01*
G01Y1541299D02*
Y1542087D01*
G01X158710Y1506654D02*
Y1507441D01*
G01Y1503504D02*
Y1504291D01*
G01Y1509803D02*
Y1510591D01*
G01Y1516102D02*
Y1516890D01*
G01Y1512953D02*
Y1513740D01*
G01Y1519252D02*
Y1520039D01*
G01Y1525551D02*
Y1526339D01*
G01Y1522402D02*
Y1523189D01*
G01Y1528701D02*
Y1529488D01*
G01Y1535000D02*
Y1535787D01*
G01Y1531850D02*
Y1532638D01*
G01Y1538150D02*
Y1538937D01*
G01Y1544449D02*
Y1545236D01*
G01Y1541299D02*
Y1542087D01*
G01X158857Y1506654D02*
Y1507441D01*
G01Y1503504D02*
Y1504291D01*
G01Y1509803D02*
Y1510591D01*
G01Y1516102D02*
Y1516890D01*
G01Y1512953D02*
Y1513740D01*
G01Y1519252D02*
Y1520039D01*
G01Y1525551D02*
Y1526339D01*
G01Y1522402D02*
Y1523189D01*
G01Y1528701D02*
Y1529488D01*
G01Y1535000D02*
Y1535787D01*
G01Y1531850D02*
Y1532638D01*
G01Y1538150D02*
Y1538937D01*
G01Y1544449D02*
Y1545236D01*
G01Y1541299D02*
Y1542087D01*
G01X159796Y1546909D02*
Y1545236D01*
G01Y1544449D02*
Y1542087D01*
G01Y1541299D02*
Y1538937D01*
G01Y1538150D02*
Y1535787D01*
G01Y1535000D02*
Y1532638D01*
G01Y1531850D02*
Y1529488D01*
G01Y1528701D02*
Y1526339D01*
G01Y1525551D02*
Y1523189D01*
G01Y1522402D02*
Y1520039D01*
G01Y1519252D02*
Y1516890D01*
G01Y1516102D02*
Y1513740D01*
G01Y1512953D02*
Y1510591D01*
G01Y1509803D02*
Y1507441D01*
G01Y1506654D02*
Y1504291D01*
G01X161524Y1506654D02*
Y1507441D01*
G01Y1503504D02*
Y1504291D01*
G01Y1509803D02*
Y1510591D01*
G01Y1516102D02*
Y1516890D01*
G01Y1512953D02*
Y1513740D01*
G01Y1519252D02*
Y1520039D01*
G01Y1525551D02*
Y1526339D01*
G01Y1522402D02*
Y1523189D01*
G01Y1528701D02*
Y1529488D01*
G01Y1535000D02*
Y1535787D01*
G01Y1531850D02*
Y1532638D01*
G01Y1538150D02*
Y1538937D01*
G01Y1544449D02*
Y1545236D01*
G01Y1541299D02*
Y1542087D01*
G01X162205Y1546240D02*
Y1544665D01*
G01Y1541240D02*
Y1539665D01*
G01Y1536240D02*
Y1534665D01*
G01Y1526240D02*
Y1524665D01*
G01Y1521240D02*
Y1519665D01*
G01Y1516240D02*
Y1514665D01*
G01Y1511240D02*
Y1509665D01*
G01Y1506240D02*
Y1504665D01*
G01X163176Y1545236D02*
Y1544449D01*
G01Y1542087D02*
Y1541299D01*
G01Y1538937D02*
Y1538150D01*
G01Y1535787D02*
Y1535000D01*
G01Y1532638D02*
Y1531850D01*
G01Y1529488D02*
Y1528701D01*
G01Y1526339D02*
Y1525551D01*
G01Y1523189D02*
Y1522402D01*
G01Y1520039D02*
Y1519252D01*
G01Y1516890D02*
Y1516102D01*
G01Y1513740D02*
Y1512953D01*
G01Y1510591D02*
Y1509803D01*
G01Y1507441D02*
Y1506654D01*
G01Y1504291D02*
Y1503504D01*
G01X164173Y1531240D02*
Y1529665D01*
G01X165159Y1545236D02*
Y1544449D01*
G01Y1542087D02*
Y1541299D01*
G01Y1538937D02*
Y1538150D01*
G01Y1535787D02*
Y1535000D01*
G01Y1532638D02*
Y1531850D01*
G01Y1529488D02*
Y1528701D01*
G01Y1526339D02*
Y1525551D01*
G01Y1523189D02*
Y1522402D01*
G01Y1520039D02*
Y1519252D01*
G01Y1516890D02*
Y1516102D01*
G01Y1513740D02*
Y1512953D01*
G01Y1510591D02*
Y1509803D01*
G01Y1507441D02*
Y1506654D01*
G01Y1504291D02*
Y1503504D01*
G01X165354Y1546240D02*
Y1544665D01*
G01Y1541240D02*
Y1539665D01*
G01Y1536240D02*
Y1534665D01*
G01Y1526240D02*
Y1524665D01*
G01Y1521240D02*
Y1519665D01*
G01Y1516240D02*
Y1514665D01*
G01Y1511240D02*
Y1509665D01*
G01Y1506240D02*
Y1504665D01*
G01X166339Y1547028D02*
Y1543878D01*
G01Y1542028D02*
Y1538878D01*
G01Y1537028D02*
Y1533878D01*
G01Y1527028D02*
Y1523878D01*
G01Y1522028D02*
Y1518878D01*
G01Y1517028D02*
Y1513878D01*
G01Y1512028D02*
Y1508878D01*
G01Y1507028D02*
Y1503878D01*
G01X167323Y1547028D02*
Y1543878D01*
G01Y1542028D02*
Y1538878D01*
G01Y1537028D02*
Y1533878D01*
G01Y1531240D02*
Y1529665D01*
G01Y1527028D02*
Y1523878D01*
G01Y1522028D02*
Y1518878D01*
G01Y1517028D02*
Y1513878D01*
G01Y1512028D02*
Y1508878D01*
G01Y1507028D02*
Y1503878D01*
G01X168307Y1546240D02*
Y1544665D01*
G01Y1541240D02*
Y1539665D01*
G01Y1532028D02*
Y1528878D01*
G01Y1536240D02*
Y1534665D01*
G01Y1526240D02*
Y1524665D01*
G01Y1521240D02*
Y1519665D01*
G01Y1516240D02*
Y1514665D01*
G01Y1511240D02*
Y1509665D01*
G01Y1506240D02*
Y1504665D01*
G01X168521Y1506654D02*
Y1507441D01*
G01Y1503504D02*
Y1504291D01*
G01Y1509803D02*
Y1510591D01*
G01Y1516102D02*
Y1516890D01*
G01Y1512953D02*
Y1513740D01*
G01Y1519252D02*
Y1520039D01*
G01Y1525551D02*
Y1526339D01*
G01Y1522402D02*
Y1523189D01*
G01Y1528701D02*
Y1529488D01*
G01Y1535000D02*
Y1535787D01*
G01Y1531850D02*
Y1532638D01*
G01Y1538150D02*
Y1538937D01*
G01Y1544449D02*
Y1545236D01*
G01Y1541299D02*
Y1542087D01*
G01X168898Y1506654D02*
Y1507441D01*
G01Y1503504D02*
Y1504291D01*
G01Y1509803D02*
Y1510591D01*
G01Y1516102D02*
Y1516890D01*
G01Y1512953D02*
Y1513740D01*
G01Y1519252D02*
Y1520039D01*
G01Y1525551D02*
Y1526339D01*
G01Y1522402D02*
Y1523189D01*
G01Y1528701D02*
Y1529488D01*
G01Y1535000D02*
Y1535787D01*
G01Y1531850D02*
Y1532638D01*
G01Y1538150D02*
Y1538937D01*
G01Y1544449D02*
Y1545236D01*
G01Y1541299D02*
Y1542087D01*
G01X168924Y1506654D02*
Y1507441D01*
G01Y1503504D02*
Y1504291D01*
G01Y1509803D02*
Y1510591D01*
G01Y1516102D02*
Y1516890D01*
G01Y1512953D02*
Y1513740D01*
G01Y1519252D02*
Y1520039D01*
G01Y1525551D02*
Y1526339D01*
G01Y1522402D02*
Y1523189D01*
G01Y1528701D02*
Y1529488D01*
G01Y1535000D02*
Y1535787D01*
G01Y1531850D02*
Y1532638D01*
G01Y1538150D02*
Y1538937D01*
G01Y1544449D02*
Y1545236D01*
G01Y1541299D02*
Y1542087D01*
G01X169291Y1532028D02*
Y1528878D01*
G01X151378Y1503504D02*
X158710D01*
G01X158857D02*
X170866D01*
G01X167323Y1503878D02*
X166339D01*
G01X167323Y1504075D02*
X166339D01*
G01X170866Y1504291D02*
X158857D01*
G01X158710D02*
X151378D01*
G01X167323Y1504469D02*
X166339D01*
G01X162205Y1504665D02*
X169370D01*
G01X162205Y1506240D02*
X169370D01*
G01X167323Y1506437D02*
X166339D01*
G01X151378Y1506654D02*
X158710D01*
G01X158857D02*
X170866D01*
G01X167323Y1506831D02*
X166339D01*
G01X167323Y1507028D02*
X166339D01*
G01X170866Y1507441D02*
X158857D01*
G01X158710D02*
X151378D01*
G01X167323Y1508878D02*
X166339D01*
G01X167323Y1509075D02*
X166339D01*
G01X167323Y1509469D02*
X166339D01*
G01X162205Y1509665D02*
X169370D01*
G01X151378Y1509803D02*
X158710D01*
G01X158857D02*
X170866D01*
G01Y1510591D02*
X158857D01*
G01X158710D02*
X151378D01*
G01X162205Y1511240D02*
X169370D01*
G01X167323Y1511437D02*
X166339D01*
G01X167323Y1511831D02*
X166339D01*
G01X167323Y1512028D02*
X166339D01*
G01X151378Y1512953D02*
X158710D01*
G01X158857D02*
X170866D01*
G01Y1513740D02*
X158857D01*
G01X158710D02*
X151378D01*
G01X167323Y1513878D02*
X166339D01*
G01X167323Y1514075D02*
X166339D01*
G01X167323Y1514469D02*
X166339D01*
G01X162205Y1514665D02*
X169370D01*
G01X151378Y1516102D02*
X158710D01*
G01X158857D02*
X170866D01*
G01X162205Y1516240D02*
X169370D01*
G01X167323Y1516437D02*
X166339D01*
G01X167323Y1516831D02*
X166339D01*
G01X170866Y1516890D02*
X158857D01*
G01X158710D02*
X151378D01*
G01X167323Y1517028D02*
X166339D01*
G01X167323Y1518878D02*
X166339D01*
G01X167323Y1519075D02*
X166339D01*
G01X151378Y1519252D02*
X158710D01*
G01X158857D02*
X170866D01*
G01X167323Y1519469D02*
X166339D01*
G01X162205Y1519665D02*
X169370D01*
G01X170866Y1520039D02*
X158857D01*
G01X158710D02*
X151378D01*
G01X162205Y1521240D02*
X169370D01*
G01X167323Y1521437D02*
X166339D01*
G01X167323Y1521831D02*
X166339D01*
G01X167323Y1522028D02*
X166339D01*
G01X151378Y1522402D02*
X158710D01*
G01X158857D02*
X170866D01*
G01Y1523189D02*
X158857D01*
G01X158710D02*
X151378D01*
G01X167323Y1523878D02*
X166339D01*
G01X167323Y1524075D02*
X166339D01*
G01X167323Y1524469D02*
X166339D01*
G01X162205Y1524665D02*
X169370D01*
G01X151378Y1525551D02*
X158710D01*
G01X158857D02*
X170866D01*
G01X162205Y1526240D02*
X169370D01*
G01X170866Y1526339D02*
X158857D01*
G01X158710D02*
X151378D01*
G01X167323Y1526437D02*
X166339D01*
G01X167323Y1526831D02*
X166339D01*
G01X167323Y1527028D02*
X166339D01*
G01X170866Y1528248D02*
X169764D01*
G01X151378Y1528701D02*
X158710D01*
G01X158857D02*
X170866D01*
G01X169291Y1528878D02*
X168307D01*
G01X169291Y1529075D02*
X168307D01*
G01X169291Y1529469D02*
X168307D01*
G01X170866Y1529488D02*
X158857D01*
G01X158710D02*
X151378D01*
G01X169764Y1529665D02*
X164173D01*
G01X169764Y1531240D02*
X164173D01*
G01X169291Y1531437D02*
X168307D01*
G01X169291Y1531831D02*
X168307D01*
G01X151378Y1531850D02*
X158710D01*
G01X158857D02*
X170866D01*
G01X169291Y1532028D02*
X168307D01*
G01X170866Y1532638D02*
X158857D01*
G01X158710D02*
X151378D01*
G01X170866Y1532657D02*
X169764D01*
G01X167323Y1533878D02*
X166339D01*
G01X167323Y1534075D02*
X166339D01*
G01X167323Y1534469D02*
X166339D01*
G01X162205Y1534665D02*
X169370D01*
G01X151378Y1535000D02*
X158710D01*
G01X158857D02*
X170866D01*
G01Y1535787D02*
X158857D01*
G01X158710D02*
X151378D01*
G01X162205Y1536240D02*
X169370D01*
G01X167323Y1536437D02*
X166339D01*
G01X167323Y1536831D02*
X166339D01*
G01X167323Y1537028D02*
X166339D01*
G01X151378Y1538150D02*
X158710D01*
G01X158857D02*
X170866D01*
G01X167323Y1538878D02*
X166339D01*
G01X170866Y1538937D02*
X158857D01*
G01X158710D02*
X151378D01*
G01X167323Y1539075D02*
X166339D01*
G01X167323Y1539469D02*
X166339D01*
G01X162205Y1539665D02*
X169370D01*
G01X162205Y1541240D02*
X169370D01*
G01X151378Y1541299D02*
X158710D01*
G01X158857D02*
X170866D01*
G01X167323Y1541437D02*
X166339D01*
G01X167323Y1541831D02*
X166339D01*
G01X167323Y1542028D02*
X166339D01*
G01X170866Y1542087D02*
X158857D01*
G01X158710D02*
X151378D01*
G01X167323Y1543878D02*
X166339D01*
G01X167323Y1544075D02*
X166339D01*
G01X151378Y1544449D02*
X158710D01*
G01X158857D02*
X170866D01*
G01X167323Y1544469D02*
X166339D01*
G01X162205Y1544665D02*
X169370D01*
G01X170866Y1545236D02*
X158857D01*
G01X158710D02*
X151378D01*
G01X169764Y1514272D02*
G03X169370Y1514665I-394J-1D01*
G01Y1516240D02*
G03X169764Y1516634I0J394D01*
G01Y1519272D02*
G03X169370Y1519665I-394J-1D01*
G01Y1521240D02*
G03X169764Y1521634I0J394D01*
G01Y1524272D02*
G03X169370Y1524665I-394J-1D01*
G01Y1526240D02*
G03X169764Y1526634I0J394D01*
G01Y1509272D02*
G03X169370Y1509665I-394J-1D01*
G01Y1511240D02*
G03X169764Y1511634I0J394D01*
G01Y1504272D02*
G03X169370Y1504665I-394J-1D01*
G01Y1506240D02*
G03X169764Y1506634I0J394D01*
G01Y1539272D02*
G03X169370Y1539665I-394J-1D01*
G01Y1541240D02*
G03X169764Y1541634I0J394D01*
G01Y1534272D02*
G03X169370Y1534665I-394J-1D01*
G01Y1536240D02*
G03X169764Y1536634I0J394D01*
G01Y1544272D02*
G03X169370Y1544665I-394J-1D01*
G01X179449Y1575472D02*
X163071D01*
G01X174409Y1785827D02*
Y1786417D01*
G01X172835Y1786122D02*
X175984D01*
G01X168110Y1786417D02*
Y1785827D01*
G01X169685Y1786122D02*
X166535D01*
G01X174409Y1786417D02*
X168110D01*
G01X172835Y1783563D02*
Y1781594D01*
G01Y1784154D02*
Y1786122D01*
G01X173228Y1786417D02*
Y1781299D01*
G01X173425D02*
Y1786417D01*
G01X174409Y1781299D02*
Y1781890D01*
G01Y1783071D02*
Y1784646D01*
G01X175984Y1786122D02*
Y1784154D01*
G01Y1781594D02*
Y1783563D01*
G01X172835Y1781594D02*
X175984D01*
G01Y1783563D02*
X172835D01*
G01X175984Y1784154D02*
X172835D01*
G01X174409Y1785827D02*
G03Y1784646I0J-590D01*
G01Y1783071D02*
G03Y1781890I0J-590D01*
G01X168028Y1782707D02*
X168121Y1782819D01*
G01Y1782691D02*
X168028Y1782580D01*
G01X166535Y1786122D02*
Y1784154D01*
G01Y1781594D02*
Y1783563D01*
G01X168028Y1782580D02*
Y1782707D01*
G01X168110Y1784646D02*
Y1783071D01*
G01Y1781890D02*
Y1781299D01*
G01X168121Y1782071D02*
Y1782691D01*
G01X168215Y1782819D02*
Y1782071D01*
G01X169094Y1781299D02*
Y1786417D01*
G01X169291D02*
Y1781299D01*
G01X169685Y1783563D02*
Y1781594D01*
G01Y1784154D02*
Y1786122D01*
G01X168110Y1781299D02*
X174409D01*
G01X169685Y1781594D02*
X166535D01*
G01X168215Y1782071D02*
X168121D01*
G01Y1782819D02*
X168215D01*
G01X166535Y1783563D02*
X169685D01*
G01X166535Y1784154D02*
X169685D01*
G01X168110Y1784646D02*
G03Y1785827I0J591D01*
G01Y1781890D02*
G03Y1783071I0J590D01*
G01X149606Y1822559D02*
Y1808878D01*
G01X149924Y1822559D02*
Y1817224D01*
G01X150399Y1822559D02*
Y1819980D01*
G01X203543Y1808878D02*
X149606D01*
G01X173228Y1810846D02*
X149606D01*
G01X173228Y1814626D02*
X149606D01*
G01Y1816594D02*
X173228D01*
G01X199606Y1817224D02*
X149606D01*
G01X173228Y1819035D02*
X149606D01*
G01X150399Y1819980D02*
X170866D01*
G01X169764Y1822559D02*
X149606D01*
G01X175141Y1823550D02*
X175577Y1823806D01*
G01X173311Y1824317D02*
X173050Y1824232D01*
G01X175054Y1824061D02*
X174793Y1823976D01*
G01X173486Y1823806D02*
X173834Y1824147D01*
G01X175315Y1824317D02*
X175054Y1824061D01*
G01X175577Y1823806D02*
X175838Y1824232D01*
G01X173486Y1824573D02*
X173311Y1824317D01*
G01X173834Y1824147D02*
X174009Y1824488D01*
G01D02*
X174096Y1824829D01*
G01X175402Y1824659D02*
X175315Y1824317D01*
G01X173573Y1824829D02*
X173486Y1824573D01*
G01X171918Y1825682D02*
X171831Y1825256D01*
G01X175838Y1824232D02*
X175925Y1824659D01*
G01X171690Y1816004D02*
Y1815266D01*
G01X171831Y1825256D02*
Y1824829D01*
G01X172298Y1802638D02*
Y1801063D01*
G01X172353Y1824829D02*
Y1825341D01*
G01X172669Y1801063D02*
Y1802638D01*
G01X172913Y1822343D02*
Y1954587D01*
G01X173228Y1819035D02*
Y1816594D01*
G01Y1814626D02*
Y1810846D01*
G01X173573Y1825341D02*
Y1824829D01*
G01X173991Y1802638D02*
Y1801063D01*
G01X174016Y1802638D02*
Y1801063D01*
G01X174050D02*
Y1802638D01*
G01X174096Y1824829D02*
Y1825341D01*
G01X174793Y1823976D02*
Y1823465D01*
G01X174882Y1838760D02*
Y1822343D01*
G01X175402Y1825341D02*
Y1824659D01*
G01X175529Y1815339D02*
Y1816004D01*
G01X175925Y1824659D02*
Y1825341D01*
G01X177165Y1808878D02*
Y1817224D01*
G01X179134Y1822933D02*
Y1821161D01*
G01X179449Y1795945D02*
Y1822343D01*
G01X181102Y1954783D02*
Y1822146D01*
G01X171831Y1824829D02*
X171918Y1824488D01*
G01X172441Y1824573D02*
X172353Y1824829D01*
G01X171918Y1824488D02*
X172092Y1824147D01*
G01X172615Y1824317D02*
X172441Y1824573D01*
G01X172092Y1824147D02*
X172441Y1823806D01*
G01X172876Y1824232D02*
X172615Y1824317D01*
G01X172441Y1823806D02*
X172789Y1823720D01*
G01X177165Y1810059D02*
X203543D01*
G01X172428Y1810098D02*
X173314D01*
G01X171690Y1815266D02*
X174643D01*
G01X175529Y1816004D02*
X171690D01*
G01X199606Y1822146D02*
X181102D01*
G01X179449Y1822343D02*
X172913D01*
G01X172789Y1823720D02*
X173137D01*
G01X173050Y1824232D02*
X172876D01*
G01X174793Y1823465D02*
X175141Y1823550D01*
G01X173137Y1823720D02*
X173486Y1823806D01*
G01X175529Y1815339D02*
G03X173314Y1810098I7141J-6107D01*
G01X174643Y1815266D02*
G03X172428Y1810098I6937J-6032D01*
G01X173425Y1800276D02*
G03Y1803425I0J1575D01*
G01X157832Y1812899D02*
X157472Y1812663D01*
X157233Y1812313D01*
X157148Y1811909D01*
X157231Y1811507D01*
X157467Y1811155D01*
X157830Y1810915D01*
X158255Y1810830D01*
G01X158678Y1810915D02*
X159039Y1811150D01*
X159277Y1811500D01*
X159363Y1811904D01*
X159280Y1812306D01*
X159043Y1812659D01*
X158680Y1812898D01*
X158255Y1812983D01*
G01X163000Y1812899D02*
X162639Y1812663D01*
X162401Y1812313D01*
X162315Y1811909D01*
X162398Y1811507D01*
X162634Y1811155D01*
X162998Y1810915D01*
X163422Y1810830D01*
G01X163846Y1810915D02*
X164206Y1811150D01*
X164444Y1811500D01*
X164530Y1811904D01*
X164447Y1812306D01*
X164211Y1812659D01*
X163847Y1812898D01*
X163422Y1812983D01*
G01X157906Y1815201D02*
X157624Y1815023D01*
X157437Y1814758D01*
X157370Y1814456D01*
X157434Y1814156D01*
X157619Y1813889D01*
X157905Y1813707D01*
X158255Y1813642D01*
G01X158604Y1813707D02*
X158887Y1813884D01*
X159074Y1814150D01*
X159141Y1814452D01*
X159076Y1814752D01*
X158891Y1815019D01*
X158606Y1815200D01*
X158255Y1815266D01*
G01X163074Y1815201D02*
X162791Y1815023D01*
X162604Y1814758D01*
X162537Y1814456D01*
X162601Y1814156D01*
X162787Y1813889D01*
X163072Y1813707D01*
X163422Y1813642D01*
G01X163772Y1813707D02*
X164054Y1813884D01*
X164241Y1814150D01*
X164308Y1814452D01*
X164244Y1814752D01*
X164058Y1815019D01*
X163773Y1815200D01*
X163422Y1815266D01*
G01X167961Y1815025D02*
X168248Y1815204D01*
X168602Y1815265D01*
G01X169801Y1813367D02*
X170138Y1813828D01*
X170283Y1814347D01*
X170223Y1814865D01*
X169972Y1815348D01*
X169535Y1815743D01*
X168962Y1815967D01*
X168328Y1815985D01*
X167743Y1815800D01*
X167288Y1815446D01*
X166996Y1814974D01*
X166892Y1814454D01*
G01X159453Y1813355D02*
X159776Y1813774D01*
X159938Y1814257D01*
X159917Y1814762D01*
X159713Y1815239D01*
X159347Y1815643D01*
X158841Y1815910D01*
X158250Y1816004D01*
X157660Y1815907D01*
X157158Y1815638D01*
X156794Y1815234D01*
X156593Y1814756D01*
X156573Y1814251D01*
X156737Y1813770D01*
X157057Y1813355D01*
G01X164620D02*
X164943Y1813774D01*
X165106Y1814257D01*
X165084Y1814762D01*
X164881Y1815239D01*
X164514Y1815643D01*
X164008Y1815910D01*
X163417Y1816004D01*
X162828Y1815907D01*
X162325Y1815638D01*
X161961Y1815234D01*
X161760Y1814756D01*
X161741Y1814251D01*
X161904Y1813770D01*
X162225Y1813355D01*
G01X169229Y1813892D02*
X167667Y1812365D01*
G01X157057Y1813355D02*
X156606Y1812915D01*
X156336Y1812379D01*
X156265Y1811809D01*
X156407Y1811244D01*
X156754Y1810720D01*
X157281Y1810326D01*
X157924Y1810123D01*
X158603Y1810126D01*
X159243Y1810333D01*
X159766Y1810730D01*
X160107Y1811253D01*
X160245Y1811815D01*
X160174Y1812382D01*
X159904Y1812916D01*
G01X162225Y1813355D02*
X161773Y1812915D01*
X161503Y1812379D01*
X161433Y1811809D01*
X161574Y1811244D01*
X161921Y1810720D01*
X162448Y1810326D01*
X163091Y1810123D01*
X163770Y1810126D01*
X164411Y1810333D01*
X164933Y1810730D01*
X165275Y1811253D01*
X165413Y1811815D01*
X165341Y1812382D01*
X165071Y1812916D01*
G01X169801Y1813367D02*
X168172Y1811820D01*
G01X169229Y1813892D02*
X169412Y1814157D01*
X169476Y1814455D01*
X169411Y1814752D01*
G01X167961Y1815026D02*
X167771Y1814757D01*
G01X166892Y1814454D02*
X166979Y1814930D01*
X167226Y1815373D01*
X167615Y1815724D01*
X168121Y1815944D01*
X168699Y1816001D01*
X169263Y1815878D01*
X169739Y1815596D01*
X170078Y1815192D01*
X170257Y1814735D01*
X170272Y1814254D01*
X170115Y1813784D01*
X169801Y1813367D01*
G01X167772Y1814758D02*
X167704Y1814454D01*
G01X151243Y1816004D02*
Y1815266D01*
G01X155081Y1815339D02*
Y1816004D01*
G01X156253Y1817224D02*
Y1819980D01*
G01X156763Y1956949D02*
Y1819980D01*
G01X159796Y1827126D02*
Y1824547D01*
G01X161240Y1826969D02*
Y1825000D01*
G01X162205Y1826752D02*
Y1825177D01*
G01X163071Y1808878D02*
Y1795945D01*
G01X164127Y1817224D02*
Y1819980D01*
G01X164766Y1819587D02*
Y1819528D01*
G01X165293Y1822559D02*
Y1954173D01*
G01X165354Y1826752D02*
Y1825177D01*
G01X165748Y1819980D02*
Y1956949D01*
G01X166339Y1827539D02*
Y1824390D01*
G01X166597Y1810541D02*
Y1810098D01*
G01X166892Y1814454D02*
Y1814306D01*
G01X167323Y1827539D02*
Y1824390D01*
G01Y1819528D02*
Y1817224D01*
G01X167704Y1814306D02*
Y1814454D01*
G01X168307Y1826752D02*
Y1825177D01*
G01X168469Y1802638D02*
Y1801063D01*
G01X168504D02*
Y1802638D01*
G01X168528Y1801063D02*
Y1802638D01*
G01X169311Y1825000D02*
Y1826969D01*
G01X169764Y1819980D02*
Y1956949D01*
G01X169851Y1802638D02*
Y1801063D01*
G01X170221D02*
Y1802638D01*
G01X170509Y1810098D02*
Y1810837D01*
G01X170866Y1957402D02*
Y1819528D01*
G01X164511Y1819980D02*
X164766Y1819587D01*
G01X157057Y1813355D02*
X156735Y1813774D01*
X156572Y1814257D01*
X156594Y1814762D01*
X156797Y1815239D01*
X157164Y1815643D01*
X157670Y1815910D01*
X158261Y1816004D01*
X158850Y1815907D01*
X159353Y1815638D01*
X159717Y1815234D01*
X159918Y1814756D01*
X159937Y1814251D01*
X159774Y1813770D01*
X159453Y1813355D01*
G01X162225D02*
X161902Y1813774D01*
X161739Y1814257D01*
X161761Y1814762D01*
X161964Y1815239D01*
X162331Y1815643D01*
X162837Y1815910D01*
X163428Y1816004D01*
X164018Y1815907D01*
X164520Y1815638D01*
X164884Y1815234D01*
X165085Y1814756D01*
X165105Y1814251D01*
X164941Y1813770D01*
X164620Y1813355D01*
G01X169229Y1815016D02*
X169411Y1814751D01*
X169476Y1814452D01*
X169411Y1814156D01*
G01X159453Y1813355D02*
X159905Y1812915D01*
X160175Y1812379D01*
X160245Y1811809D01*
X160104Y1811244D01*
X159757Y1810720D01*
X159230Y1810326D01*
X158587Y1810123D01*
X157907Y1810126D01*
X157267Y1810333D01*
X156744Y1810730D01*
X156403Y1811253D01*
X156265Y1811815D01*
X156337Y1812382D01*
X156607Y1812916D01*
G01X164620Y1813355D02*
X165072Y1812915D01*
X165342Y1812379D01*
X165413Y1811809D01*
X165271Y1811244D01*
X164924Y1810720D01*
X164397Y1810326D01*
X163754Y1810123D01*
X163075Y1810126D01*
X162435Y1810333D01*
X161912Y1810730D01*
X161570Y1811253D01*
X161432Y1811815D01*
X161504Y1812382D01*
X161774Y1812916D01*
G01X157906Y1813707D02*
X157624Y1813884D01*
X157437Y1814150D01*
X157370Y1814452D01*
X157434Y1814752D01*
X157619Y1815019D01*
X157905Y1815200D01*
X158255Y1815266D01*
G01X158604Y1815201D02*
X158887Y1815023D01*
X159074Y1814758D01*
X159141Y1814456D01*
X159076Y1814156D01*
X158891Y1813889D01*
X158606Y1813707D01*
X158255Y1813642D01*
G01X163074Y1813707D02*
X162791Y1813884D01*
X162604Y1814150D01*
X162537Y1814452D01*
X162601Y1814752D01*
X162787Y1815019D01*
X163072Y1815200D01*
X163422Y1815266D01*
G01X163772Y1815201D02*
X164054Y1815023D01*
X164241Y1814758D01*
X164308Y1814456D01*
X164244Y1814156D01*
X164058Y1813889D01*
X163773Y1813707D01*
X163422Y1813642D01*
G01X168949Y1815196D02*
X169229Y1815015D01*
G01X157832Y1810915D02*
X157472Y1811150D01*
X157233Y1811500D01*
X157148Y1811904D01*
X157231Y1812306D01*
X157467Y1812659D01*
X157830Y1812898D01*
X158255Y1812983D01*
G01X158678Y1812899D02*
X159039Y1812663D01*
X159277Y1812313D01*
X159363Y1811909D01*
X159280Y1811507D01*
X159043Y1811155D01*
X158680Y1810915D01*
X158255Y1810830D01*
G01X163000Y1810915D02*
X162639Y1811150D01*
X162401Y1811500D01*
X162315Y1811904D01*
X162398Y1812306D01*
X162634Y1812659D01*
X162998Y1812898D01*
X163422Y1812983D01*
G01X163846Y1812899D02*
X164206Y1812663D01*
X164444Y1812313D01*
X164530Y1811909D01*
X164447Y1811507D01*
X164211Y1811155D01*
X163847Y1810915D01*
X163422Y1810830D01*
G01X168602Y1815265D02*
X168950Y1815196D01*
G01X179449Y1795945D02*
X163071D01*
G01X173425Y1800276D02*
X169094D01*
G01X174050Y1801063D02*
X168469D01*
G01Y1802638D02*
X174050D01*
G01X169094Y1803425D02*
X173425D01*
G01X179449Y1806122D02*
X163071D01*
G01X151981Y1810098D02*
X152867D01*
G01X166597D02*
X170509D01*
G01Y1810837D02*
X167630D01*
G01X166892Y1814306D02*
X167704D01*
G01X151243Y1815266D02*
X154195D01*
G01X155081Y1816004D02*
X151243D01*
G01X170866Y1819528D02*
X164766D01*
G01Y1819587D02*
X170866D01*
G01X169764Y1821161D02*
X179134D01*
G01X170866Y1821752D02*
X201575D01*
G01X169764Y1822933D02*
X179134D01*
G01X167323Y1824390D02*
X166339D01*
G01X165748Y1824547D02*
X156763D01*
G01X167323Y1824587D02*
X166339D01*
G01X167323Y1824980D02*
X166339D01*
G01X161240Y1825000D02*
X169311D01*
G01X162205Y1825177D02*
X169370D01*
G01X155081Y1815339D02*
G03X152866Y1810098I7141J-6107D01*
G01X154195Y1815266D02*
G03X151981Y1810098I6938J-6031D01*
G01X166535Y1813661D02*
G03I-4527J0D01*
G01X165512D02*
G03I-3504J0D01*
G01X165354D02*
G03I-3346J0D01*
G01X164173D02*
G03I-2165J0D01*
G01X168172Y1811820D02*
G03X167630Y1810837I1276J-1344D01*
G01X169094Y1803425D02*
G03Y1800276I0J-1574D01*
G01X169764Y1824783D02*
G03X169370Y1825177I-394J0D01*
G01X167667Y1812365D02*
G03X166597Y1810541I2810J-2874D01*
G01X174882Y1878209D02*
Y1858720D01*
G01X200563Y1852362D02*
X181102D01*
G01X199606Y1856358D02*
X172913D01*
G01X199606Y1858701D02*
X181102D01*
G01X195106Y1858720D02*
X172913D01*
G01X172528Y1826280D02*
X172179Y1826024D01*
G01X174357Y1825938D02*
X174618Y1826109D01*
G01X172615Y1825768D02*
X172789Y1825853D01*
G01X174531Y1826620D02*
X174183Y1826450D01*
G01X172789Y1826365D02*
X172528Y1826280D01*
G01X172179Y1826024D02*
X171918Y1825682D01*
G01X172441Y1825597D02*
X172615Y1825768D01*
G01X174183Y1826450D02*
X173834Y1826109D01*
G01X174183Y1825682D02*
X174357Y1825938D01*
G01X173834Y1826109D02*
X173660Y1825768D01*
G01X174096Y1825341D02*
X174183Y1825682D01*
G01X172353Y1825341D02*
X172441Y1825597D01*
G01X173660Y1825768D02*
X173573Y1825341D01*
G01X171831Y1827815D02*
Y1828327D01*
G01X172789Y1825853D02*
Y1826365D01*
G01X174882Y1856358D02*
Y1841122D01*
G01X175925Y1828327D02*
Y1827815D01*
G01Y1825341D02*
X175838Y1825768D01*
G01X175315Y1825682D02*
X175402Y1825341D01*
G01X175838Y1825768D02*
X175664Y1826109D01*
G01X175141Y1825938D02*
X175315Y1825682D01*
G01X175664Y1826109D02*
X175315Y1826450D01*
G01X172441Y1827303D02*
X171831Y1827815D01*
G01X172528D02*
X173137Y1827303D01*
G01X174880Y1826109D02*
X175141Y1825938D01*
G01X175315Y1826450D02*
X174967Y1826620D01*
G01X174618Y1826109D02*
X174880D01*
G01X174967Y1826620D02*
X174531D01*
G01X173137Y1827303D02*
X172441D01*
G01X175925Y1827815D02*
X172528D01*
G01X171831Y1828327D02*
X175925D01*
G01X199606Y1838760D02*
X172913D01*
G01X199606Y1841122D02*
X172913D01*
G01X151378Y1849173D02*
Y1849961D01*
G01Y1846024D02*
Y1846811D01*
G01Y1852323D02*
Y1853110D01*
G01Y1858622D02*
Y1859409D01*
G01Y1855472D02*
Y1856260D01*
G01Y1861772D02*
Y1862559D01*
G01Y1864921D02*
Y1865709D01*
G01X153151Y1849173D02*
Y1849961D01*
G01Y1846024D02*
Y1846811D01*
G01Y1852323D02*
Y1853110D01*
G01Y1858622D02*
Y1859409D01*
G01Y1855472D02*
Y1856260D01*
G01Y1861772D02*
Y1862559D01*
G01Y1864921D02*
Y1865709D01*
G01X153340D02*
Y1864921D01*
G01Y1862559D02*
Y1861772D01*
G01Y1859409D02*
Y1858622D01*
G01Y1856260D02*
Y1855472D01*
G01Y1853110D02*
Y1852323D01*
G01Y1849961D02*
Y1849173D01*
G01Y1846811D02*
Y1846024D01*
G01X156176Y1865709D02*
Y1864921D01*
G01Y1862559D02*
Y1861772D01*
G01Y1859409D02*
Y1858622D01*
G01Y1856260D02*
Y1855472D01*
G01Y1853110D02*
Y1852323D01*
G01Y1849961D02*
Y1849173D01*
G01Y1846811D02*
Y1846024D01*
G01X157118Y1849173D02*
Y1849961D01*
G01Y1846024D02*
Y1846811D01*
G01Y1852323D02*
Y1853110D01*
G01Y1858622D02*
Y1859409D01*
G01Y1855472D02*
Y1856260D01*
G01Y1861772D02*
Y1862559D01*
G01Y1864921D02*
Y1865709D01*
G01X158710Y1849173D02*
Y1849961D01*
G01Y1846024D02*
Y1846811D01*
G01Y1852323D02*
Y1853110D01*
G01Y1858622D02*
Y1859409D01*
G01Y1855472D02*
Y1856260D01*
G01Y1861772D02*
Y1862559D01*
G01Y1864921D02*
Y1865709D01*
G01X158857Y1849173D02*
Y1849961D01*
G01Y1846024D02*
Y1846811D01*
G01Y1852323D02*
Y1853110D01*
G01Y1858622D02*
Y1859409D01*
G01Y1855472D02*
Y1856260D01*
G01Y1861772D02*
Y1862559D01*
G01Y1864921D02*
Y1865709D01*
G01X159796Y1868071D02*
Y1865709D01*
G01Y1864921D02*
Y1862559D01*
G01Y1861772D02*
Y1859409D01*
G01Y1858622D02*
Y1856260D01*
G01Y1855472D02*
Y1853110D01*
G01Y1852323D02*
Y1849961D01*
G01Y1849173D02*
Y1846811D01*
G01X161524Y1849173D02*
Y1849961D01*
G01Y1846024D02*
Y1846811D01*
G01Y1852323D02*
Y1853110D01*
G01Y1858622D02*
Y1859409D01*
G01Y1855472D02*
Y1856260D01*
G01Y1861772D02*
Y1862559D01*
G01Y1864921D02*
Y1865709D01*
G01X161874Y1862638D02*
Y1864843D01*
G01X162205Y1856752D02*
Y1855177D01*
G01Y1851752D02*
Y1850177D01*
G01X163176Y1865709D02*
Y1864921D01*
G01Y1862559D02*
Y1861772D01*
G01Y1859409D02*
Y1858622D01*
G01Y1856260D02*
Y1855472D01*
G01Y1853110D02*
Y1852323D01*
G01Y1849961D02*
Y1849173D01*
G01Y1846811D02*
Y1846024D01*
G01X163331Y1858819D02*
Y1862638D01*
G01Y1864843D02*
Y1872087D01*
G01X163739Y1867480D02*
Y1866299D01*
G01Y1864331D02*
Y1863150D01*
G01Y1861181D02*
Y1860000D01*
G01X163757Y1864843D02*
Y1862638D01*
G01X163809Y1858819D02*
Y1878110D01*
G01X165159Y1865709D02*
Y1864921D01*
G01Y1862559D02*
Y1861772D01*
G01Y1859409D02*
Y1858622D01*
G01Y1856260D02*
Y1855472D01*
G01Y1853110D02*
Y1852323D01*
G01Y1849961D02*
Y1849173D01*
G01Y1846811D02*
Y1846024D01*
G01X165354Y1856752D02*
Y1855177D01*
G01Y1851752D02*
Y1850177D01*
G01X166339Y1857539D02*
Y1854390D01*
G01Y1852539D02*
Y1849390D01*
G01X166888Y1867480D02*
Y1866299D01*
G01Y1864331D02*
Y1863150D01*
G01Y1861181D02*
Y1860000D01*
G01X167165Y1858819D02*
Y1878110D01*
G01X167323Y1857539D02*
Y1854390D01*
G01Y1852539D02*
Y1849390D01*
G01X167872Y1859311D02*
Y1877618D01*
G01X168082Y1878110D02*
Y1858819D01*
G01X168307Y1856752D02*
Y1855177D01*
G01Y1851752D02*
Y1850177D01*
G01X168521Y1849173D02*
Y1849961D01*
G01Y1846024D02*
Y1846811D01*
G01Y1852323D02*
Y1853110D01*
G01Y1858622D02*
Y1859409D01*
G01Y1855472D02*
Y1856260D01*
G01Y1861772D02*
Y1862559D01*
G01Y1864921D02*
Y1865709D01*
G01X168583Y1878110D02*
Y1858819D01*
G01X168857Y1868071D02*
Y1865709D01*
G01Y1864921D02*
Y1862559D01*
G01Y1861772D02*
Y1859409D01*
G01X168898Y1849173D02*
Y1849961D01*
G01Y1846024D02*
Y1846811D01*
G01Y1852323D02*
Y1853110D01*
G01Y1858622D02*
Y1859409D01*
G01Y1855472D02*
Y1856260D01*
G01Y1861772D02*
Y1862559D01*
G01Y1864921D02*
Y1865709D01*
G01X168924Y1849173D02*
Y1849961D01*
G01Y1846024D02*
Y1846811D01*
G01Y1852323D02*
Y1853110D01*
G01Y1858622D02*
Y1859409D01*
G01Y1855472D02*
Y1856260D01*
G01Y1861772D02*
Y1862559D01*
G01Y1864921D02*
Y1865709D01*
G01X169370Y1858819D02*
Y1878110D01*
G01X169685D02*
Y1858819D01*
G01X151378Y1846024D02*
X158710D01*
G01X158857D02*
X170866D01*
G01X162205Y1846752D02*
X169370D01*
G01X170866Y1846811D02*
X158857D01*
G01X158710D02*
X151378D01*
G01X167323Y1846949D02*
X166339D01*
G01X167323Y1847343D02*
X166339D01*
G01X167323Y1847539D02*
X166339D01*
G01X151378Y1849173D02*
X158710D01*
G01X158857D02*
X170866D01*
G01X167323Y1849390D02*
X166339D01*
G01X167323Y1849587D02*
X166339D01*
G01X170866Y1849961D02*
X158857D01*
G01X158710D02*
X151378D01*
G01X167323Y1849980D02*
X166339D01*
G01X162205Y1850177D02*
X169370D01*
G01X162205Y1851752D02*
X169370D01*
G01X167323Y1851949D02*
X166339D01*
G01X151378Y1852323D02*
X158710D01*
G01X158857D02*
X170866D01*
G01X167323Y1852343D02*
X166339D01*
G01X167323Y1852539D02*
X166339D01*
G01X170866Y1853110D02*
X158857D01*
G01X158710D02*
X151378D01*
G01X167323Y1854390D02*
X166339D01*
G01X167323Y1854587D02*
X166339D01*
G01X167323Y1854980D02*
X166339D01*
G01X162205Y1855177D02*
X169370D01*
G01X151378Y1855472D02*
X158710D01*
G01X158857D02*
X170866D01*
G01Y1856260D02*
X158857D01*
G01X158710D02*
X151378D01*
G01X162205Y1856752D02*
X169370D01*
G01X167323Y1856949D02*
X166339D01*
G01X167323Y1857343D02*
X166339D01*
G01X167323Y1857539D02*
X166339D01*
G01X151378Y1858622D02*
X158710D01*
G01X158857D02*
X170866D01*
G01Y1858701D02*
X169764D01*
G01X163331Y1858819D02*
X170866D01*
G01X167872Y1859311D02*
X165748D01*
G01X170866Y1859409D02*
X158857D01*
G01X158710D02*
X151378D01*
G01X168857Y1859606D02*
X167872D01*
G01X168857Y1859803D02*
X167872D01*
G01X169764Y1860000D02*
X163739D01*
G01X169764Y1861181D02*
X163739D01*
G01X168857Y1861378D02*
X167872D01*
G01X168857Y1861575D02*
X167872D01*
G01X151378Y1861772D02*
X158710D01*
G01X158857D02*
X170866D01*
G01Y1862559D02*
X158857D01*
G01X158710D02*
X151378D01*
G01X161874Y1862638D02*
X163757D01*
G01X168857Y1862756D02*
X167872D01*
G01X168857Y1862953D02*
X167872D01*
G01X169764Y1863150D02*
X163739D01*
G01X169764Y1864331D02*
X163739D01*
G01X168857Y1864528D02*
X167872D01*
G01X168857Y1864724D02*
X167872D01*
G01X163757Y1864843D02*
X161874D01*
G01X151378Y1864921D02*
X158710D01*
G01X158857D02*
X170866D01*
G01Y1865709D02*
X158857D01*
G01X158710D02*
X151378D01*
G01X168857Y1865906D02*
X167872D01*
G01X168857Y1866102D02*
X167872D01*
G01X169764Y1866299D02*
X163739D01*
G01X169370Y1846752D02*
G03X169764Y1847146I0J394D01*
G01Y1849783D02*
G03X169370Y1850177I-394J0D01*
G01Y1851752D02*
G03X169764Y1852146I0J394D01*
G01Y1854783D02*
G03X169370Y1855177I-394J0D01*
G01Y1856752D02*
G03X169764Y1857146I0J394D01*
G01X151378Y1830276D02*
Y1831063D01*
G01Y1827126D02*
Y1827913D01*
G01Y1833425D02*
Y1834213D01*
G01Y1839724D02*
Y1840512D01*
G01Y1836575D02*
Y1837362D01*
G01Y1842874D02*
Y1843661D01*
G01X153151Y1830276D02*
Y1831063D01*
G01Y1827126D02*
Y1827913D01*
G01Y1833425D02*
Y1834213D01*
G01Y1839724D02*
Y1840512D01*
G01Y1836575D02*
Y1837362D01*
G01Y1842874D02*
Y1843661D01*
G01X153340D02*
Y1842874D01*
G01Y1840512D02*
Y1839724D01*
G01Y1837362D02*
Y1836575D01*
G01Y1834213D02*
Y1833425D01*
G01Y1831063D02*
Y1830276D01*
G01Y1827913D02*
Y1827126D01*
G01X156176Y1843661D02*
Y1842874D01*
G01Y1840512D02*
Y1839724D01*
G01Y1837362D02*
Y1836575D01*
G01Y1834213D02*
Y1833425D01*
G01Y1831063D02*
Y1830276D01*
G01Y1827913D02*
Y1827126D01*
G01X157118Y1830276D02*
Y1831063D01*
G01Y1827126D02*
Y1827913D01*
G01Y1833425D02*
Y1834213D01*
G01Y1839724D02*
Y1840512D01*
G01Y1836575D02*
Y1837362D01*
G01Y1842874D02*
Y1843661D01*
G01X158710Y1830276D02*
Y1831063D01*
G01Y1827126D02*
Y1827913D01*
G01Y1833425D02*
Y1834213D01*
G01Y1839724D02*
Y1840512D01*
G01Y1836575D02*
Y1837362D01*
G01Y1842874D02*
Y1843661D01*
G01X158857Y1830276D02*
Y1831063D01*
G01Y1827126D02*
Y1827913D01*
G01Y1833425D02*
Y1834213D01*
G01Y1839724D02*
Y1840512D01*
G01Y1836575D02*
Y1837362D01*
G01Y1842874D02*
Y1843661D01*
G01X159796Y1846024D02*
Y1843661D01*
G01Y1842874D02*
Y1840512D01*
G01Y1839724D02*
Y1837362D01*
G01Y1836575D02*
Y1834213D01*
G01Y1833425D02*
Y1831063D01*
G01Y1830276D02*
Y1827913D01*
G01X161524Y1830276D02*
Y1831063D01*
G01Y1827126D02*
Y1827913D01*
G01Y1833425D02*
Y1834213D01*
G01Y1839724D02*
Y1840512D01*
G01Y1836575D02*
Y1837362D01*
G01Y1842874D02*
Y1843661D01*
G01X162205Y1846752D02*
Y1845177D01*
G01Y1841752D02*
Y1840177D01*
G01Y1836752D02*
Y1835177D01*
G01Y1831752D02*
Y1830177D01*
G01X163176Y1843661D02*
Y1842874D01*
G01Y1840512D02*
Y1839724D01*
G01Y1837362D02*
Y1836575D01*
G01Y1834213D02*
Y1833425D01*
G01Y1831063D02*
Y1830276D01*
G01Y1827913D02*
Y1827126D01*
G01X165159Y1843661D02*
Y1842874D01*
G01Y1840512D02*
Y1839724D01*
G01Y1837362D02*
Y1836575D01*
G01Y1834213D02*
Y1833425D01*
G01Y1831063D02*
Y1830276D01*
G01Y1827913D02*
Y1827126D01*
G01X165354Y1846752D02*
Y1845177D01*
G01Y1841752D02*
Y1840177D01*
G01Y1836752D02*
Y1835177D01*
G01Y1831752D02*
Y1830177D01*
G01X166339Y1847539D02*
Y1844390D01*
G01Y1842539D02*
Y1839390D01*
G01Y1837539D02*
Y1834390D01*
G01Y1832539D02*
Y1829390D01*
G01X167323Y1847539D02*
Y1844390D01*
G01Y1842539D02*
Y1839390D01*
G01Y1837539D02*
Y1834390D01*
G01Y1832539D02*
Y1829390D01*
G01X168307Y1846752D02*
Y1845177D01*
G01Y1841752D02*
Y1840177D01*
G01Y1836752D02*
Y1835177D01*
G01Y1831752D02*
Y1830177D01*
G01X168521Y1830276D02*
Y1831063D01*
G01Y1827126D02*
Y1827913D01*
G01Y1833425D02*
Y1834213D01*
G01Y1839724D02*
Y1840512D01*
G01Y1836575D02*
Y1837362D01*
G01Y1842874D02*
Y1843661D01*
G01X168898Y1830276D02*
Y1831063D01*
G01Y1827126D02*
Y1827913D01*
G01Y1833425D02*
Y1834213D01*
G01Y1839724D02*
Y1840512D01*
G01Y1836575D02*
Y1837362D01*
G01Y1842874D02*
Y1843661D01*
G01X168924Y1830276D02*
Y1831063D01*
G01Y1827126D02*
Y1827913D01*
G01Y1833425D02*
Y1834213D01*
G01Y1839724D02*
Y1840512D01*
G01Y1836575D02*
Y1837362D01*
G01Y1842874D02*
Y1843661D01*
G01X162205Y1826752D02*
X169370D01*
G01X167323Y1826949D02*
X166339D01*
G01X169311Y1826969D02*
X161240D01*
G01X151378Y1827126D02*
X158710D01*
G01X158857D02*
X170866D01*
G01X167323Y1827343D02*
X166339D01*
G01X167323Y1827539D02*
X166339D01*
G01X170866Y1827913D02*
X158857D01*
G01X158710D02*
X151378D01*
G01X167323Y1829390D02*
X166339D01*
G01X167323Y1829587D02*
X166339D01*
G01X167323Y1829980D02*
X166339D01*
G01X162205Y1830177D02*
X169370D01*
G01X151378Y1830276D02*
X158710D01*
G01X158857D02*
X170866D01*
G01Y1831063D02*
X158857D01*
G01X158710D02*
X151378D01*
G01X162205Y1831752D02*
X169370D01*
G01X167323Y1831949D02*
X166339D01*
G01X167323Y1832343D02*
X166339D01*
G01X167323Y1832539D02*
X166339D01*
G01X151378Y1833425D02*
X158710D01*
G01X158857D02*
X170866D01*
G01Y1834213D02*
X158857D01*
G01X158710D02*
X151378D01*
G01X167323Y1834390D02*
X166339D01*
G01X167323Y1834587D02*
X166339D01*
G01X167323Y1834980D02*
X166339D01*
G01X162205Y1835177D02*
X169370D01*
G01X151378Y1836575D02*
X158710D01*
G01X158857D02*
X170866D01*
G01X162205Y1836752D02*
X169370D01*
G01X167323Y1836949D02*
X166339D01*
G01X167323Y1837343D02*
X166339D01*
G01X170866Y1837362D02*
X158857D01*
G01X158710D02*
X151378D01*
G01X167323Y1837539D02*
X166339D01*
G01X167323Y1839390D02*
X166339D01*
G01X167323Y1839587D02*
X166339D01*
G01X151378Y1839724D02*
X158710D01*
G01X158857D02*
X170866D01*
G01X167323Y1839980D02*
X166339D01*
G01X162205Y1840177D02*
X169370D01*
G01X170866Y1840512D02*
X158857D01*
G01X158710D02*
X151378D01*
G01X162205Y1841752D02*
X169370D01*
G01X167323Y1841949D02*
X166339D01*
G01X167323Y1842343D02*
X166339D01*
G01X167323Y1842539D02*
X166339D01*
G01X151378Y1842874D02*
X158710D01*
G01X158857D02*
X170866D01*
G01Y1843661D02*
X158857D01*
G01X158710D02*
X151378D01*
G01X167323Y1844390D02*
X166339D01*
G01X167323Y1844587D02*
X166339D01*
G01X167323Y1844980D02*
X166339D01*
G01X162205Y1845177D02*
X169370D01*
G01X169764Y1829783D02*
G03X169370Y1830177I-394J0D01*
G01Y1831752D02*
G03X169764Y1832146I0J394D01*
G01Y1839783D02*
G03X169370Y1840177I-394J0D01*
G01Y1841752D02*
G03X169764Y1842146I0J394D01*
G01Y1834783D02*
G03X169370Y1835177I-394J0D01*
G01Y1836752D02*
G03X169764Y1837146I0J394D01*
G01Y1844783D02*
G03X169370Y1845177I-394J0D01*
G01Y1826752D02*
G03X169764Y1827146I0J394D01*
G01X174882Y1918169D02*
Y1934705D01*
G01Y1937067D02*
Y1954587D01*
G01X199606Y1915807D02*
X172913D01*
G01X199606Y1918169D02*
X172913D01*
G01X199606Y1934705D02*
X172913D01*
G01X199606Y1937067D02*
X172913D01*
G01X151378Y1909016D02*
Y1909803D01*
G01Y1905866D02*
Y1906654D01*
G01Y1912165D02*
Y1912953D01*
G01Y1918465D02*
Y1919252D01*
G01Y1915315D02*
Y1916102D01*
G01Y1921614D02*
Y1922402D01*
G01Y1927913D02*
Y1928701D01*
G01Y1924764D02*
Y1925551D01*
G01Y1931063D02*
Y1931850D01*
G01Y1937362D02*
Y1938150D01*
G01Y1934213D02*
Y1935000D01*
G01X153151Y1909016D02*
Y1909803D01*
G01Y1905866D02*
Y1906654D01*
G01Y1912165D02*
Y1912953D01*
G01Y1918465D02*
Y1919252D01*
G01Y1915315D02*
Y1916102D01*
G01Y1921614D02*
Y1922402D01*
G01Y1927913D02*
Y1928701D01*
G01Y1924764D02*
Y1925551D01*
G01Y1931063D02*
Y1931850D01*
G01Y1937362D02*
Y1938150D01*
G01Y1934213D02*
Y1935000D01*
G01X153340Y1938150D02*
Y1937362D01*
G01Y1935000D02*
Y1934213D01*
G01Y1931850D02*
Y1931063D01*
G01Y1928701D02*
Y1927913D01*
G01Y1925551D02*
Y1924764D01*
G01Y1922402D02*
Y1921614D01*
G01Y1919252D02*
Y1918465D01*
G01Y1916102D02*
Y1915315D01*
G01Y1912953D02*
Y1912165D01*
G01Y1909803D02*
Y1909016D01*
G01Y1906654D02*
Y1905866D01*
G01X156176Y1938150D02*
Y1937362D01*
G01Y1935000D02*
Y1934213D01*
G01Y1931850D02*
Y1931063D01*
G01Y1928701D02*
Y1927913D01*
G01Y1925551D02*
Y1924764D01*
G01Y1922402D02*
Y1921614D01*
G01Y1919252D02*
Y1918465D01*
G01Y1916102D02*
Y1915315D01*
G01Y1912953D02*
Y1912165D01*
G01Y1909803D02*
Y1909016D01*
G01Y1906654D02*
Y1905866D01*
G01X157118Y1909016D02*
Y1909803D01*
G01Y1905866D02*
Y1906654D01*
G01Y1912165D02*
Y1912953D01*
G01Y1918465D02*
Y1919252D01*
G01Y1915315D02*
Y1916102D01*
G01Y1921614D02*
Y1922402D01*
G01Y1927913D02*
Y1928701D01*
G01Y1924764D02*
Y1925551D01*
G01Y1931063D02*
Y1931850D01*
G01Y1937362D02*
Y1938150D01*
G01Y1934213D02*
Y1935000D01*
G01X158710Y1909016D02*
Y1909803D01*
G01Y1905866D02*
Y1906654D01*
G01Y1912165D02*
Y1912953D01*
G01Y1918465D02*
Y1919252D01*
G01Y1915315D02*
Y1916102D01*
G01Y1921614D02*
Y1922402D01*
G01Y1927913D02*
Y1928701D01*
G01Y1924764D02*
Y1925551D01*
G01Y1931063D02*
Y1931850D01*
G01Y1937362D02*
Y1938150D01*
G01Y1934213D02*
Y1935000D01*
G01X158857Y1909016D02*
Y1909803D01*
G01Y1905866D02*
Y1906654D01*
G01Y1912165D02*
Y1912953D01*
G01Y1918465D02*
Y1919252D01*
G01Y1915315D02*
Y1916102D01*
G01Y1921614D02*
Y1922402D01*
G01Y1927913D02*
Y1928701D01*
G01Y1924764D02*
Y1925551D01*
G01Y1931063D02*
Y1931850D01*
G01Y1937362D02*
Y1938150D01*
G01Y1934213D02*
Y1935000D01*
G01X159796Y1940512D02*
Y1938150D01*
G01Y1937362D02*
Y1935000D01*
G01Y1934213D02*
Y1931850D01*
G01Y1931063D02*
Y1928701D01*
G01Y1927913D02*
Y1925551D01*
G01Y1924764D02*
Y1922402D01*
G01Y1921614D02*
Y1919252D01*
G01Y1918465D02*
Y1916102D01*
G01Y1915315D02*
Y1912953D01*
G01Y1912165D02*
Y1909803D01*
G01Y1909016D02*
Y1906654D01*
G01X161524Y1909016D02*
Y1909803D01*
G01Y1905866D02*
Y1906654D01*
G01Y1912165D02*
Y1912953D01*
G01Y1918465D02*
Y1919252D01*
G01Y1915315D02*
Y1916102D01*
G01Y1921614D02*
Y1922402D01*
G01Y1927913D02*
Y1928701D01*
G01Y1924764D02*
Y1925551D01*
G01Y1931063D02*
Y1931850D01*
G01Y1937362D02*
Y1938150D01*
G01Y1934213D02*
Y1935000D01*
G01X162205Y1931752D02*
Y1930177D01*
G01Y1926752D02*
Y1925177D01*
G01Y1921752D02*
Y1920177D01*
G01Y1916752D02*
Y1915177D01*
G01Y1911752D02*
Y1910177D01*
G01X163176Y1938150D02*
Y1937362D01*
G01Y1935000D02*
Y1934213D01*
G01Y1931850D02*
Y1931063D01*
G01Y1928701D02*
Y1927913D01*
G01Y1925551D02*
Y1924764D01*
G01Y1922402D02*
Y1921614D01*
G01Y1919252D02*
Y1918465D01*
G01Y1916102D02*
Y1915315D01*
G01Y1912953D02*
Y1912165D01*
G01Y1909803D02*
Y1909016D01*
G01Y1906654D02*
Y1905866D01*
G01X164173Y1936752D02*
Y1935177D01*
G01X165159Y1938150D02*
Y1937362D01*
G01Y1935000D02*
Y1934213D01*
G01Y1931850D02*
Y1931063D01*
G01Y1928701D02*
Y1927913D01*
G01Y1925551D02*
Y1924764D01*
G01Y1922402D02*
Y1921614D01*
G01Y1919252D02*
Y1918465D01*
G01Y1916102D02*
Y1915315D01*
G01Y1912953D02*
Y1912165D01*
G01Y1909803D02*
Y1909016D01*
G01Y1906654D02*
Y1905866D01*
G01X165354Y1931752D02*
Y1930177D01*
G01Y1926752D02*
Y1925177D01*
G01Y1921752D02*
Y1920177D01*
G01Y1916752D02*
Y1915177D01*
G01Y1911752D02*
Y1910177D01*
G01X166339Y1932539D02*
Y1929390D01*
G01Y1927539D02*
Y1924390D01*
G01Y1922539D02*
Y1919390D01*
G01Y1917539D02*
Y1914390D01*
G01Y1912539D02*
Y1909390D01*
G01X167323Y1936752D02*
Y1935177D01*
G01Y1932539D02*
Y1929390D01*
G01Y1927539D02*
Y1924390D01*
G01Y1922539D02*
Y1919390D01*
G01Y1917539D02*
Y1914390D01*
G01Y1912539D02*
Y1909390D01*
G01X168307Y1937539D02*
Y1934390D01*
G01Y1931752D02*
Y1930177D01*
G01Y1926752D02*
Y1925177D01*
G01Y1921752D02*
Y1920177D01*
G01Y1916752D02*
Y1915177D01*
G01Y1911752D02*
Y1910177D01*
G01X168521Y1909016D02*
Y1909803D01*
G01Y1905866D02*
Y1906654D01*
G01Y1912165D02*
Y1912953D01*
G01Y1918465D02*
Y1919252D01*
G01Y1915315D02*
Y1916102D01*
G01Y1921614D02*
Y1922402D01*
G01Y1927913D02*
Y1928701D01*
G01Y1924764D02*
Y1925551D01*
G01Y1931063D02*
Y1931850D01*
G01Y1937362D02*
Y1938150D01*
G01Y1934213D02*
Y1935000D01*
G01X168898Y1909016D02*
Y1909803D01*
G01Y1905866D02*
Y1906654D01*
G01Y1912165D02*
Y1912953D01*
G01Y1918465D02*
Y1919252D01*
G01Y1915315D02*
Y1916102D01*
G01Y1921614D02*
Y1922402D01*
G01Y1927913D02*
Y1928701D01*
G01Y1924764D02*
Y1925551D01*
G01Y1931063D02*
Y1931850D01*
G01Y1937362D02*
Y1938150D01*
G01Y1934213D02*
Y1935000D01*
G01X168924Y1909016D02*
Y1909803D01*
G01Y1905866D02*
Y1906654D01*
G01Y1912165D02*
Y1912953D01*
G01Y1918465D02*
Y1919252D01*
G01Y1915315D02*
Y1916102D01*
G01Y1921614D02*
Y1922402D01*
G01Y1927913D02*
Y1928701D01*
G01Y1924764D02*
Y1925551D01*
G01Y1931063D02*
Y1931850D01*
G01Y1937362D02*
Y1938150D01*
G01Y1934213D02*
Y1935000D01*
G01X169291Y1937539D02*
Y1934390D01*
G01X151378Y1905866D02*
X158710D01*
G01X158857D02*
X170866D01*
G01Y1906654D02*
X158857D01*
G01X158710D02*
X151378D01*
G01X162205Y1906752D02*
X169370D01*
G01X167323Y1906949D02*
X166339D01*
G01X167323Y1907343D02*
X166339D01*
G01X167323Y1907539D02*
X166339D01*
G01X151378Y1909016D02*
X158710D01*
G01X158857D02*
X170866D01*
G01X167323Y1909390D02*
X166339D01*
G01X167323Y1909587D02*
X166339D01*
G01X170866Y1909803D02*
X158857D01*
G01X158710D02*
X151378D01*
G01X167323Y1909980D02*
X166339D01*
G01X162205Y1910177D02*
X169370D01*
G01X162205Y1911752D02*
X169370D01*
G01X167323Y1911949D02*
X166339D01*
G01X151378Y1912165D02*
X158710D01*
G01X158857D02*
X170866D01*
G01X167323Y1912343D02*
X166339D01*
G01X167323Y1912539D02*
X166339D01*
G01X170866Y1912953D02*
X158857D01*
G01X158710D02*
X151378D01*
G01X167323Y1914390D02*
X166339D01*
G01X167323Y1914587D02*
X166339D01*
G01X167323Y1914980D02*
X166339D01*
G01X162205Y1915177D02*
X169370D01*
G01X151378Y1915315D02*
X158710D01*
G01X158857D02*
X170866D01*
G01Y1916102D02*
X158857D01*
G01X158710D02*
X151378D01*
G01X162205Y1916752D02*
X169370D01*
G01X167323Y1916949D02*
X166339D01*
G01X167323Y1917343D02*
X166339D01*
G01X167323Y1917539D02*
X166339D01*
G01X151378Y1918465D02*
X158710D01*
G01X158857D02*
X170866D01*
G01Y1919252D02*
X158857D01*
G01X158710D02*
X151378D01*
G01X167323Y1919390D02*
X166339D01*
G01X167323Y1919587D02*
X166339D01*
G01X167323Y1919980D02*
X166339D01*
G01X162205Y1920177D02*
X169370D01*
G01X151378Y1921614D02*
X158710D01*
G01X158857D02*
X170866D01*
G01X162205Y1921752D02*
X169370D01*
G01X167323Y1921949D02*
X166339D01*
G01X167323Y1922343D02*
X166339D01*
G01X170866Y1922402D02*
X158857D01*
G01X158710D02*
X151378D01*
G01X167323Y1922539D02*
X166339D01*
G01X167323Y1924390D02*
X166339D01*
G01X167323Y1924587D02*
X166339D01*
G01X151378Y1924764D02*
X158710D01*
G01X158857D02*
X170866D01*
G01X167323Y1924980D02*
X166339D01*
G01X162205Y1925177D02*
X169370D01*
G01X170866Y1925551D02*
X158857D01*
G01X158710D02*
X151378D01*
G01X162205Y1926752D02*
X169370D01*
G01X167323Y1926949D02*
X166339D01*
G01X167323Y1927343D02*
X166339D01*
G01X167323Y1927539D02*
X166339D01*
G01X151378Y1927913D02*
X158710D01*
G01X158857D02*
X170866D01*
G01Y1928701D02*
X158857D01*
G01X158710D02*
X151378D01*
G01X167323Y1929390D02*
X166339D01*
G01X167323Y1929587D02*
X166339D01*
G01X167323Y1929980D02*
X166339D01*
G01X162205Y1930177D02*
X169370D01*
G01X151378Y1931063D02*
X158710D01*
G01X158857D02*
X170866D01*
G01X162205Y1931752D02*
X169370D01*
G01X170866Y1931850D02*
X158857D01*
G01X158710D02*
X151378D01*
G01X167323Y1931949D02*
X166339D01*
G01X167323Y1932343D02*
X166339D01*
G01X167323Y1932539D02*
X166339D01*
G01X170866Y1933760D02*
X169764D01*
G01X151378Y1934213D02*
X158710D01*
G01X158857D02*
X170866D01*
G01X169291Y1934390D02*
X168307D01*
G01X169291Y1934587D02*
X168307D01*
G01X169291Y1934980D02*
X168307D01*
G01X170866Y1935000D02*
X158857D01*
G01X158710D02*
X151378D01*
G01X169764Y1935177D02*
X164173D01*
G01X169764Y1936752D02*
X164173D01*
G01X169291Y1936949D02*
X168307D01*
G01X169291Y1937343D02*
X168307D01*
G01X151378Y1937362D02*
X158710D01*
G01X158857D02*
X170866D01*
G01X169291Y1937539D02*
X168307D01*
G01X170866Y1938150D02*
X158857D01*
G01X158710D02*
X151378D01*
G01X170866Y1938169D02*
X169764D01*
G01X169370Y1906752D02*
G03X169764Y1907146I0J394D01*
G01Y1919783D02*
G03X169370Y1920177I-394J0D01*
G01Y1921752D02*
G03X169764Y1922146I0J394D01*
G01Y1924783D02*
G03X169370Y1925177I-394J0D01*
G01Y1926752D02*
G03X169764Y1927146I0J394D01*
G01Y1914783D02*
G03X169370Y1915177I-394J0D01*
G01Y1916752D02*
G03X169764Y1917146I0J394D01*
G01Y1909783D02*
G03X169370Y1910177I-394J0D01*
G01Y1911752D02*
G03X169764Y1912146I0J394D01*
G01Y1929783D02*
G03X169370Y1930177I-394J0D01*
G01Y1931752D02*
G03X169764Y1932146I0J394D01*
G01X174882Y1880571D02*
Y1896909D01*
G01Y1899272D02*
Y1915807D01*
G01X195106Y1878209D02*
X172913D01*
G01X181102Y1878228D02*
X199606D01*
G01Y1880571D02*
X172913D01*
G01X200563Y1884665D02*
X181102D01*
G01X199606Y1896909D02*
X172913D01*
G01X199606Y1899272D02*
X172913D01*
G01X151378Y1871220D02*
Y1872008D01*
G01Y1868071D02*
Y1868858D01*
G01Y1874370D02*
Y1875157D01*
G01Y1880669D02*
Y1881457D01*
G01Y1877520D02*
Y1878307D01*
G01Y1883819D02*
Y1884606D01*
G01Y1890118D02*
Y1890906D01*
G01Y1886969D02*
Y1887756D01*
G01Y1893268D02*
Y1894055D01*
G01Y1899567D02*
Y1900354D01*
G01Y1896417D02*
Y1897205D01*
G01Y1902717D02*
Y1903504D01*
G01X153151Y1871220D02*
Y1872008D01*
G01Y1868071D02*
Y1868858D01*
G01Y1874370D02*
Y1875157D01*
G01Y1880669D02*
Y1881457D01*
G01Y1877520D02*
Y1878307D01*
G01Y1883819D02*
Y1884606D01*
G01Y1890118D02*
Y1890906D01*
G01Y1886969D02*
Y1887756D01*
G01Y1893268D02*
Y1894055D01*
G01Y1899567D02*
Y1900354D01*
G01Y1896417D02*
Y1897205D01*
G01Y1902717D02*
Y1903504D01*
G01X153340D02*
Y1902717D01*
G01Y1900354D02*
Y1899567D01*
G01Y1897205D02*
Y1896417D01*
G01Y1894055D02*
Y1893268D01*
G01Y1890906D02*
Y1890118D01*
G01Y1887756D02*
Y1886969D01*
G01Y1884606D02*
Y1883819D01*
G01Y1881457D02*
Y1880669D01*
G01Y1878307D02*
Y1877520D01*
G01Y1875157D02*
Y1874370D01*
G01Y1872008D02*
Y1871220D01*
G01Y1868858D02*
Y1868071D01*
G01X156176Y1903504D02*
Y1902717D01*
G01Y1900354D02*
Y1899567D01*
G01Y1897205D02*
Y1896417D01*
G01Y1894055D02*
Y1893268D01*
G01Y1890906D02*
Y1890118D01*
G01Y1887756D02*
Y1886969D01*
G01Y1884606D02*
Y1883819D01*
G01Y1881457D02*
Y1880669D01*
G01Y1878307D02*
Y1877520D01*
G01Y1875157D02*
Y1874370D01*
G01Y1872008D02*
Y1871220D01*
G01Y1868858D02*
Y1868071D01*
G01X157118Y1871220D02*
Y1872008D01*
G01Y1868071D02*
Y1868858D01*
G01Y1874370D02*
Y1875157D01*
G01Y1880669D02*
Y1881457D01*
G01Y1877520D02*
Y1878307D01*
G01Y1883819D02*
Y1884606D01*
G01Y1890118D02*
Y1890906D01*
G01Y1886969D02*
Y1887756D01*
G01Y1893268D02*
Y1894055D01*
G01Y1899567D02*
Y1900354D01*
G01Y1896417D02*
Y1897205D01*
G01Y1902717D02*
Y1903504D01*
G01X158710Y1871220D02*
Y1872008D01*
G01Y1868071D02*
Y1868858D01*
G01Y1874370D02*
Y1875157D01*
G01Y1880669D02*
Y1881457D01*
G01Y1877520D02*
Y1878307D01*
G01Y1883819D02*
Y1884606D01*
G01Y1890118D02*
Y1890906D01*
G01Y1886969D02*
Y1887756D01*
G01Y1893268D02*
Y1894055D01*
G01Y1899567D02*
Y1900354D01*
G01Y1896417D02*
Y1897205D01*
G01Y1902717D02*
Y1903504D01*
G01X158857Y1871220D02*
Y1872008D01*
G01Y1868071D02*
Y1868858D01*
G01Y1874370D02*
Y1875157D01*
G01Y1880669D02*
Y1881457D01*
G01Y1877520D02*
Y1878307D01*
G01Y1883819D02*
Y1884606D01*
G01Y1890118D02*
Y1890906D01*
G01Y1886969D02*
Y1887756D01*
G01Y1893268D02*
Y1894055D01*
G01Y1899567D02*
Y1900354D01*
G01Y1896417D02*
Y1897205D01*
G01Y1902717D02*
Y1903504D01*
G01X159796Y1905866D02*
Y1903504D01*
G01Y1902717D02*
Y1900354D01*
G01Y1899567D02*
Y1897205D01*
G01Y1896417D02*
Y1894055D01*
G01Y1893268D02*
Y1890906D01*
G01Y1890118D02*
Y1887756D01*
G01Y1886969D02*
Y1884606D01*
G01Y1883819D02*
Y1881457D01*
G01Y1880669D02*
Y1878307D01*
G01Y1877520D02*
Y1875157D01*
G01Y1874370D02*
Y1872008D01*
G01Y1871220D02*
Y1868858D01*
G01X161524Y1871220D02*
Y1872008D01*
G01Y1868071D02*
Y1868858D01*
G01Y1874370D02*
Y1875157D01*
G01Y1880669D02*
Y1881457D01*
G01Y1877520D02*
Y1878307D01*
G01Y1883819D02*
Y1884606D01*
G01Y1890118D02*
Y1890906D01*
G01Y1886969D02*
Y1887756D01*
G01Y1893268D02*
Y1894055D01*
G01Y1899567D02*
Y1900354D01*
G01Y1896417D02*
Y1897205D01*
G01Y1902717D02*
Y1903504D01*
G01X161874Y1872087D02*
Y1874291D01*
G01X162205Y1906752D02*
Y1905177D01*
G01Y1901752D02*
Y1900177D01*
G01Y1891752D02*
Y1890177D01*
G01Y1886752D02*
Y1885177D01*
G01Y1881752D02*
Y1880177D01*
G01X163176Y1903504D02*
Y1902717D01*
G01Y1900354D02*
Y1899567D01*
G01Y1897205D02*
Y1896417D01*
G01Y1894055D02*
Y1893268D01*
G01Y1890906D02*
Y1890118D01*
G01Y1887756D02*
Y1886969D01*
G01Y1884606D02*
Y1883819D01*
G01Y1881457D02*
Y1880669D01*
G01Y1878307D02*
Y1877520D01*
G01Y1875157D02*
Y1874370D01*
G01Y1872008D02*
Y1871220D01*
G01Y1868858D02*
Y1868071D01*
G01X163331Y1874291D02*
Y1878110D01*
G01X163739Y1873780D02*
Y1872598D01*
G01Y1876929D02*
Y1875748D01*
G01Y1870630D02*
Y1869449D01*
G01X163757Y1874291D02*
Y1872087D01*
G01X164173Y1896752D02*
Y1895177D01*
G01X165159Y1903504D02*
Y1902717D01*
G01Y1900354D02*
Y1899567D01*
G01Y1897205D02*
Y1896417D01*
G01Y1894055D02*
Y1893268D01*
G01Y1890906D02*
Y1890118D01*
G01Y1887756D02*
Y1886969D01*
G01Y1884606D02*
Y1883819D01*
G01Y1881457D02*
Y1880669D01*
G01Y1878307D02*
Y1877520D01*
G01Y1875157D02*
Y1874370D01*
G01Y1872008D02*
Y1871220D01*
G01Y1868858D02*
Y1868071D01*
G01X165354Y1906752D02*
Y1905177D01*
G01Y1901752D02*
Y1900177D01*
G01Y1891752D02*
Y1890177D01*
G01Y1886752D02*
Y1885177D01*
G01Y1881752D02*
Y1880177D01*
G01X166339Y1907539D02*
Y1904390D01*
G01Y1902539D02*
Y1899390D01*
G01Y1892539D02*
Y1889390D01*
G01Y1887539D02*
Y1884390D01*
G01Y1882539D02*
Y1879390D01*
G01X166888Y1873780D02*
Y1872598D01*
G01Y1876929D02*
Y1875748D01*
G01Y1870630D02*
Y1869449D01*
G01X167323Y1907539D02*
Y1904390D01*
G01Y1902539D02*
Y1899390D01*
G01Y1896752D02*
Y1895177D01*
G01Y1892539D02*
Y1889390D01*
G01Y1887539D02*
Y1884390D01*
G01Y1882539D02*
Y1879390D01*
G01X168307Y1906752D02*
Y1905177D01*
G01Y1901752D02*
Y1900177D01*
G01Y1897539D02*
Y1894390D01*
G01Y1891752D02*
Y1890177D01*
G01Y1886752D02*
Y1885177D01*
G01Y1881752D02*
Y1880177D01*
G01X168521Y1871220D02*
Y1872008D01*
G01Y1868071D02*
Y1868858D01*
G01Y1874370D02*
Y1875157D01*
G01Y1880669D02*
Y1881457D01*
G01Y1877520D02*
Y1878307D01*
G01Y1883819D02*
Y1884606D01*
G01Y1890118D02*
Y1890906D01*
G01Y1886969D02*
Y1887756D01*
G01Y1893268D02*
Y1894055D01*
G01Y1899567D02*
Y1900354D01*
G01Y1896417D02*
Y1897205D01*
G01Y1902717D02*
Y1903504D01*
G01X168857Y1877520D02*
Y1875157D01*
G01Y1874370D02*
Y1872008D01*
G01Y1871220D02*
Y1868858D01*
G01X168898Y1871220D02*
Y1872008D01*
G01Y1868071D02*
Y1868858D01*
G01Y1874370D02*
Y1875157D01*
G01Y1880669D02*
Y1881457D01*
G01Y1877520D02*
Y1878307D01*
G01Y1883819D02*
Y1884606D01*
G01Y1890118D02*
Y1890906D01*
G01Y1886969D02*
Y1887756D01*
G01Y1893268D02*
Y1894055D01*
G01Y1899567D02*
Y1900354D01*
G01Y1896417D02*
Y1897205D01*
G01Y1902717D02*
Y1903504D01*
G01X168924Y1871220D02*
Y1872008D01*
G01Y1868071D02*
Y1868858D01*
G01Y1874370D02*
Y1875157D01*
G01Y1880669D02*
Y1881457D01*
G01Y1877520D02*
Y1878307D01*
G01Y1883819D02*
Y1884606D01*
G01Y1890118D02*
Y1890906D01*
G01Y1886969D02*
Y1887756D01*
G01Y1893268D02*
Y1894055D01*
G01Y1899567D02*
Y1900354D01*
G01Y1896417D02*
Y1897205D01*
G01Y1902717D02*
Y1903504D01*
G01X169291Y1897539D02*
Y1894390D01*
G01X169764Y1867480D02*
X163739D01*
G01X168857Y1867677D02*
X167872D01*
G01X168857Y1867874D02*
X167872D01*
G01X151378Y1868071D02*
X158710D01*
G01X158857D02*
X170866D01*
G01Y1868858D02*
X158857D01*
G01X158710D02*
X151378D01*
G01X168857Y1869055D02*
X167872D01*
G01X168857Y1869252D02*
X167872D01*
G01X169764Y1869449D02*
X163739D01*
G01X169764Y1870630D02*
X163739D01*
G01X168857Y1870827D02*
X167872D01*
G01X168857Y1871024D02*
X167872D01*
G01X151378Y1871220D02*
X158710D01*
G01X158857D02*
X170866D01*
G01Y1872008D02*
X158857D01*
G01X158710D02*
X151378D01*
G01X161874Y1872087D02*
X163757D01*
G01X168857Y1872205D02*
X167872D01*
G01X168857Y1872402D02*
X167872D01*
G01X169764Y1872598D02*
X163739D01*
G01X169764Y1873780D02*
X163739D01*
G01X168857Y1873976D02*
X167872D01*
G01X168857Y1874173D02*
X167872D01*
G01X163757Y1874291D02*
X161874D01*
G01X151378Y1874370D02*
X158710D01*
G01X158857D02*
X170866D01*
G01Y1875157D02*
X158857D01*
G01X158710D02*
X151378D01*
G01X168857Y1875354D02*
X167872D01*
G01X168857Y1875551D02*
X167872D01*
G01X169764Y1875748D02*
X163739D01*
G01X169764Y1876929D02*
X163739D01*
G01X168857Y1877126D02*
X167872D01*
G01X168857Y1877323D02*
X167872D01*
G01X151378Y1877520D02*
X158710D01*
G01X158857D02*
X170866D01*
G01X167872Y1877618D02*
X165748D01*
G01X170866Y1878110D02*
X163331D01*
G01X170866Y1878228D02*
X169764D01*
G01X170866Y1878307D02*
X158857D01*
G01X158710D02*
X151378D01*
G01X167323Y1879390D02*
X166339D01*
G01X167323Y1879587D02*
X166339D01*
G01X167323Y1879980D02*
X166339D01*
G01X162205Y1880177D02*
X169370D01*
G01X151378Y1880669D02*
X158710D01*
G01X158857D02*
X170866D01*
G01Y1881457D02*
X158857D01*
G01X158710D02*
X151378D01*
G01X162205Y1881752D02*
X169370D01*
G01X167323Y1881949D02*
X166339D01*
G01X167323Y1882343D02*
X166339D01*
G01X167323Y1882539D02*
X166339D01*
G01X151378Y1883819D02*
X158710D01*
G01X158857D02*
X170866D01*
G01X167323Y1884390D02*
X166339D01*
G01X167323Y1884587D02*
X166339D01*
G01X170866Y1884606D02*
X158857D01*
G01X158710D02*
X151378D01*
G01X167323Y1884980D02*
X166339D01*
G01X162205Y1885177D02*
X169370D01*
G01X162205Y1886752D02*
X169370D01*
G01X167323Y1886949D02*
X166339D01*
G01X151378Y1886969D02*
X158710D01*
G01X158857D02*
X170866D01*
G01X167323Y1887343D02*
X166339D01*
G01X167323Y1887539D02*
X166339D01*
G01X170866Y1887756D02*
X158857D01*
G01X158710D02*
X151378D01*
G01X167323Y1889390D02*
X166339D01*
G01X167323Y1889587D02*
X166339D01*
G01X167323Y1889980D02*
X166339D01*
G01X151378Y1890118D02*
X158710D01*
G01X158857D02*
X170866D01*
G01X162205Y1890177D02*
X169370D01*
G01X170866Y1890906D02*
X158857D01*
G01X158710D02*
X151378D01*
G01X162205Y1891752D02*
X169370D01*
G01X167323Y1891949D02*
X166339D01*
G01X167323Y1892343D02*
X166339D01*
G01X167323Y1892539D02*
X166339D01*
G01X151378Y1893268D02*
X158710D01*
G01X158857D02*
X170866D01*
G01Y1893760D02*
X169764D01*
G01X170866Y1894055D02*
X158857D01*
G01X158710D02*
X151378D01*
G01X169291Y1894390D02*
X168307D01*
G01X169291Y1894587D02*
X168307D01*
G01X169291Y1894980D02*
X168307D01*
G01X169764Y1895177D02*
X164173D01*
G01X151378Y1896417D02*
X158710D01*
G01X158857D02*
X170866D01*
G01X169764Y1896752D02*
X164173D01*
G01X169291Y1896949D02*
X168307D01*
G01X170866Y1897205D02*
X158857D01*
G01X158710D02*
X151378D01*
G01X169291Y1897343D02*
X168307D01*
G01X169291Y1897539D02*
X168307D01*
G01X169764Y1898169D02*
X170866D01*
G01X167323Y1899390D02*
X166339D01*
G01X151378Y1899567D02*
X158710D01*
G01X158857D02*
X170866D01*
G01X167323Y1899587D02*
X166339D01*
G01X167323Y1899980D02*
X166339D01*
G01X162205Y1900177D02*
X169370D01*
G01X170866Y1900354D02*
X158857D01*
G01X158710D02*
X151378D01*
G01X162205Y1901752D02*
X169370D01*
G01X167323Y1901949D02*
X166339D01*
G01X167323Y1902343D02*
X166339D01*
G01X167323Y1902539D02*
X166339D01*
G01X151378Y1902717D02*
X158710D01*
G01X158857D02*
X170866D01*
G01Y1903504D02*
X158857D01*
G01X158710D02*
X151378D01*
G01X167323Y1904390D02*
X166339D01*
G01X167323Y1904587D02*
X166339D01*
G01X167323Y1904980D02*
X166339D01*
G01X162205Y1905177D02*
X169370D01*
G01X169764Y1879783D02*
G03X169370Y1880177I-394J0D01*
G01Y1881752D02*
G03X169764Y1882146I0J394D01*
G01Y1904783D02*
G03X169370Y1905177I-394J0D01*
G01X169764Y1889783D02*
G03X169370Y1890177I-394J0D01*
G01Y1891752D02*
G03X169764Y1892146I0J394D01*
G01Y1884783D02*
G03X169370Y1885177I-394J0D01*
G01Y1886752D02*
G03X169764Y1887146I0J394D01*
G01Y1899783D02*
G03X169370Y1900177I-394J0D01*
G01Y1901752D02*
G03X169764Y1902146I0J394D01*
G01X173228Y1966083D02*
X149606D01*
G01Y1968051D02*
X203543D01*
G01X149606D02*
Y1954173D01*
G01X149924Y1959705D02*
Y1954173D01*
G01X150399Y1956949D02*
Y1954173D01*
G01X149606D02*
X169764D01*
G01X150399Y1956949D02*
X170866D01*
G01X149606Y1957933D02*
X173228D01*
G01X199606Y1959705D02*
X149606D01*
G01X173228Y1960335D02*
X149606D01*
G01X173228Y1962303D02*
X149606D01*
G01X151378Y1940512D02*
Y1941299D01*
G01Y1943661D02*
Y1944449D01*
G01X153151Y1940512D02*
Y1941299D01*
G01Y1943661D02*
Y1944449D01*
G01X153340D02*
Y1943661D01*
G01Y1941299D02*
Y1940512D01*
G01X156176Y1944449D02*
Y1943661D01*
G01Y1941299D02*
Y1940512D01*
G01X157118D02*
Y1941299D01*
G01Y1943661D02*
Y1944449D01*
G01X158710Y1940512D02*
Y1941299D01*
G01Y1943661D02*
Y1944449D01*
G01X158857Y1940512D02*
Y1941299D01*
G01Y1943661D02*
Y1944449D01*
G01X159796Y1946811D02*
Y1944449D01*
G01Y1943661D02*
Y1941299D01*
G01X161524Y1940512D02*
Y1941299D01*
G01Y1943661D02*
Y1944449D01*
G01X162205Y1946752D02*
Y1945177D01*
G01Y1941752D02*
Y1940177D01*
G01X163176Y1944449D02*
Y1943661D01*
G01Y1941299D02*
Y1940512D01*
G01X165159Y1944449D02*
Y1943661D01*
G01Y1941299D02*
Y1940512D01*
G01X165354Y1946752D02*
Y1945177D01*
G01Y1941752D02*
Y1940177D01*
G01X166339Y1947539D02*
Y1944390D01*
G01Y1942539D02*
Y1939390D01*
G01X167323Y1947539D02*
Y1944390D01*
G01Y1942539D02*
Y1939390D01*
G01X168307Y1946752D02*
Y1945177D01*
G01Y1941752D02*
Y1940177D01*
G01X168521Y1940512D02*
Y1941299D01*
G01Y1943661D02*
Y1944449D01*
G01X168898Y1940512D02*
Y1941299D01*
G01Y1943661D02*
Y1944449D01*
G01X168924Y1940512D02*
Y1941299D01*
G01Y1943661D02*
Y1944449D01*
G01X167323Y1939390D02*
X166339D01*
G01X167323Y1939587D02*
X166339D01*
G01X167323Y1939980D02*
X166339D01*
G01X162205Y1940177D02*
X169370D01*
G01X151378Y1940512D02*
X158710D01*
G01X158857D02*
X170866D01*
G01Y1941299D02*
X158857D01*
G01X158710D02*
X151378D01*
G01X162205Y1941752D02*
X169370D01*
G01X167323Y1941949D02*
X166339D01*
G01X167323Y1942343D02*
X166339D01*
G01X167323Y1942539D02*
X166339D01*
G01X151378Y1943661D02*
X158710D01*
G01X158857D02*
X170866D01*
G01X167323Y1944390D02*
X166339D01*
G01X170866Y1944449D02*
X158857D01*
G01X158710D02*
X151378D01*
G01X167323Y1944587D02*
X166339D01*
G01X167323Y1944980D02*
X166339D01*
G01X162205Y1945177D02*
X169370D01*
G01X169764Y1944783D02*
G03X169370Y1945177I-394J0D01*
G01X169764Y1939783D02*
G03X169370Y1940177I-394J0D01*
G01Y1941752D02*
G03X169764Y1942146I0J394D01*
G01X172298Y1975866D02*
Y1974291D01*
G01X172669D02*
Y1975866D01*
G01X173991D02*
Y1974291D01*
G01X174016Y1975866D02*
Y1974291D01*
G01X174050D02*
Y1975866D01*
G01X175424Y1966649D02*
X173984D01*
G01X203543Y1966870D02*
X177165D01*
G01X173425Y1973504D02*
G03Y1976654I0J1575D01*
G01X172554Y1966649D02*
Y1964124D01*
G01X173228Y1966083D02*
Y1962303D01*
G01Y1960335D02*
Y1957933D01*
G01X173982Y1963199D02*
Y1962643D01*
G01X173984Y1964124D02*
Y1966649D01*
G01X175424D02*
Y1962643D01*
G01X177165Y1968051D02*
Y1959705D01*
G01X179134Y1955768D02*
Y1953996D01*
G01X179449Y1954587D02*
Y1980984D01*
G01Y1954587D02*
X172913D01*
G01X199606Y1954783D02*
X181102D01*
G01X175424Y1962643D02*
X173982D01*
G01X171201Y1963194D02*
G03X173982Y1963199I1388J1207D01*
G01X172554Y1964124D02*
G03X173984I715J0D01*
G01X154432Y1966649D02*
X153641Y1965372D01*
G01X164311Y1967165D02*
X164208Y1966796D01*
X164112Y1966467D01*
X164032Y1966204D01*
X163980Y1966039D01*
X163962Y1965984D01*
G01X163071Y1980984D02*
Y1968051D01*
G01X168469Y1975866D02*
Y1974291D01*
G01X168504D02*
Y1975866D01*
G01X168528Y1974291D02*
Y1975866D01*
G01X169851D02*
Y1974291D01*
G01X170221D02*
Y1975866D01*
G01X160054Y1965984D02*
X160035Y1966040D01*
X159983Y1966206D01*
X159904Y1966464D01*
X159809Y1966791D01*
X159704Y1967165D01*
G01X152896Y1966649D02*
X153641Y1965372D01*
G01X157500Y1965493D02*
X155997D01*
G01X160054Y1965984D02*
X163962D01*
G01X169664Y1966649D02*
X168271D01*
G01X172554D02*
X171094D01*
G01X162472D02*
X161012D01*
G01X155840D02*
X154432D01*
G01X152896D02*
X151347D01*
G01X164311Y1967165D02*
X159704D01*
G01X179449Y1970807D02*
X163071D01*
G01X173425Y1973504D02*
X169094D01*
G01X174050Y1974291D02*
X168469D01*
G01Y1975866D02*
X174050D01*
G01X169094Y1976654D02*
X173425D01*
G01X179449Y1980984D02*
X163071D01*
G01X158425Y1966849D02*
G03X156840Y1966563I-264J-3073D01*
G01X160161Y1965832D02*
G03X158422Y1966849I-1807J-1094D01*
G01X156840Y1966563D02*
G03X155997Y1965493I704J-1422D01*
G01X158091Y1965858D02*
G03X157500Y1965493I-9J-646D01*
G01X166816Y1966441D02*
G03X163770Y1966439I-1521J-2363D01*
G01D02*
G03X163249Y1965873I831J-1288D01*
G01X167337Y1965875D02*
G03X166816Y1966440I-1351J-723D01*
G01X166065Y1965540D02*
G03X164592I-737J-277D01*
G01X169094Y1976654D02*
G03Y1973504I0J-1575D01*
G01X155840Y1966649D02*
X154398Y1964502D01*
G01X153444Y1963629D02*
X152755Y1962643D01*
G01X152668Y1964494D02*
X151373Y1962643D01*
G01X164766Y1957343D02*
X164511Y1956949D01*
G01X160054Y1960551D02*
X160035Y1960495D01*
X159983Y1960330D01*
X159905Y1960072D01*
X159809Y1959744D01*
X159704Y1959370D01*
G01X151378Y1946811D02*
Y1947598D01*
G01Y1949961D02*
Y1950748D01*
G01X153151Y1946811D02*
Y1947598D01*
G01Y1949961D02*
Y1950748D01*
G01X153340D02*
Y1949961D01*
G01Y1947598D02*
Y1946811D01*
G01X156176Y1950748D02*
Y1949961D01*
G01Y1947598D02*
Y1946811D01*
G01X156253Y1956949D02*
Y1959705D01*
G01X157118Y1946811D02*
Y1947598D01*
G01Y1949961D02*
Y1950748D01*
G01X158710Y1946811D02*
Y1947598D01*
G01Y1949961D02*
Y1950748D01*
G01X158857Y1946811D02*
Y1947598D01*
G01Y1949961D02*
Y1950748D01*
G01X159796Y1952421D02*
Y1950748D01*
G01Y1949961D02*
Y1947598D01*
G01X161012Y1966649D02*
Y1960895D01*
G01X161524Y1946811D02*
Y1947598D01*
G01Y1949961D02*
Y1950748D01*
G01X162205Y1951752D02*
Y1950177D01*
G01X162472Y1966649D02*
Y1960895D01*
G01X163176Y1950748D02*
Y1949961D01*
G01Y1947598D02*
Y1946811D01*
G01X164127Y1956949D02*
Y1959705D01*
G01X164766Y1957402D02*
Y1957343D01*
G01X165159Y1950748D02*
Y1949961D01*
G01Y1947598D02*
Y1946811D01*
G01X165354Y1951752D02*
Y1950177D01*
G01X166339Y1952539D02*
Y1949390D01*
G01X167323Y1959705D02*
Y1957402D01*
G01Y1952539D02*
Y1949390D01*
G01X168271Y1966649D02*
Y1963720D01*
G01X168307Y1951752D02*
Y1950177D01*
G01X168521Y1946811D02*
Y1947598D01*
G01Y1949961D02*
Y1950748D01*
G01X168898Y1946811D02*
Y1947598D01*
G01Y1949961D02*
Y1950748D01*
G01X168924Y1946811D02*
Y1947598D01*
G01Y1949961D02*
Y1950748D01*
G01X169664Y1966649D02*
Y1964124D01*
G01X171094D02*
Y1966649D01*
G01X163962Y1960551D02*
X163980Y1960495D01*
X164032Y1960330D01*
X164111Y1960071D01*
X164207Y1959744D01*
X164311Y1959370D01*
G01X153444Y1963629D02*
X154050Y1962643D01*
G01X151347Y1966649D02*
X152668Y1964494D01*
G01X154398Y1964502D02*
X155667Y1962643D01*
G01X162205Y1946752D02*
X169370D01*
G01X151378Y1946811D02*
X158710D01*
G01X158857D02*
X170866D01*
G01X167323Y1946949D02*
X166339D01*
G01X167323Y1947343D02*
X166339D01*
G01X167323Y1947539D02*
X166339D01*
G01X170866Y1947598D02*
X158857D01*
G01X158710D02*
X151378D01*
G01X167323Y1949390D02*
X166339D01*
G01X167323Y1949587D02*
X166339D01*
G01X151378Y1949961D02*
X158710D01*
G01X158857D02*
X170866D01*
G01X167323Y1949980D02*
X166339D01*
G01X162205Y1950177D02*
X169370D01*
G01X170866Y1950748D02*
X158857D01*
G01X158710D02*
X151378D01*
G01X162205Y1951752D02*
X169370D01*
G01X167323Y1951949D02*
X166339D01*
G01X167323Y1952343D02*
X166339D01*
G01X165748Y1952421D02*
X156763D01*
G01X167323Y1952539D02*
X166339D01*
G01X169764Y1953996D02*
X179134D01*
G01X201575Y1955177D02*
X170866D01*
G01X169764Y1955768D02*
X179134D01*
G01X164766Y1957343D02*
X170866D01*
G01X164766Y1957402D02*
X170866D01*
G01X159704Y1959370D02*
X164311D01*
G01X163962Y1960551D02*
X160054D01*
G01X162472Y1960895D02*
X161012D01*
G01X155667Y1962643D02*
X154050D01*
G01X152755D02*
X151373D01*
G01X158865Y1964224D02*
X157440D01*
G01X158866Y1965050D02*
X155867D01*
G01X157440Y1964224D02*
G03X158865I713J-82D01*
G01X160247Y1963816D02*
G03X160421Y1964476I-4018J1412D01*
G01D02*
G03Y1964974I-3524J249D01*
G01X155867Y1965050D02*
G03X156206Y1963607I3015J-53D01*
G01X160421Y1964972D02*
G03X160159Y1965834I-2971J-432D01*
G01X157440Y1962634D02*
G03X159082Y1962677I757J2475D01*
G01D02*
G03X160247Y1963816I-729J1911D01*
G01X156205Y1963607D02*
G03X157439Y1962633I1736J930D01*
G01X158865Y1965050D02*
G03X158091Y1965858I-792J17D01*
G01X159704Y1967165D02*
G03Y1959370I2304J-3898D01*
G01X164311D02*
G03Y1967165I-2304J3897D01*
G01X165512Y1963268D02*
G03I-3504J0D01*
G01X163962Y1960551D02*
G03Y1965984I-1954J2717D01*
G01X160054D02*
G03Y1960551I1954J-2717D01*
G01X164173Y1963268D02*
G03I-2165J0D01*
G01X163771Y1962996D02*
G03X166817I1523J2362D01*
G01X163249Y1965873D02*
G03X163250Y1963561I2163J-1155D01*
G01X167338D02*
G03X167337Y1965875I-2163J1156D01*
G01X166065Y1963856D02*
G03Y1965540I-2237J842D01*
G01X166817Y1962996D02*
G03X167338Y1963561I-830J1289D01*
G01X163250D02*
G03X163771Y1962996I1351J723D01*
G01X164592Y1963856D02*
G03X166065I737J277D01*
G01X169370Y1946752D02*
G03X169764Y1947146I0J394D01*
G01Y1949783D02*
G03X169370Y1950177I-394J0D01*
G01Y1951752D02*
G03X169764Y1952146I0J394D01*
G01X164592Y1965540D02*
G03Y1963856I2236J-842D01*
G01X168271Y1963720D02*
G03X168565Y1963049I914J0D01*
G01D02*
G03X171201Y1963194I1248J1352D01*
G01X169664Y1964124D02*
G03X171094I715J0D01*
G01X176314Y2437400D02*
Y2418463D01*
G01X203602Y187553D02*
X203547Y187938D01*
G01X203543Y188012D02*
Y195177D01*
G01X208268Y193209D02*
Y191476D01*
G01X203575Y186862D02*
X203632Y187002D01*
X203637Y187242D01*
G01X203575Y186862D02*
X203631Y186996D01*
X203638Y187232D01*
X203601Y187561D01*
G01X208268Y192580D02*
X203547Y187938D01*
G01X208268Y191476D02*
X203543Y186831D01*
G01X197341Y227126D02*
X191256D01*
G01X197588Y227323D02*
X190976D01*
G01Y227717D02*
X197588D01*
G01X197341Y227913D02*
X191256D01*
G01X197311Y228130D02*
X191565D01*
G01X191139Y228720D02*
X197725D01*
G01X191139Y229114D02*
X197725D01*
G01X197311Y229705D02*
X191565D01*
G01X197341Y230276D02*
X191256D01*
G01X197588Y230472D02*
X190976D01*
G01Y230866D02*
X197588D01*
G01X197341Y231063D02*
X191256D01*
G01X197410Y233130D02*
X191497D01*
G01X197341Y233425D02*
X191256D01*
G01X197588Y233622D02*
X190976D01*
G01X191074Y233720D02*
X197816D01*
G01X190976Y234016D02*
X197588D01*
G01X191074Y234114D02*
X197816D01*
G01X197341Y234213D02*
X191256D01*
G01X197410Y234705D02*
X191497D01*
G01X201575Y235492D02*
X195106D01*
G01X197341Y236575D02*
X191256D01*
G01X197588Y236772D02*
X190976D01*
G01Y237165D02*
X197588D01*
G01X197341Y237362D02*
X191256D01*
G01X191542Y237856D02*
X197350D01*
G01X191280Y238053D02*
X197598D01*
G01Y239037D02*
X191280D01*
G01X191542Y239234D02*
X197350D01*
G01X197341Y239724D02*
X191256D01*
G01X197588Y239921D02*
X190976D01*
G01Y240315D02*
X197588D01*
G01X192370Y237856D02*
X192341Y237860D01*
X192313Y237871D01*
X192288Y237889D01*
X192265Y237914D01*
X192247Y237944D01*
X192233Y237978D01*
X192225Y238014D01*
X192222Y238053D01*
G01X192370Y241006D02*
X192341Y241010D01*
X192313Y241021D01*
X192288Y241039D01*
X192265Y241064D01*
X192247Y241093D01*
X192233Y241127D01*
X192225Y241164D01*
X192222Y241203D01*
G01X192370Y244156D02*
X192341Y244159D01*
X192313Y244170D01*
X192288Y244189D01*
X192265Y244213D01*
X192247Y244243D01*
X192233Y244277D01*
X192225Y244313D01*
X192222Y244352D01*
G01X192370Y247305D02*
X192341Y247309D01*
X192313Y247320D01*
X192288Y247338D01*
X192265Y247363D01*
X192247Y247393D01*
X192233Y247426D01*
X192225Y247463D01*
X192222Y247502D01*
G01X192370Y250455D02*
X192341Y250459D01*
X192313Y250470D01*
X192288Y250488D01*
X192265Y250513D01*
X192247Y250542D01*
X192233Y250576D01*
X192225Y250613D01*
X192222Y250652D01*
G01X192370Y253604D02*
X192341Y253608D01*
X192313Y253619D01*
X192288Y253637D01*
X192265Y253662D01*
X192247Y253692D01*
X192233Y253726D01*
X192225Y253762D01*
X192222Y253801D01*
G01X193407Y237856D02*
X193400Y237860D01*
X193394Y237871D01*
X193389Y237889D01*
X193383Y237914D01*
X193380Y237944D01*
X193376Y237978D01*
X193375Y238014D01*
X193374Y238053D01*
G01X193407Y241006D02*
X193400Y241010D01*
X193394Y241021D01*
X193389Y241039D01*
X193383Y241064D01*
X193380Y241093D01*
X193376Y241127D01*
X193375Y241164D01*
X193374Y241203D01*
G01X193407Y244156D02*
X193400Y244159D01*
X193394Y244170D01*
X193389Y244189D01*
X193383Y244213D01*
X193380Y244243D01*
X193376Y244277D01*
X193375Y244313D01*
X193374Y244352D01*
G01X193407Y247305D02*
X193400Y247309D01*
X193394Y247320D01*
X193389Y247338D01*
X193383Y247363D01*
X193380Y247393D01*
X193376Y247426D01*
X193375Y247463D01*
X193374Y247502D01*
G01X193407Y250455D02*
X193400Y250459D01*
X193394Y250470D01*
X193389Y250488D01*
X193383Y250513D01*
X193380Y250542D01*
X193376Y250576D01*
X193375Y250613D01*
X193374Y250652D01*
G01X193407Y253604D02*
X193400Y253608D01*
X193394Y253619D01*
X193389Y253637D01*
X193383Y253662D01*
X193380Y253692D01*
X193376Y253726D01*
X193375Y253762D01*
X193374Y253801D01*
G01X192743Y227126D02*
X192705Y227152D01*
X192677Y227224D01*
X192667Y227323D01*
G01X192743Y230276D02*
X192705Y230302D01*
X192677Y230374D01*
X192667Y230472D01*
G01X192743Y233425D02*
X192705Y233452D01*
X192677Y233524D01*
X192667Y233622D01*
G01X192743Y236575D02*
X192705Y236601D01*
X192677Y236673D01*
X192667Y236772D01*
G01X192743Y239724D02*
X192705Y239751D01*
X192677Y239823D01*
X192667Y239921D01*
G01X192743Y242874D02*
X192705Y242900D01*
X192677Y242972D01*
X192667Y243071D01*
G01X192743Y246024D02*
X192705Y246050D01*
X192677Y246122D01*
X192667Y246220D01*
G01X192743Y249173D02*
X192705Y249200D01*
X192677Y249272D01*
X192667Y249370D01*
G01X192743Y252323D02*
X192705Y252349D01*
X192677Y252421D01*
X192667Y252520D01*
G01X192743Y255472D02*
X192705Y255499D01*
X192677Y255571D01*
X192667Y255669D01*
G01X192743Y258622D02*
X192705Y258648D01*
X192677Y258720D01*
X192667Y258819D01*
G01X192743Y261772D02*
X192705Y261798D01*
X192677Y261870D01*
X192667Y261969D01*
G01X192743Y264921D02*
X192705Y264948D01*
X192677Y265020D01*
X192667Y265118D01*
G01X199606Y236654D02*
X201575Y234685D01*
G01X197341Y227126D02*
X197468Y227154D01*
X197557Y227226D01*
X197588Y227323D01*
G01X197341Y230276D02*
X197468Y230303D01*
X197557Y230376D01*
X197588Y230472D01*
G01X192292Y227913D02*
X192265Y227909D01*
X192239Y227898D01*
X192215Y227880D01*
X192194Y227856D01*
X192177Y227826D01*
X192164Y227792D01*
X192156Y227756D01*
X192154Y227717D01*
G01X192292Y231063D02*
X192265Y231059D01*
X192239Y231048D01*
X192215Y231030D01*
X192194Y231005D01*
X192177Y230976D01*
X192164Y230942D01*
X192156Y230905D01*
X192154Y230866D01*
G01X192292Y234213D02*
X192265Y234209D01*
X192239Y234198D01*
X192215Y234180D01*
X192194Y234155D01*
X192177Y234125D01*
X192164Y234091D01*
X192156Y234055D01*
X192154Y234016D01*
G01X192292Y237362D02*
X192265Y237358D01*
X192239Y237347D01*
X192215Y237329D01*
X192194Y237304D01*
X192177Y237275D01*
X192164Y237241D01*
X192156Y237204D01*
X192154Y237165D01*
G01X192292Y240512D02*
X192265Y240508D01*
X192239Y240497D01*
X192215Y240479D01*
X192194Y240454D01*
X192177Y240424D01*
X192164Y240391D01*
X192156Y240354D01*
X192154Y240315D01*
G01X192292Y243661D02*
X192265Y243657D01*
X192239Y243646D01*
X192215Y243628D01*
X192194Y243604D01*
X192177Y243574D01*
X192164Y243540D01*
X192156Y243504D01*
X192154Y243465D01*
G01X192292Y246811D02*
X192265Y246807D01*
X192239Y246796D01*
X192215Y246778D01*
X192194Y246753D01*
X192177Y246724D01*
X192164Y246690D01*
X192156Y246653D01*
X192154Y246614D01*
G01X192292Y249961D02*
X192265Y249957D01*
X192239Y249946D01*
X192215Y249928D01*
X192194Y249903D01*
X192177Y249873D01*
X192164Y249839D01*
X192156Y249803D01*
X192154Y249764D01*
G01X192292Y253110D02*
X192265Y253106D01*
X192239Y253095D01*
X192215Y253077D01*
X192194Y253052D01*
X192177Y253023D01*
X192164Y252989D01*
X192156Y252952D01*
X192154Y252913D01*
G01X192292Y256260D02*
X192265Y256256D01*
X192239Y256245D01*
X192215Y256227D01*
X192194Y256202D01*
X192177Y256172D01*
X192164Y256139D01*
X192156Y256102D01*
X192154Y256063D01*
G01X192292Y259409D02*
X192265Y259406D01*
X192239Y259394D01*
X192215Y259376D01*
X192194Y259352D01*
X192177Y259322D01*
X192164Y259288D01*
X192156Y259252D01*
X192154Y259213D01*
G01X192292Y262559D02*
X192265Y262555D01*
X192239Y262544D01*
X192215Y262526D01*
X192194Y262501D01*
X192177Y262472D01*
X192164Y262438D01*
X192156Y262401D01*
X192154Y262362D01*
G01X197341Y240512D02*
X191256D01*
G01X191542Y241006D02*
X197350D01*
G01X191280Y241203D02*
X197598D01*
G01Y242187D02*
X191280D01*
G01X191542Y242384D02*
X197350D01*
G01X197341Y242874D02*
X191256D01*
G01X197588Y243071D02*
X190976D01*
G01Y243465D02*
X197588D01*
G01X197341Y243661D02*
X191256D01*
G01X191542Y244156D02*
X197350D01*
G01X191280Y244352D02*
X197598D01*
G01Y245337D02*
X191280D01*
G01X191542Y245533D02*
X197350D01*
G01X197341Y246024D02*
X191256D01*
G01X197588Y246220D02*
X190976D01*
G01Y246614D02*
X197588D01*
G01X197341Y246811D02*
X191256D01*
G01X191542Y247305D02*
X197350D01*
G01X191280Y247502D02*
X197598D01*
G01Y248486D02*
X191280D01*
G01X191542Y248683D02*
X197350D01*
G01X197341Y249173D02*
X191256D01*
G01X197588Y249370D02*
X190976D01*
G01Y249764D02*
X197588D01*
G01X197341Y249961D02*
X191256D01*
G01X191542Y250455D02*
X197350D01*
G01X191280Y250652D02*
X197598D01*
G01Y251636D02*
X191280D01*
G01X191542Y251833D02*
X197350D01*
G01X197341Y252323D02*
X191256D01*
G01X197588Y252520D02*
X190976D01*
G01Y252913D02*
X197588D01*
G01X197341Y253110D02*
X191256D01*
G01X191542Y253604D02*
X197350D01*
G01X191280Y253801D02*
X197598D01*
G01Y254785D02*
X191280D01*
G01X191542Y254982D02*
X197350D01*
G01X197341Y255472D02*
X191256D01*
G01X197588Y255669D02*
X190976D01*
G01Y256063D02*
X197588D01*
G01X197341Y256260D02*
X191256D01*
G01X195106Y257343D02*
X201575D01*
G01X197410Y258130D02*
X191497D01*
G01X197341Y258622D02*
X191256D01*
G01X191074Y258720D02*
X197816D01*
G01X197588Y258819D02*
X190976D01*
G01X191074Y259114D02*
X197816D01*
G01X190976Y259213D02*
X197588D01*
G01X197341Y259409D02*
X191256D01*
G01X197410Y259705D02*
X191497D01*
G01X197341Y261772D02*
X191256D01*
G01X197588Y261969D02*
X190976D01*
G01Y262362D02*
X197588D01*
G01X197341Y262559D02*
X191256D01*
G01X197311Y263130D02*
X191565D01*
G01X191139Y263720D02*
X197725D01*
G01X191139Y264114D02*
X197725D01*
G01X197311Y264705D02*
X191565D01*
G01X197341Y264921D02*
X191256D01*
G01X197588Y265118D02*
X190976D01*
G01X191565Y228130D02*
X191139Y228720D01*
G01X191565Y263130D02*
X191139Y263720D01*
G01X191497Y233130D02*
X191074Y233720D01*
G01X191497Y258130D02*
X191074Y258720D01*
G01X197725Y229114D02*
X197588Y229312D01*
X197450Y229509D01*
X197311Y229705D01*
G01X197816Y234114D02*
X197681Y234311D01*
X197546Y234508D01*
X197410Y234705D01*
G01X197341Y233425D02*
X197468Y233453D01*
X197557Y233526D01*
X197588Y233622D01*
G01X197341Y236575D02*
X197468Y236602D01*
X197557Y236675D01*
X197588Y236772D01*
G01X197341Y239724D02*
X197468Y239752D01*
X197557Y239825D01*
X197588Y239921D01*
G01X197341Y242874D02*
X197468Y242902D01*
X197557Y242974D01*
X197588Y243071D01*
G01X197341Y246024D02*
X197468Y246051D01*
X197557Y246124D01*
X197588Y246220D01*
G01X197341Y249173D02*
X197468Y249201D01*
X197557Y249274D01*
X197588Y249370D01*
G01X197341Y252323D02*
X197468Y252350D01*
X197557Y252423D01*
X197588Y252520D01*
G01X197341Y255472D02*
X197468Y255500D01*
X197557Y255573D01*
X197588Y255669D01*
G01X197341Y258622D02*
X197468Y258650D01*
X197557Y258722D01*
X197588Y258819D01*
G01X197341Y261772D02*
X197468Y261799D01*
X197557Y261872D01*
X197588Y261969D01*
G01X197341Y264921D02*
X197468Y264949D01*
X197557Y265022D01*
X197588Y265118D01*
G01X197350Y237856D02*
X197477Y237884D01*
X197567Y237956D01*
X197598Y238053D01*
G01X197350Y241006D02*
X197477Y241033D01*
X197567Y241106D01*
X197598Y241203D01*
G01X197350Y244156D02*
X197477Y244183D01*
X197567Y244256D01*
X197598Y244352D01*
G01X197350Y247305D02*
X197477Y247333D01*
X197567Y247405D01*
X197598Y247502D01*
G01X197350Y250455D02*
X197477Y250482D01*
X197567Y250555D01*
X197598Y250652D01*
G01X197350Y253604D02*
X197477Y253632D01*
X197567Y253704D01*
X197598Y253801D01*
G01X197725Y264114D02*
X197588Y264312D01*
X197450Y264509D01*
X197311Y264705D01*
G01X197816Y259114D02*
X197681Y259311D01*
X197546Y259508D01*
X197410Y259705D01*
G01X192255Y228130D02*
X191983Y228720D01*
G01X192255Y233130D02*
X191983Y233720D01*
G01X192255Y258130D02*
X191983Y258720D01*
G01X192255Y263130D02*
X191983Y263720D01*
G01X197598Y239037D02*
X197565Y239137D01*
X197476Y239207D01*
X197350Y239234D01*
G01X197598Y242187D02*
X197565Y242286D01*
X197476Y242357D01*
X197350Y242384D01*
G01X197598Y245337D02*
X197565Y245436D01*
X197476Y245507D01*
X197350Y245533D01*
G01X197598Y248486D02*
X197565Y248585D01*
X197476Y248656D01*
X197350Y248683D01*
G01X197598Y251636D02*
X197565Y251735D01*
X197476Y251806D01*
X197350Y251833D01*
G01X197598Y254785D02*
X197565Y254885D01*
X197476Y254956D01*
X197350Y254982D01*
G01X197588Y227717D02*
X197556Y227813D01*
X197468Y227885D01*
X197341Y227913D01*
G01X197588Y230866D02*
X197556Y230963D01*
X197468Y231035D01*
X197341Y231063D01*
G01X197588Y234016D02*
X197556Y234113D01*
X197468Y234185D01*
X197341Y234213D01*
G01X197588Y237165D02*
X197556Y237262D01*
X197468Y237334D01*
X197341Y237362D01*
G01X197588Y240315D02*
X197556Y240412D01*
X197468Y240484D01*
X197341Y240512D01*
G01X197588Y243465D02*
X197556Y243561D01*
X197468Y243633D01*
X197341Y243661D01*
G01X197588Y246614D02*
X197556Y246711D01*
X197468Y246783D01*
X197341Y246811D01*
G01X197588Y249764D02*
X197556Y249861D01*
X197468Y249933D01*
X197341Y249961D01*
G01X197588Y252913D02*
X197556Y253010D01*
X197468Y253082D01*
X197341Y253110D01*
G01X197588Y256063D02*
X197556Y256160D01*
X197468Y256232D01*
X197341Y256260D01*
G01X197588Y259213D02*
X197556Y259309D01*
X197468Y259381D01*
X197341Y259409D01*
G01X197588Y262362D02*
X197556Y262459D01*
X197468Y262531D01*
X197341Y262559D01*
G01X193107Y228720D02*
X193185Y228130D01*
G01X193107Y233720D02*
X193185Y233130D01*
G01X193107Y258720D02*
X193185Y258130D01*
G01X193107Y263720D02*
X193185Y263130D01*
G01X192154Y227323D02*
X192156Y227285D01*
X192164Y227248D01*
X192177Y227214D01*
X192194Y227183D01*
X192215Y227159D01*
X192239Y227141D01*
X192265Y227130D01*
X192292Y227126D01*
G01X192154Y230472D02*
X192156Y230434D01*
X192164Y230397D01*
X192177Y230363D01*
X192194Y230333D01*
X192215Y230309D01*
X192239Y230291D01*
X192265Y230280D01*
X192292Y230276D01*
G01X192154Y233622D02*
X192156Y233584D01*
X192164Y233547D01*
X192177Y233513D01*
X192194Y233483D01*
X192215Y233458D01*
X192239Y233440D01*
X192265Y233429D01*
X192292Y233425D01*
G01X192154Y236772D02*
X192156Y236733D01*
X192164Y236696D01*
X192177Y236663D01*
X192194Y236632D01*
X192215Y236608D01*
X192239Y236590D01*
X192265Y236579D01*
X192292Y236575D01*
G01X192154Y239921D02*
X192156Y239883D01*
X192164Y239846D01*
X192177Y239812D01*
X192194Y239782D01*
X192215Y239757D01*
X192239Y239739D01*
X192265Y239728D01*
X192292Y239724D01*
G01X192154Y243071D02*
X192156Y243033D01*
X192164Y242996D01*
X192177Y242962D01*
X192194Y242931D01*
X192215Y242907D01*
X192239Y242889D01*
X192265Y242878D01*
X192292Y242874D01*
G01X192154Y246220D02*
X192156Y246182D01*
X192164Y246145D01*
X192177Y246111D01*
X192194Y246081D01*
X192215Y246057D01*
X192239Y246039D01*
X192265Y246028D01*
X192292Y246024D01*
G01X192154Y249370D02*
X192156Y249332D01*
X192164Y249295D01*
X192177Y249261D01*
X192194Y249231D01*
X192215Y249206D01*
X192239Y249188D01*
X192265Y249177D01*
X192292Y249173D01*
G01X192154Y252520D02*
X192156Y252481D01*
X192164Y252444D01*
X192177Y252411D01*
X192194Y252380D01*
X192215Y252356D01*
X192239Y252338D01*
X192265Y252327D01*
X192292Y252323D01*
G01X192154Y255669D02*
X192156Y255631D01*
X192164Y255594D01*
X192177Y255560D01*
X192194Y255530D01*
X192215Y255506D01*
X192239Y255487D01*
X192265Y255476D01*
X192292Y255472D01*
G01X192154Y258819D02*
X192156Y258781D01*
X192164Y258744D01*
X192177Y258710D01*
X192194Y258680D01*
X192215Y258655D01*
X192239Y258637D01*
X192265Y258626D01*
X192292Y258622D01*
G01X192154Y261969D02*
X192156Y261930D01*
X192164Y261893D01*
X192177Y261859D01*
X192194Y261829D01*
X192215Y261805D01*
X192239Y261787D01*
X192265Y261776D01*
X192292Y261772D01*
G01X192154Y265118D02*
X192156Y265080D01*
X192164Y265043D01*
X192177Y265009D01*
X192194Y264979D01*
X192215Y264954D01*
X192239Y264936D01*
X192265Y264925D01*
X192292Y264921D01*
G01X190976Y265512D02*
Y265118D01*
G01Y262362D02*
Y261969D01*
G01Y259213D02*
Y258819D01*
G01Y256063D02*
Y255669D01*
G01Y252913D02*
Y252520D01*
G01Y249764D02*
Y249370D01*
G01Y246614D02*
Y246220D01*
G01Y243465D02*
Y243071D01*
G01Y240315D02*
Y239921D01*
G01Y237165D02*
Y236772D01*
G01Y230866D02*
Y230472D01*
G01Y234016D02*
Y233622D01*
G01Y227717D02*
Y227323D01*
G01X191074Y233720D02*
Y234114D01*
G01Y258720D02*
Y259114D01*
G01X191139Y228720D02*
Y229114D01*
G01Y263720D02*
Y264114D01*
G01X191280Y238053D02*
Y239037D01*
G01Y241203D02*
Y242187D01*
G01Y247502D02*
Y248486D01*
G01Y244352D02*
Y245337D01*
G01Y250652D02*
Y251636D01*
G01Y253801D02*
Y254785D01*
G01X191983Y228720D02*
Y229114D01*
G01Y233720D02*
Y234114D01*
G01Y258720D02*
Y259114D01*
G01Y263720D02*
Y264114D01*
G01X192154Y265512D02*
Y265118D01*
G01Y262362D02*
Y261969D01*
G01Y259213D02*
Y258819D01*
G01Y256063D02*
Y255669D01*
G01Y252913D02*
Y252520D01*
G01Y249764D02*
Y249370D01*
G01Y246614D02*
Y246220D01*
G01Y243465D02*
Y243071D01*
G01Y240315D02*
Y239921D01*
G01Y237165D02*
Y236772D01*
G01Y230866D02*
Y230472D01*
G01Y234016D02*
Y233622D01*
G01Y227717D02*
Y227323D01*
G01X192222Y238053D02*
Y239037D01*
G01Y241203D02*
Y242187D01*
G01Y247502D02*
Y248486D01*
G01Y244352D02*
Y245337D01*
G01Y250652D02*
Y251636D01*
G01Y253801D02*
Y254785D01*
G01X192667Y227323D02*
Y227717D01*
G01Y230472D02*
Y230866D01*
G01Y233622D02*
Y234016D01*
G01Y236772D02*
Y237165D01*
G01Y243071D02*
Y243465D01*
G01Y239921D02*
Y240315D01*
G01Y246220D02*
Y246614D01*
G01Y252520D02*
Y252913D01*
G01Y249370D02*
Y249764D01*
G01Y255669D02*
Y256063D01*
G01Y261969D02*
Y262362D01*
G01Y258819D02*
Y259213D01*
G01Y265118D02*
Y265512D01*
G01X193107Y264114D02*
Y263720D01*
G01Y259114D02*
Y258720D01*
G01Y234114D02*
Y233720D01*
G01Y229114D02*
Y228720D01*
G01X193374Y238053D02*
Y239037D01*
G01Y241203D02*
Y242187D01*
G01Y247502D02*
Y248486D01*
G01Y244352D02*
Y245337D01*
G01Y250652D02*
Y251636D01*
G01Y253801D02*
Y254785D01*
G01X195106Y257343D02*
Y256161D01*
G01Y236673D02*
Y235492D01*
G01X197588Y227323D02*
Y227717D01*
G01Y230472D02*
Y230866D01*
G01Y233622D02*
Y234016D01*
G01Y236772D02*
Y237165D01*
G01Y243071D02*
Y243465D01*
G01Y239921D02*
Y240315D01*
G01Y246220D02*
Y246614D01*
G01Y252520D02*
Y252913D01*
G01Y249370D02*
Y249764D01*
G01Y255669D02*
Y256063D01*
G01Y261969D02*
Y262362D01*
G01Y258819D02*
Y259213D01*
G01Y265118D02*
Y265512D01*
G01X197598Y254785D02*
Y253801D01*
G01Y251636D02*
Y250652D01*
G01Y248486D02*
Y247502D01*
G01Y245337D02*
Y244352D01*
G01Y242187D02*
Y241203D01*
G01Y239037D02*
Y238053D01*
G01X197725Y264114D02*
Y263720D01*
G01Y229114D02*
Y228720D01*
G01X197816Y259114D02*
Y258720D01*
G01Y234114D02*
Y233720D01*
G01X200394Y333524D02*
Y262618D01*
G01Y235492D02*
Y257343D01*
G01X200563Y262618D02*
Y257138D01*
G01Y235696D02*
Y230315D01*
G01X193374Y254785D02*
X193375Y254824D01*
X193376Y254861D01*
X193380Y254894D01*
X193383Y254925D01*
X193389Y254949D01*
X193394Y254967D01*
X193400Y254978D01*
X193407Y254982D01*
G01X193374Y251636D02*
X193375Y251674D01*
X193376Y251711D01*
X193380Y251745D01*
X193383Y251775D01*
X193389Y251800D01*
X193394Y251818D01*
X193400Y251829D01*
X193407Y251833D01*
G01X193374Y248486D02*
X193375Y248524D01*
X193376Y248561D01*
X193380Y248595D01*
X193383Y248626D01*
X193389Y248650D01*
X193394Y248668D01*
X193400Y248679D01*
X193407Y248683D01*
G01X193374Y245337D02*
X193375Y245375D01*
X193376Y245412D01*
X193380Y245446D01*
X193383Y245476D01*
X193389Y245500D01*
X193394Y245519D01*
X193400Y245530D01*
X193407Y245533D01*
G01X193374Y242187D02*
X193375Y242225D01*
X193376Y242262D01*
X193380Y242296D01*
X193383Y242326D01*
X193389Y242351D01*
X193394Y242369D01*
X193400Y242380D01*
X193407Y242384D01*
G01X193374Y239037D02*
X193375Y239076D01*
X193376Y239113D01*
X193380Y239146D01*
X193383Y239177D01*
X193389Y239201D01*
X193394Y239219D01*
X193400Y239230D01*
X193407Y239234D01*
G01X192222Y254785D02*
X192225Y254824D01*
X192233Y254861D01*
X192247Y254894D01*
X192265Y254925D01*
X192288Y254949D01*
X192313Y254967D01*
X192341Y254978D01*
X192370Y254982D01*
G01X192222Y251636D02*
X192225Y251674D01*
X192233Y251711D01*
X192247Y251745D01*
X192265Y251775D01*
X192288Y251800D01*
X192313Y251818D01*
X192341Y251829D01*
X192370Y251833D01*
G01X192222Y248486D02*
X192225Y248524D01*
X192233Y248561D01*
X192247Y248595D01*
X192265Y248626D01*
X192288Y248650D01*
X192313Y248668D01*
X192341Y248679D01*
X192370Y248683D01*
G01X192222Y245337D02*
X192225Y245375D01*
X192233Y245412D01*
X192247Y245446D01*
X192265Y245476D01*
X192288Y245500D01*
X192313Y245519D01*
X192341Y245530D01*
X192370Y245533D01*
G01X192222Y242187D02*
X192225Y242225D01*
X192233Y242262D01*
X192247Y242296D01*
X192265Y242326D01*
X192288Y242351D01*
X192313Y242369D01*
X192341Y242380D01*
X192370Y242384D01*
G01X192222Y239037D02*
X192225Y239076D01*
X192233Y239113D01*
X192247Y239146D01*
X192265Y239177D01*
X192288Y239201D01*
X192313Y239219D01*
X192341Y239230D01*
X192370Y239234D01*
G01X192667Y262362D02*
X192677Y262461D01*
X192705Y262533D01*
X192743Y262559D01*
G01X192667Y259213D02*
X192677Y259311D01*
X192705Y259383D01*
X192743Y259409D01*
G01X192667Y256063D02*
X192677Y256161D01*
X192705Y256233D01*
X192743Y256260D01*
G01X192667Y252913D02*
X192677Y253012D01*
X192705Y253084D01*
X192743Y253110D01*
G01X192667Y246614D02*
X192677Y246713D01*
X192705Y246785D01*
X192743Y246811D01*
G01X192667Y243465D02*
X192677Y243563D01*
X192705Y243635D01*
X192743Y243661D01*
G01X192667Y240315D02*
X192677Y240413D01*
X192705Y240485D01*
X192743Y240512D01*
G01X192667Y237165D02*
X192677Y237264D01*
X192705Y237336D01*
X192743Y237362D01*
G01X192667Y227717D02*
X192677Y227815D01*
X192705Y227887D01*
X192743Y227913D01*
G01X193107Y264114D02*
X193185Y264705D01*
G01X193107Y259114D02*
X193185Y259705D01*
G01X193107Y234114D02*
X193185Y234705D01*
G01X193107Y229114D02*
X193185Y229705D01*
G01X191983Y264114D02*
X192255Y264705D01*
G01X191983Y259114D02*
X192255Y259705D01*
G01X191983Y234114D02*
X192255Y234705D01*
G01X191983Y229114D02*
X192255Y229705D01*
G01X197410Y258130D02*
X197546Y258326D01*
X197681Y258523D01*
X197816Y258720D01*
G01X197410Y233130D02*
X197546Y233326D01*
X197681Y233523D01*
X197816Y233720D01*
G01X197311Y263130D02*
X197450Y263326D01*
X197588Y263523D01*
X197725Y263720D01*
G01X197311Y228130D02*
X197450Y228326D01*
X197588Y228523D01*
X197725Y228720D01*
G01X191497Y259705D02*
X191074Y259114D01*
G01X191497Y234705D02*
X191074Y234114D01*
G01X191565Y264705D02*
X191139Y264114D01*
G01X191565Y229705D02*
X191139Y229114D01*
G01X201575Y258150D02*
X199606Y256181D01*
G01X192743Y249961D02*
X192705Y249934D01*
X192677Y249862D01*
X192667Y249764D01*
G01X192743Y234213D02*
X192705Y234186D01*
X192677Y234114D01*
X192667Y234016D01*
G01X192743Y231063D02*
X192705Y231037D01*
X192677Y230964D01*
X192667Y230866D01*
G01X192292Y265709D02*
X192265Y265705D01*
X192239Y265694D01*
X192215Y265676D01*
X192194Y265651D01*
X192177Y265621D01*
X192164Y265587D01*
X192156Y265551D01*
X192154Y265512D01*
G01X190976D02*
X197588D01*
G01X197341Y265709D02*
X191256D01*
G01X197588Y265512D02*
X197556Y265609D01*
X197468Y265681D01*
X197341Y265709D01*
G01X192667Y265512D02*
X192677Y265610D01*
X192705Y265682D01*
X192743Y265709D01*
G01X204858Y195177D02*
X208268Y193209D01*
G01X204858Y195177D02*
X201575D01*
G01X197311Y203130D02*
X191565D01*
G01X191139Y203720D02*
X197725D01*
G01X191139Y204114D02*
X197725D01*
G01X197311Y204705D02*
X191565D01*
G01X197341Y205079D02*
X191256D01*
G01X197588Y205276D02*
X190976D01*
G01Y205669D02*
X197588D01*
G01X197341Y205866D02*
X191256D01*
G01X197311Y208130D02*
X191565D01*
G01X197341Y208228D02*
X191256D01*
G01X197588Y208425D02*
X190976D01*
G01X191139Y208720D02*
X197725D01*
G01X190976Y208819D02*
X197588D01*
G01X197341Y209016D02*
X191256D01*
G01X191139Y209114D02*
X197725D01*
G01X197311Y209705D02*
X191565D01*
G01X197341Y211378D02*
X191256D01*
G01X197588Y211575D02*
X190976D01*
G01Y211969D02*
X197588D01*
G01X197341Y212165D02*
X191256D01*
G01X197311Y213130D02*
X191565D01*
G01X191139Y213720D02*
X197725D01*
G01X191139Y214114D02*
X197725D01*
G01X197341Y214528D02*
X191256D01*
G01X197311Y214705D02*
X191565D01*
G01X197588Y214724D02*
X190976D01*
G01Y215118D02*
X197588D01*
G01X197341Y215315D02*
X191256D01*
G01X197341Y217677D02*
X191256D01*
G01X197588Y217874D02*
X190976D01*
G01X197311Y218130D02*
X191565D01*
G01X190976Y218268D02*
X197588D01*
G01X197341Y218465D02*
X191256D01*
G01X191139Y218720D02*
X197725D01*
G01X191139Y219114D02*
X197725D01*
G01X197311Y219705D02*
X191565D01*
G01X197341Y220827D02*
X191256D01*
G01X197588Y221024D02*
X190976D01*
G01Y221417D02*
X197588D01*
G01X197341Y221614D02*
X191256D01*
G01X197311Y223130D02*
X191565D01*
G01X191139Y223720D02*
X197725D01*
G01X197341Y223976D02*
X191256D01*
G01X191139Y224114D02*
X197725D01*
G01X197588Y224173D02*
X190976D01*
G01Y224567D02*
X197588D01*
G01X197311Y224705D02*
X191565D01*
G01X197341Y224764D02*
X191256D01*
G01X192743Y205079D02*
X192705Y205105D01*
X192677Y205177D01*
X192667Y205276D01*
G01X192743Y208228D02*
X192705Y208255D01*
X192677Y208327D01*
X192667Y208425D01*
G01X192743Y211378D02*
X192705Y211404D01*
X192677Y211476D01*
X192667Y211575D01*
G01X192743Y214528D02*
X192705Y214554D01*
X192677Y214626D01*
X192667Y214724D01*
G01X192743Y217677D02*
X192705Y217704D01*
X192677Y217776D01*
X192667Y217874D01*
G01X192743Y220827D02*
X192705Y220853D01*
X192677Y220925D01*
X192667Y221024D01*
G01X192743Y223976D02*
X192705Y224003D01*
X192677Y224075D01*
X192667Y224173D01*
G01X201575Y198130D02*
X199606Y200098D01*
G01X197341Y205079D02*
X197468Y205106D01*
X197557Y205179D01*
X197588Y205276D01*
G01X197341Y208228D02*
X197468Y208256D01*
X197557Y208329D01*
X197588Y208425D01*
G01X197341Y211378D02*
X197468Y211406D01*
X197557Y211478D01*
X197588Y211575D01*
G01X197341Y214528D02*
X197468Y214555D01*
X197557Y214628D01*
X197588Y214724D01*
G01X197341Y217677D02*
X197468Y217705D01*
X197557Y217778D01*
X197588Y217874D01*
G01X197341Y220827D02*
X197468Y220854D01*
X197557Y220927D01*
X197588Y221024D01*
G01X197341Y223976D02*
X197468Y224004D01*
X197557Y224077D01*
X197588Y224173D01*
G01X192292Y205866D02*
X192265Y205862D01*
X192239Y205851D01*
X192215Y205833D01*
X192194Y205808D01*
X192177Y205779D01*
X192164Y205745D01*
X192156Y205708D01*
X192154Y205669D01*
G01X192292Y209016D02*
X192265Y209012D01*
X192239Y209001D01*
X192215Y208983D01*
X192194Y208958D01*
X192177Y208928D01*
X192164Y208894D01*
X192156Y208858D01*
X192154Y208819D01*
G01X192292Y212165D02*
X192265Y212161D01*
X192239Y212150D01*
X192215Y212132D01*
X192194Y212107D01*
X192177Y212078D01*
X192164Y212044D01*
X192156Y212007D01*
X192154Y211969D01*
G01X192292Y215315D02*
X192265Y215311D01*
X192239Y215300D01*
X192215Y215282D01*
X192194Y215257D01*
X192177Y215228D01*
X192164Y215194D01*
X192156Y215157D01*
X192154Y215118D01*
G01X192292Y218465D02*
X192265Y218461D01*
X192239Y218450D01*
X192215Y218431D01*
X192194Y218407D01*
X192177Y218377D01*
X192164Y218343D01*
X192156Y218307D01*
X192154Y218268D01*
G01X192292Y221614D02*
X192265Y221610D01*
X192239Y221599D01*
X192215Y221581D01*
X192194Y221556D01*
X192177Y221527D01*
X192164Y221493D01*
X192156Y221456D01*
X192154Y221417D01*
G01X192292Y224764D02*
X192265Y224760D01*
X192239Y224749D01*
X192215Y224731D01*
X192194Y224706D01*
X192177Y224676D01*
X192164Y224643D01*
X192156Y224606D01*
X192154Y224567D01*
G01X191565Y203130D02*
X191139Y203720D01*
G01X191565Y208130D02*
X191139Y208720D01*
G01X191565Y213130D02*
X191139Y213720D01*
G01X191565Y218130D02*
X191139Y218720D01*
G01X191565Y223130D02*
X191139Y223720D01*
G01X197725Y204114D02*
X197588Y204312D01*
X197450Y204509D01*
X197311Y204705D01*
G01X197725Y209114D02*
X197588Y209312D01*
X197450Y209509D01*
X197311Y209705D01*
G01X197725Y214114D02*
X197588Y214312D01*
X197450Y214509D01*
X197311Y214705D01*
G01X197725Y219114D02*
X197588Y219312D01*
X197450Y219509D01*
X197311Y219705D01*
G01X197725Y224114D02*
X197588Y224312D01*
X197450Y224509D01*
X197311Y224705D01*
G01X192255Y203130D02*
X191983Y203720D01*
G01X192255Y208130D02*
X191983Y208720D01*
G01X192255Y213130D02*
X191983Y213720D01*
G01X192255Y218130D02*
X191983Y218720D01*
G01X192255Y223130D02*
X191983Y223720D01*
G01X197588Y205669D02*
X197556Y205766D01*
X197468Y205838D01*
X197341Y205866D01*
G01X197588Y208819D02*
X197556Y208916D01*
X197468Y208988D01*
X197341Y209016D01*
G01X197588Y211969D02*
X197556Y212065D01*
X197468Y212137D01*
X197341Y212165D01*
G01X197588Y215118D02*
X197556Y215215D01*
X197468Y215287D01*
X197341Y215315D01*
G01X197588Y218268D02*
X197556Y218365D01*
X197468Y218437D01*
X197341Y218465D01*
G01X197588Y221417D02*
X197556Y221514D01*
X197468Y221586D01*
X197341Y221614D01*
G01X197588Y224567D02*
X197556Y224664D01*
X197468Y224736D01*
X197341Y224764D01*
G01X193107Y203720D02*
X193185Y203130D01*
G01X193107Y208720D02*
X193185Y208130D01*
G01X193107Y213720D02*
X193185Y213130D01*
G01X193107Y218720D02*
X193185Y218130D01*
G01X193107Y223720D02*
X193185Y223130D01*
G01X192154Y205276D02*
X192156Y205237D01*
X192164Y205200D01*
X192177Y205167D01*
X192194Y205136D01*
X192215Y205112D01*
X192239Y205094D01*
X192265Y205083D01*
X192292Y205079D01*
G01X192154Y208425D02*
X192156Y208387D01*
X192164Y208350D01*
X192177Y208316D01*
X192194Y208286D01*
X192215Y208261D01*
X192239Y208243D01*
X192265Y208232D01*
X192292Y208228D01*
G01X192154Y211575D02*
X192156Y211537D01*
X192164Y211500D01*
X192177Y211466D01*
X192194Y211435D01*
X192215Y211411D01*
X192239Y211393D01*
X192265Y211382D01*
X192292Y211378D01*
G01X192154Y214724D02*
X192156Y214686D01*
X192164Y214649D01*
X192177Y214615D01*
X192194Y214585D01*
X192215Y214561D01*
X192239Y214543D01*
X192265Y214531D01*
X192292Y214528D01*
G01X192154Y217874D02*
X192156Y217836D01*
X192164Y217799D01*
X192177Y217765D01*
X192194Y217735D01*
X192215Y217710D01*
X192239Y217692D01*
X192265Y217681D01*
X192292Y217677D01*
G01X192154Y221024D02*
X192156Y220985D01*
X192164Y220948D01*
X192177Y220915D01*
X192194Y220884D01*
X192215Y220860D01*
X192239Y220842D01*
X192265Y220831D01*
X192292Y220827D01*
G01X192154Y224173D02*
X192156Y224135D01*
X192164Y224098D01*
X192177Y224064D01*
X192194Y224034D01*
X192215Y224009D01*
X192239Y223991D01*
X192265Y223980D01*
X192292Y223976D01*
G01X190976Y221417D02*
Y221024D01*
G01Y224567D02*
Y224173D01*
G01Y218268D02*
Y217874D01*
G01Y211969D02*
Y211575D01*
G01Y215118D02*
Y214724D01*
G01Y208819D02*
Y208425D01*
G01Y205669D02*
Y205276D01*
G01X191139Y203720D02*
Y204114D01*
G01Y208720D02*
Y209114D01*
G01Y213720D02*
Y214114D01*
G01Y218720D02*
Y219114D01*
G01Y223720D02*
Y224114D01*
G01X191983Y203720D02*
Y204114D01*
G01Y208720D02*
Y209114D01*
G01Y213720D02*
Y214114D01*
G01Y218720D02*
Y219114D01*
G01Y223720D02*
Y224114D01*
G01X192154Y221417D02*
Y221024D01*
G01Y224567D02*
Y224173D01*
G01Y218268D02*
Y217874D01*
G01Y211969D02*
Y211575D01*
G01Y215118D02*
Y214724D01*
G01Y208819D02*
Y208425D01*
G01Y205669D02*
Y205276D01*
G01X192667D02*
Y205669D01*
G01Y208425D02*
Y208819D01*
G01Y211575D02*
Y211969D01*
G01Y214724D02*
Y215118D01*
G01Y217874D02*
Y218268D01*
G01Y221024D02*
Y221417D01*
G01Y224173D02*
Y224567D01*
G01X193107Y224114D02*
Y223720D01*
G01Y219114D02*
Y218720D01*
G01Y214114D02*
Y213720D01*
G01Y209114D02*
Y208720D01*
G01Y204114D02*
Y203720D01*
G01X197588Y205276D02*
Y205669D01*
G01Y208425D02*
Y208819D01*
G01Y211575D02*
Y211969D01*
G01Y214724D02*
Y215118D01*
G01Y217874D02*
Y218268D01*
G01Y221024D02*
Y221417D01*
G01Y224173D02*
Y224567D01*
G01X197725Y224114D02*
Y223720D01*
G01Y219114D02*
Y218720D01*
G01Y214114D02*
Y213720D01*
G01Y209114D02*
Y208720D01*
G01Y204114D02*
Y203720D01*
G01X199606Y200098D02*
Y332736D01*
G01X200394Y230315D02*
Y199311D01*
G01X200453Y333130D02*
Y199705D01*
G01X201575Y195177D02*
Y337657D01*
G01X192667Y224567D02*
X192677Y224665D01*
X192705Y224737D01*
X192743Y224764D01*
G01X192667Y211969D02*
X192677Y212067D01*
X192705Y212139D01*
X192743Y212165D01*
G01X192667Y208819D02*
X192677Y208917D01*
X192705Y208989D01*
X192743Y209016D01*
G01X193107Y224114D02*
X193185Y224705D01*
G01X193107Y219114D02*
X193185Y219705D01*
G01X193107Y214114D02*
X193185Y214705D01*
G01X193107Y209114D02*
X193185Y209705D01*
G01X193107Y204114D02*
X193185Y204705D01*
G01X191983Y224114D02*
X192255Y224705D01*
G01X191983Y219114D02*
X192255Y219705D01*
G01X191983Y214114D02*
X192255Y214705D01*
G01X191983Y209114D02*
X192255Y209705D01*
G01X191983Y204114D02*
X192255Y204705D01*
G01X197311Y223130D02*
X197450Y223326D01*
X197588Y223523D01*
X197725Y223720D01*
G01X197311Y218130D02*
X197450Y218326D01*
X197588Y218523D01*
X197725Y218720D01*
G01X197311Y213130D02*
X197450Y213326D01*
X197588Y213523D01*
X197725Y213720D01*
G01X197311Y208130D02*
X197450Y208326D01*
X197588Y208523D01*
X197725Y208720D01*
G01X197311Y203130D02*
X197450Y203326D01*
X197588Y203523D01*
X197725Y203720D01*
G01X191565Y224705D02*
X191139Y224114D01*
G01X191565Y219705D02*
X191139Y219114D01*
G01X191565Y214705D02*
X191139Y214114D01*
G01X191565Y209705D02*
X191139Y209114D01*
G01X191565Y204705D02*
X191139Y204114D01*
G01X201575Y197146D02*
X199606Y195177D01*
G01X192743Y221614D02*
X192705Y221588D01*
X192677Y221515D01*
X192667Y221417D01*
G01X192743Y218465D02*
X192705Y218438D01*
X192677Y218366D01*
X192667Y218268D01*
G01X192743Y215315D02*
X192705Y215289D01*
X192677Y215216D01*
X192667Y215118D01*
G01X192743Y205866D02*
X192705Y205840D01*
X192677Y205767D01*
X192667Y205669D01*
G01X197341Y287756D02*
X197467Y287728D01*
X197557Y287656D01*
X197588Y287559D01*
G01X192743Y286969D02*
X192705Y286995D01*
X192677Y287067D01*
X192667Y287165D01*
G01X192743Y290118D02*
X192705Y290144D01*
X192677Y290217D01*
X192667Y290315D01*
G01X192743Y293268D02*
X192705Y293294D01*
X192677Y293366D01*
X192667Y293465D01*
G01X192743Y296417D02*
X192705Y296444D01*
X192677Y296516D01*
X192667Y296614D01*
G01X197341Y286969D02*
X191256D01*
G01X197588Y287165D02*
X190976D01*
G01Y287559D02*
X197588D01*
G01X197341Y287756D02*
X191256D01*
G01X197311Y288130D02*
X191565D01*
G01X191139Y288720D02*
X197725D01*
G01X191139Y289114D02*
X197725D01*
G01X197311Y289705D02*
X191565D01*
G01X197341Y290118D02*
X191256D01*
G01X197588Y290315D02*
X190976D01*
G01Y290709D02*
X197588D01*
G01X197341Y290906D02*
X191256D01*
G01X197311Y293130D02*
X191565D01*
G01X197341Y293268D02*
X191256D01*
G01X197588Y293465D02*
X190976D01*
G01X191139Y293720D02*
X197725D01*
G01X190976Y293858D02*
X197588D01*
G01X197341Y294055D02*
X191256D01*
G01X191139Y294114D02*
X197725D01*
G01X197311Y294705D02*
X191565D01*
G01X197341Y296417D02*
X191256D01*
G01X197588Y296614D02*
X190976D01*
G01Y297008D02*
X197588D01*
G01X197341Y297205D02*
X191256D01*
G01X197311Y298130D02*
X191565D01*
G01X191139Y298720D02*
X197725D01*
G01X191139Y299114D02*
X197725D01*
G01X197341Y299567D02*
X191256D01*
G01X197311Y299705D02*
X191565D01*
G01X197588Y299764D02*
X190976D01*
G01Y300157D02*
X197588D01*
G01X197341Y300354D02*
X191256D01*
G01X197341Y302717D02*
X191256D01*
G01X197588Y302913D02*
X190976D01*
G01X197311Y303130D02*
X191565D01*
G01X190976Y303307D02*
X197588D01*
G01X197341Y303504D02*
X191256D01*
G01X191139Y303720D02*
X197725D01*
G01X191139Y304114D02*
X197725D01*
G01X197311Y304705D02*
X191565D01*
G01X197341Y305866D02*
X191256D01*
G01X197588Y306063D02*
X190976D01*
G01Y306457D02*
X197588D01*
G01X197341Y306654D02*
X191256D01*
G01X197311Y308130D02*
X191565D01*
G01X191139Y308720D02*
X197725D01*
G01X197341Y309016D02*
X191256D01*
G01X191139Y309114D02*
X197725D01*
G01X197588Y309213D02*
X190976D01*
G01Y309606D02*
X197588D01*
G01X197311Y309705D02*
X191565D01*
G01X197341Y309803D02*
X191256D01*
G01X197341Y312165D02*
X191256D01*
G01X197588Y312362D02*
X190976D01*
G01Y312756D02*
X197588D01*
G01X197341Y312953D02*
X191256D01*
G01X199279Y313130D02*
X193534D01*
G01X193107Y313720D02*
X199693D01*
G01X193107Y314114D02*
X199693D01*
G01X199279Y314705D02*
X193534D01*
G01X197341Y315315D02*
X191256D01*
G01X197588Y315512D02*
X190976D01*
G01Y315906D02*
X197588D01*
G01X197341Y316102D02*
X191256D01*
G01X197341D02*
X197467Y316075D01*
X197557Y316002D01*
X197588Y315906D01*
G01X192743Y299567D02*
X192705Y299593D01*
X192677Y299665D01*
X192667Y299764D01*
G01X192743Y302717D02*
X192705Y302743D01*
X192677Y302815D01*
X192667Y302913D01*
G01X192743Y305866D02*
X192705Y305893D01*
X192677Y305965D01*
X192667Y306063D01*
G01X192743Y309016D02*
X192705Y309042D01*
X192677Y309114D01*
X192667Y309213D01*
G01X192743Y312165D02*
X192705Y312192D01*
X192677Y312264D01*
X192667Y312362D01*
G01X192743Y315315D02*
X192705Y315341D01*
X192677Y315413D01*
X192667Y315512D01*
G01X192743Y318465D02*
X192705Y318491D01*
X192677Y318563D01*
X192667Y318661D01*
G01X192743Y321614D02*
X192705Y321641D01*
X192677Y321713D01*
X192667Y321811D01*
G01X192743Y324764D02*
X192705Y324790D01*
X192677Y324862D01*
X192667Y324961D01*
G01X192743Y327913D02*
X192705Y327940D01*
X192677Y328012D01*
X192667Y328110D01*
G01X199606Y337657D02*
X201575Y335689D01*
G01X197341Y290118D02*
X197468Y290146D01*
X197557Y290219D01*
X197588Y290315D01*
G01X197341Y293268D02*
X197468Y293295D01*
X197557Y293368D01*
X197588Y293465D01*
G01X197341Y296417D02*
X197468Y296445D01*
X197557Y296518D01*
X197588Y296614D01*
G01X197341Y299567D02*
X197468Y299594D01*
X197557Y299667D01*
X197588Y299764D01*
G01X197341Y302717D02*
X197468Y302744D01*
X197557Y302817D01*
X197588Y302913D01*
G01X197341Y305866D02*
X197468Y305894D01*
X197557Y305967D01*
X197588Y306063D01*
G01X197341Y309016D02*
X197468Y309043D01*
X197557Y309116D01*
X197588Y309213D01*
G01X192292Y287756D02*
X192265Y287752D01*
X192239Y287741D01*
X192215Y287723D01*
X192194Y287698D01*
X192177Y287669D01*
X192164Y287635D01*
X192156Y287598D01*
X192154Y287559D01*
G01X192292Y290906D02*
X192265Y290902D01*
X192239Y290891D01*
X192215Y290872D01*
X192194Y290848D01*
X192177Y290818D01*
X192164Y290784D01*
X192156Y290748D01*
X192154Y290709D01*
G01X192292Y294055D02*
X192265Y294051D01*
X192239Y294040D01*
X192215Y294022D01*
X192194Y293997D01*
X192177Y293968D01*
X192164Y293934D01*
X192156Y293897D01*
X192154Y293858D01*
G01X192292Y297205D02*
X192265Y297201D01*
X192239Y297190D01*
X192215Y297172D01*
X192194Y297147D01*
X192177Y297117D01*
X192164Y297083D01*
X192156Y297047D01*
X192154Y297008D01*
G01X192292Y300354D02*
X192265Y300350D01*
X192239Y300339D01*
X192215Y300321D01*
X192194Y300296D01*
X192177Y300267D01*
X192164Y300233D01*
X192156Y300196D01*
X192154Y300157D01*
G01X192292Y303504D02*
X192265Y303500D01*
X192239Y303489D01*
X192215Y303471D01*
X192194Y303446D01*
X192177Y303417D01*
X192164Y303383D01*
X192156Y303346D01*
X192154Y303307D01*
G01X192292Y306654D02*
X192265Y306650D01*
X192239Y306639D01*
X192215Y306620D01*
X192194Y306596D01*
X192177Y306566D01*
X192164Y306532D01*
X192156Y306496D01*
X192154Y306457D01*
G01X192292Y309803D02*
X192265Y309799D01*
X192239Y309788D01*
X192215Y309770D01*
X192194Y309745D01*
X192177Y309716D01*
X192164Y309682D01*
X192156Y309645D01*
X192154Y309606D01*
G01X192292Y312953D02*
X192265Y312949D01*
X192239Y312938D01*
X192215Y312920D01*
X192194Y312895D01*
X192177Y312865D01*
X192164Y312831D01*
X192156Y312795D01*
X192154Y312756D01*
G01X192292Y316102D02*
X192265Y316098D01*
X192239Y316087D01*
X192215Y316069D01*
X192194Y316044D01*
X192177Y316015D01*
X192164Y315981D01*
X192156Y315944D01*
X192154Y315906D01*
G01X192292Y319252D02*
X192265Y319248D01*
X192239Y319237D01*
X192215Y319219D01*
X192194Y319194D01*
X192177Y319165D01*
X192164Y319131D01*
X192156Y319094D01*
X192154Y319055D01*
G01X192292Y322402D02*
X192265Y322398D01*
X192239Y322387D01*
X192215Y322369D01*
X192194Y322344D01*
X192177Y322314D01*
X192164Y322280D01*
X192156Y322244D01*
X192154Y322205D01*
G01X192292Y325551D02*
X192265Y325547D01*
X192239Y325536D01*
X192215Y325518D01*
X192194Y325493D01*
X192177Y325464D01*
X192164Y325430D01*
X192156Y325393D01*
X192154Y325354D01*
G01X192292Y328701D02*
X192265Y328697D01*
X192239Y328686D01*
X192215Y328668D01*
X192194Y328643D01*
X192177Y328613D01*
X192164Y328580D01*
X192156Y328543D01*
X192154Y328504D01*
G01X197311Y318130D02*
X191565D01*
G01X197341Y318465D02*
X191256D01*
G01X197588Y318661D02*
X190976D01*
G01X191139Y318720D02*
X197725D01*
G01X190976Y319055D02*
X197588D01*
G01X191139Y319114D02*
X197725D01*
G01X197341Y319252D02*
X191256D01*
G01X197311Y319705D02*
X191565D01*
G01X197341Y321614D02*
X191256D01*
G01X197588Y321811D02*
X190976D01*
G01Y322205D02*
X197588D01*
G01X197341Y322402D02*
X191256D01*
G01X197311Y323130D02*
X191565D01*
G01X191139Y323720D02*
X197725D01*
G01X191139Y324114D02*
X197725D01*
G01X197311Y324705D02*
X191565D01*
G01X197341Y324764D02*
X191256D01*
G01X197588Y324961D02*
X190976D01*
G01Y325354D02*
X197588D01*
G01X197341Y325551D02*
X191256D01*
G01X197341Y327913D02*
X191256D01*
G01X197588Y328110D02*
X190976D01*
G01X197311Y328130D02*
X191565D01*
G01X190976Y328504D02*
X197588D01*
G01X197341Y328701D02*
X191256D01*
G01X191139Y328720D02*
X197725D01*
G01X191139Y329114D02*
X197725D01*
G01X197311Y329705D02*
X191565D01*
G01X204858Y337657D02*
X201575D01*
G01X191565Y288130D02*
X191139Y288720D01*
G01X191565Y293130D02*
X191139Y293720D01*
G01X191565Y298130D02*
X191139Y298720D01*
G01X191565Y303130D02*
X191139Y303720D01*
G01X191565Y308130D02*
X191139Y308720D01*
G01X193534Y313130D02*
X193107Y313720D01*
G01X191565Y318130D02*
X191139Y318720D01*
G01X191565Y323130D02*
X191139Y323720D01*
G01X191565Y328130D02*
X191139Y328720D01*
G01X197725Y289114D02*
X197588Y289312D01*
X197450Y289509D01*
X197311Y289705D01*
G01X197725Y294114D02*
X197588Y294312D01*
X197450Y294509D01*
X197311Y294705D01*
G01X197725Y299114D02*
X197588Y299312D01*
X197450Y299509D01*
X197311Y299705D01*
G01X197725Y304114D02*
X197588Y304312D01*
X197450Y304509D01*
X197311Y304705D01*
G01X197725Y309114D02*
X197588Y309312D01*
X197450Y309509D01*
X197311Y309705D01*
G01X199693Y314114D02*
X199556Y314312D01*
X199419Y314509D01*
X199279Y314705D01*
G01X197725Y319114D02*
X197588Y319312D01*
X197450Y319509D01*
X197311Y319705D01*
G01X197725Y324114D02*
X197588Y324312D01*
X197450Y324509D01*
X197311Y324705D01*
G01X197725Y329114D02*
X197588Y329312D01*
X197450Y329509D01*
X197311Y329705D01*
G01X197341Y312165D02*
X197468Y312193D01*
X197557Y312266D01*
X197588Y312362D01*
G01X197341Y318465D02*
X197468Y318492D01*
X197557Y318565D01*
X197588Y318661D01*
G01X197341Y321614D02*
X197468Y321642D01*
X197557Y321715D01*
X197588Y321811D01*
G01X197341Y324764D02*
X197468Y324791D01*
X197557Y324864D01*
X197588Y324961D01*
G01X197341Y327913D02*
X197468Y327941D01*
X197557Y328014D01*
X197588Y328110D01*
G01X192255Y288130D02*
X191983Y288720D01*
G01X192255Y293130D02*
X191983Y293720D01*
G01X192255Y298130D02*
X191983Y298720D01*
G01X192255Y303130D02*
X191983Y303720D01*
G01X192255Y308130D02*
X191983Y308720D01*
G01X194224Y313130D02*
X193951Y313720D01*
G01X192255Y318130D02*
X191983Y318720D01*
G01X192255Y323130D02*
X191983Y323720D01*
G01X192255Y328130D02*
X191983Y328720D01*
G01X197588Y290709D02*
X197556Y290806D01*
X197468Y290878D01*
X197341Y290906D01*
G01X197588Y293858D02*
X197556Y293955D01*
X197468Y294027D01*
X197341Y294055D01*
G01X197588Y297008D02*
X197556Y297105D01*
X197468Y297177D01*
X197341Y297205D01*
G01X197588Y300157D02*
X197556Y300254D01*
X197468Y300326D01*
X197341Y300354D01*
G01X197588Y303307D02*
X197556Y303404D01*
X197468Y303476D01*
X197341Y303504D01*
G01X197588Y306457D02*
X197556Y306554D01*
X197468Y306626D01*
X197341Y306654D01*
G01X197588Y309606D02*
X197556Y309703D01*
X197468Y309775D01*
X197341Y309803D01*
G01X197588Y312756D02*
X197556Y312853D01*
X197468Y312925D01*
X197341Y312953D01*
G01X197588Y319055D02*
X197556Y319152D01*
X197468Y319224D01*
X197341Y319252D01*
G01X197588Y322205D02*
X197556Y322302D01*
X197468Y322374D01*
X197341Y322402D01*
G01X197588Y325354D02*
X197556Y325451D01*
X197468Y325523D01*
X197341Y325551D01*
G01X197588Y328504D02*
X197556Y328601D01*
X197468Y328673D01*
X197341Y328701D01*
G01X193107Y288720D02*
X193185Y288130D01*
G01X193107Y293720D02*
X193185Y293130D01*
G01X193107Y298720D02*
X193185Y298130D01*
G01X193107Y303720D02*
X193185Y303130D01*
G01X193107Y308720D02*
X193185Y308130D01*
G01X193107Y318720D02*
X193185Y318130D01*
G01Y323130D02*
X193107Y323720D01*
G01X195076Y313720D02*
X195154Y313130D01*
G01X193107Y328720D02*
X193185Y328130D01*
G01X192154Y287165D02*
X192156Y287127D01*
X192164Y287090D01*
X192177Y287056D01*
X192194Y287026D01*
X192215Y287002D01*
X192239Y286983D01*
X192265Y286972D01*
X192292Y286969D01*
G01X192154Y290315D02*
X192156Y290277D01*
X192164Y290240D01*
X192177Y290206D01*
X192194Y290176D01*
X192215Y290151D01*
X192239Y290133D01*
X192265Y290122D01*
X192292Y290118D01*
G01X192154Y293465D02*
X192156Y293426D01*
X192164Y293389D01*
X192177Y293356D01*
X192194Y293325D01*
X192215Y293301D01*
X192239Y293283D01*
X192265Y293272D01*
X192292Y293268D01*
G01X192154Y296614D02*
X192156Y296576D01*
X192164Y296539D01*
X192177Y296505D01*
X192194Y296475D01*
X192215Y296450D01*
X192239Y296432D01*
X192265Y296421D01*
X192292Y296417D01*
G01X192154Y299764D02*
X192156Y299726D01*
X192164Y299689D01*
X192177Y299655D01*
X192194Y299624D01*
X192215Y299600D01*
X192239Y299582D01*
X192265Y299571D01*
X192292Y299567D01*
G01X192154Y302913D02*
X192156Y302875D01*
X192164Y302838D01*
X192177Y302804D01*
X192194Y302774D01*
X192215Y302750D01*
X192239Y302731D01*
X192265Y302720D01*
X192292Y302717D01*
G01X192154Y306063D02*
X192156Y306025D01*
X192164Y305988D01*
X192177Y305954D01*
X192194Y305924D01*
X192215Y305899D01*
X192239Y305881D01*
X192265Y305870D01*
X192292Y305866D01*
G01X192154Y309213D02*
X192156Y309174D01*
X192164Y309137D01*
X192177Y309104D01*
X192194Y309073D01*
X192215Y309049D01*
X192239Y309031D01*
X192265Y309020D01*
X192292Y309016D01*
G01X192154Y312362D02*
X192156Y312324D01*
X192164Y312287D01*
X192177Y312253D01*
X192194Y312223D01*
X192215Y312198D01*
X192239Y312180D01*
X192265Y312169D01*
X192292Y312165D01*
G01X192154Y315512D02*
X192156Y315474D01*
X192164Y315437D01*
X192177Y315403D01*
X192194Y315372D01*
X192215Y315348D01*
X192239Y315330D01*
X192265Y315319D01*
X192292Y315315D01*
G01X192154Y318661D02*
X192156Y318623D01*
X192164Y318586D01*
X192177Y318552D01*
X192194Y318522D01*
X192215Y318498D01*
X192239Y318480D01*
X192265Y318469D01*
X192292Y318465D01*
G01X192154Y321811D02*
X192156Y321773D01*
X192164Y321736D01*
X192177Y321702D01*
X192194Y321672D01*
X192215Y321647D01*
X192239Y321629D01*
X192265Y321618D01*
X192292Y321614D01*
G01X192154Y324961D02*
X192156Y324922D01*
X192164Y324885D01*
X192177Y324852D01*
X192194Y324821D01*
X192215Y324797D01*
X192239Y324779D01*
X192265Y324768D01*
X192292Y324764D01*
G01X192154Y328110D02*
X192156Y328072D01*
X192164Y328035D01*
X192177Y328001D01*
X192194Y327971D01*
X192215Y327946D01*
X192239Y327928D01*
X192265Y327917D01*
X192292Y327913D01*
G01X190976Y328504D02*
Y328110D01*
G01Y325354D02*
Y324961D01*
G01Y322205D02*
Y321811D01*
G01Y315906D02*
Y315512D01*
G01Y319055D02*
Y318661D01*
G01Y312756D02*
Y312362D01*
G01Y306457D02*
Y306063D01*
G01Y309606D02*
Y309213D01*
G01Y303307D02*
Y302913D01*
G01Y297008D02*
Y296614D01*
G01Y300157D02*
Y299764D01*
G01Y293858D02*
Y293465D01*
G01Y290709D02*
Y290315D01*
G01Y287559D02*
Y287165D01*
G01X191139Y288720D02*
Y289114D01*
G01Y293720D02*
Y294114D01*
G01Y298720D02*
Y299114D01*
G01Y303720D02*
Y304114D01*
G01Y308720D02*
Y309114D01*
G01Y318720D02*
Y319114D01*
G01Y323720D02*
Y324114D01*
G01Y328720D02*
Y329114D01*
G01X191983Y288720D02*
Y289114D01*
G01Y293720D02*
Y294114D01*
G01Y298720D02*
Y299114D01*
G01Y303720D02*
Y304114D01*
G01Y308720D02*
Y309114D01*
G01Y318720D02*
Y319114D01*
G01Y323720D02*
Y324114D01*
G01Y328720D02*
Y329114D01*
G01X192154Y328504D02*
Y328110D01*
G01Y325354D02*
Y324961D01*
G01Y322205D02*
Y321811D01*
G01Y315906D02*
Y315512D01*
G01Y319055D02*
Y318661D01*
G01Y312756D02*
Y312362D01*
G01Y306457D02*
Y306063D01*
G01Y309606D02*
Y309213D01*
G01Y303307D02*
Y302913D01*
G01Y297008D02*
Y296614D01*
G01Y300157D02*
Y299764D01*
G01Y293858D02*
Y293465D01*
G01Y290709D02*
Y290315D01*
G01Y287559D02*
Y287165D01*
G01X192667Y290315D02*
Y290709D01*
G01Y287165D02*
Y287559D01*
G01Y293465D02*
Y293858D01*
G01Y296614D02*
Y297008D01*
G01Y299764D02*
Y300157D01*
G01Y302913D02*
Y303307D01*
G01Y306063D02*
Y306457D01*
G01Y309213D02*
Y309606D01*
G01Y312362D02*
Y312756D01*
G01Y315512D02*
Y315906D01*
G01Y318661D02*
Y319055D01*
G01Y321811D02*
Y322205D01*
G01Y328110D02*
Y328504D01*
G01Y324961D02*
Y325354D01*
G01X193107Y329114D02*
Y328720D01*
G01Y319114D02*
Y318720D01*
G01Y309114D02*
Y308720D01*
G01Y304114D02*
Y303720D01*
G01Y299114D02*
Y298720D01*
G01Y294114D02*
Y293720D01*
G01Y289114D02*
Y288720D01*
G01Y323720D02*
Y324114D01*
G01Y313720D02*
Y314114D01*
G01X193951Y313720D02*
Y314114D01*
G01X195076D02*
Y313720D01*
G01X197588Y290315D02*
Y290709D01*
G01Y287165D02*
Y287559D01*
G01Y293465D02*
Y293858D01*
G01Y296614D02*
Y297008D01*
G01Y299764D02*
Y300157D01*
G01Y302913D02*
Y303307D01*
G01Y306063D02*
Y306457D01*
G01Y309213D02*
Y309606D01*
G01Y312362D02*
Y312756D01*
G01Y315512D02*
Y315906D01*
G01Y318661D02*
Y319055D01*
G01Y321811D02*
Y322205D01*
G01Y328110D02*
Y328504D01*
G01Y324961D02*
Y325354D01*
G01X197725Y329114D02*
Y328720D01*
G01Y324114D02*
Y323720D01*
G01Y319114D02*
Y318720D01*
G01Y309114D02*
Y308720D01*
G01Y304114D02*
Y303720D01*
G01Y299114D02*
Y298720D01*
G01Y294114D02*
Y293720D01*
G01Y289114D02*
Y288720D01*
G01X199693Y314114D02*
Y313720D01*
G01X203543Y337657D02*
Y344823D01*
G01X192667Y328504D02*
X192677Y328602D01*
X192705Y328674D01*
X192743Y328701D01*
G01X192667Y325354D02*
X192677Y325453D01*
X192705Y325525D01*
X192743Y325551D01*
G01X192667Y322205D02*
X192677Y322303D01*
X192705Y322375D01*
X192743Y322402D01*
G01X192667Y319055D02*
X192677Y319154D01*
X192705Y319226D01*
X192743Y319252D01*
G01X192667Y315906D02*
X192677Y316004D01*
X192705Y316076D01*
X192743Y316102D01*
G01X192667Y312756D02*
X192677Y312854D01*
X192705Y312926D01*
X192743Y312953D01*
G01X192667Y309606D02*
X192677Y309705D01*
X192705Y309777D01*
X192743Y309803D01*
G01X192667Y306457D02*
X192677Y306555D01*
X192705Y306627D01*
X192743Y306654D01*
G01X192667Y303307D02*
X192677Y303406D01*
X192705Y303478D01*
X192743Y303504D01*
G01X192667Y300157D02*
X192677Y300256D01*
X192705Y300328D01*
X192743Y300354D01*
G01X192667Y297008D02*
X192677Y297106D01*
X192705Y297178D01*
X192743Y297205D01*
G01X192667Y293858D02*
X192677Y293957D01*
X192705Y294029D01*
X192743Y294055D01*
G01X192667Y290709D02*
X192677Y290807D01*
X192705Y290879D01*
X192743Y290906D01*
G01X192667Y287559D02*
X192677Y287657D01*
X192705Y287730D01*
X192743Y287756D01*
G01X193107Y329114D02*
X193185Y329705D01*
G01Y324705D02*
X193107Y324114D01*
G01Y319114D02*
X193185Y319705D01*
G01X193107Y309114D02*
X193185Y309705D01*
G01X193107Y304114D02*
X193185Y304705D01*
G01X195076Y314114D02*
X195154Y314705D01*
G01X193107Y299114D02*
X193185Y299705D01*
G01X193107Y294114D02*
X193185Y294705D01*
G01X193107Y289114D02*
X193185Y289705D01*
G01X197588Y315512D02*
X197555Y315413D01*
X197467Y315342D01*
X197341Y315315D01*
G01X197588Y287165D02*
X197555Y287066D01*
X197467Y286995D01*
X197341Y286969D01*
G01X191983Y329114D02*
X192255Y329705D01*
G01X191983Y324114D02*
X192255Y324705D01*
G01X191983Y319114D02*
X192255Y319705D01*
G01X193951Y314114D02*
X194224Y314705D01*
G01X191983Y309114D02*
X192255Y309705D01*
G01X191983Y304114D02*
X192255Y304705D01*
G01X191983Y299114D02*
X192255Y299705D01*
G01X191983Y294114D02*
X192255Y294705D01*
G01X191983Y289114D02*
X192255Y289705D01*
G01X197311Y328130D02*
X197450Y328326D01*
X197588Y328523D01*
X197725Y328720D01*
G01X197311Y323130D02*
X197450Y323326D01*
X197588Y323523D01*
X197725Y323720D01*
G01X197311Y318130D02*
X197450Y318326D01*
X197588Y318523D01*
X197725Y318720D01*
G01X199279Y313130D02*
X199419Y313326D01*
X199556Y313523D01*
X199693Y313720D01*
G01X197311Y308130D02*
X197450Y308326D01*
X197588Y308523D01*
X197725Y308720D01*
G01X197311Y303130D02*
X197450Y303326D01*
X197588Y303523D01*
X197725Y303720D01*
G01X197311Y298130D02*
X197450Y298326D01*
X197588Y298523D01*
X197725Y298720D01*
G01X197311Y293130D02*
X197450Y293326D01*
X197588Y293523D01*
X197725Y293720D01*
G01X197311Y288130D02*
X197450Y288326D01*
X197588Y288523D01*
X197725Y288720D01*
G01X191565Y329705D02*
X191139Y329114D01*
G01X191565Y324705D02*
X191139Y324114D01*
G01X191565Y319705D02*
X191139Y319114D01*
G01X193534Y314705D02*
X193107Y314114D01*
G01X191565Y309705D02*
X191139Y309114D01*
G01X191565Y304705D02*
X191139Y304114D01*
G01X191565Y299705D02*
X191139Y299114D01*
G01X191565Y294705D02*
X191139Y294114D01*
G01X191565Y289705D02*
X191139Y289114D01*
G01X199606Y332736D02*
X201575Y334705D01*
G01X204858Y337657D02*
X208268Y339626D01*
G01X192743Y268071D02*
X192705Y268097D01*
X192677Y268169D01*
X192667Y268268D01*
G01X192743Y271220D02*
X192705Y271247D01*
X192677Y271319D01*
X192667Y271417D01*
G01X192743Y274370D02*
X192705Y274396D01*
X192677Y274469D01*
X192667Y274567D01*
G01X192743Y277520D02*
X192705Y277546D01*
X192677Y277618D01*
X192667Y277717D01*
G01X192743Y280669D02*
X192705Y280696D01*
X192677Y280768D01*
X192667Y280866D01*
G01X192743Y283819D02*
X192705Y283845D01*
X192677Y283917D01*
X192667Y284016D01*
G01X197341Y268071D02*
X191256D01*
G01X197311Y268130D02*
X191565D01*
G01X197588Y268268D02*
X190976D01*
G01Y268661D02*
X197588D01*
G01X191139Y268720D02*
X197725D01*
G01X197341Y268858D02*
X191256D01*
G01X191139Y269114D02*
X197725D01*
G01X197311Y269705D02*
X191565D01*
G01X197341Y271220D02*
X191256D01*
G01X197588Y271417D02*
X190976D01*
G01Y271811D02*
X197588D01*
G01X197341Y272008D02*
X191256D01*
G01X199279Y273130D02*
X193534D01*
G01X193107Y273720D02*
X199693D01*
G01X193107Y274114D02*
X199693D01*
G01X197341Y274370D02*
X191256D01*
G01X197588Y274567D02*
X190976D01*
G01X199279Y274705D02*
X193534D01*
G01X190976Y274961D02*
X197588D01*
G01X197341Y275157D02*
X191256D01*
G01X197341Y277520D02*
X191256D01*
G01X197588Y277717D02*
X190976D01*
G01Y278110D02*
X197588D01*
G01X197311Y278130D02*
X191565D01*
G01X197341Y278307D02*
X191256D01*
G01X191139Y278720D02*
X197725D01*
G01X191139Y279114D02*
X197725D01*
G01X197311Y279705D02*
X191565D01*
G01X197341Y280669D02*
X191256D01*
G01X197588Y280866D02*
X190976D01*
G01Y281260D02*
X197588D01*
G01X197341Y281457D02*
X191256D01*
G01X197311Y283130D02*
X191565D01*
G01X191139Y283720D02*
X197725D01*
G01X197341Y283819D02*
X191256D01*
G01X197588Y284016D02*
X190976D01*
G01X191139Y284114D02*
X197725D01*
G01X190976Y284409D02*
X197588D01*
G01X197341Y284606D02*
X191256D01*
G01X197311Y284705D02*
X191565D01*
G01Y268130D02*
X191139Y268720D01*
G01X193534Y273130D02*
X193107Y273720D01*
G01X197341Y268071D02*
X197468Y268098D01*
X197557Y268171D01*
X197588Y268268D01*
G01X197341Y271220D02*
X197468Y271248D01*
X197557Y271321D01*
X197588Y271417D01*
G01X197341Y274370D02*
X197468Y274398D01*
X197557Y274470D01*
X197588Y274567D01*
G01X197341Y277520D02*
X197468Y277547D01*
X197557Y277620D01*
X197588Y277717D01*
G01X197341Y280669D02*
X197468Y280697D01*
X197557Y280770D01*
X197588Y280866D01*
G01X197341Y283819D02*
X197468Y283846D01*
X197557Y283919D01*
X197588Y284016D01*
G01X192292Y268858D02*
X192265Y268854D01*
X192239Y268843D01*
X192215Y268825D01*
X192194Y268800D01*
X192177Y268771D01*
X192164Y268737D01*
X192156Y268700D01*
X192154Y268661D01*
G01X192292Y272008D02*
X192265Y272004D01*
X192239Y271993D01*
X192215Y271975D01*
X192194Y271950D01*
X192177Y271920D01*
X192164Y271887D01*
X192156Y271850D01*
X192154Y271811D01*
G01X192292Y275157D02*
X192265Y275154D01*
X192239Y275143D01*
X192215Y275124D01*
X192194Y275100D01*
X192177Y275070D01*
X192164Y275036D01*
X192156Y275000D01*
X192154Y274961D01*
G01X192292Y278307D02*
X192265Y278303D01*
X192239Y278292D01*
X192215Y278274D01*
X192194Y278249D01*
X192177Y278220D01*
X192164Y278186D01*
X192156Y278149D01*
X192154Y278110D01*
G01X192292Y281457D02*
X192265Y281453D01*
X192239Y281442D01*
X192215Y281424D01*
X192194Y281399D01*
X192177Y281369D01*
X192164Y281335D01*
X192156Y281299D01*
X192154Y281260D01*
G01X192292Y284606D02*
X192265Y284602D01*
X192239Y284591D01*
X192215Y284573D01*
X192194Y284548D01*
X192177Y284519D01*
X192164Y284485D01*
X192156Y284448D01*
X192154Y284409D01*
G01X191565Y278130D02*
X191139Y278720D01*
G01X191565Y283130D02*
X191139Y283720D01*
G01X197725Y269114D02*
X197588Y269312D01*
X197450Y269509D01*
X197311Y269705D01*
G01X199693Y274114D02*
X199556Y274312D01*
X199419Y274509D01*
X199279Y274705D01*
G01X197725Y279114D02*
X197588Y279312D01*
X197450Y279509D01*
X197311Y279705D01*
G01X197725Y284114D02*
X197588Y284312D01*
X197450Y284509D01*
X197311Y284705D01*
G01X192255Y268130D02*
X191983Y268720D01*
G01X194224Y273130D02*
X193951Y273720D01*
G01X192255Y278130D02*
X191983Y278720D01*
G01X192255Y283130D02*
X191983Y283720D01*
G01X197588Y268661D02*
X197556Y268758D01*
X197468Y268830D01*
X197341Y268858D01*
G01X197588Y271811D02*
X197556Y271908D01*
X197468Y271980D01*
X197341Y272008D01*
G01X197588Y274961D02*
X197556Y275057D01*
X197468Y275130D01*
X197341Y275157D01*
G01X197588Y278110D02*
X197556Y278207D01*
X197468Y278279D01*
X197341Y278307D01*
G01X197588Y281260D02*
X197556Y281357D01*
X197468Y281429D01*
X197341Y281457D01*
G01X197588Y284409D02*
X197556Y284506D01*
X197468Y284578D01*
X197341Y284606D01*
G01X193107Y268720D02*
X193185Y268130D01*
G01X193107Y278720D02*
X193185Y278130D01*
G01X193107Y283720D02*
X193185Y283130D01*
G01X195076Y273720D02*
X195154Y273130D01*
G01X192154Y268268D02*
X192156Y268230D01*
X192164Y268193D01*
X192177Y268159D01*
X192194Y268128D01*
X192215Y268104D01*
X192239Y268086D01*
X192265Y268075D01*
X192292Y268071D01*
G01X192154Y271417D02*
X192156Y271379D01*
X192164Y271342D01*
X192177Y271308D01*
X192194Y271278D01*
X192215Y271254D01*
X192239Y271235D01*
X192265Y271224D01*
X192292Y271220D01*
G01X192154Y274567D02*
X192156Y274529D01*
X192164Y274492D01*
X192177Y274458D01*
X192194Y274428D01*
X192215Y274403D01*
X192239Y274385D01*
X192265Y274374D01*
X192292Y274370D01*
G01X192154Y277717D02*
X192156Y277678D01*
X192164Y277641D01*
X192177Y277607D01*
X192194Y277577D01*
X192215Y277553D01*
X192239Y277535D01*
X192265Y277524D01*
X192292Y277520D01*
G01X192154Y280866D02*
X192156Y280828D01*
X192164Y280791D01*
X192177Y280757D01*
X192194Y280727D01*
X192215Y280702D01*
X192239Y280684D01*
X192265Y280673D01*
X192292Y280669D01*
G01X192154Y284016D02*
X192156Y283978D01*
X192164Y283941D01*
X192177Y283907D01*
X192194Y283876D01*
X192215Y283852D01*
X192239Y283834D01*
X192265Y283823D01*
X192292Y283819D01*
G01X190976Y284409D02*
Y284016D01*
G01Y281260D02*
Y280866D01*
G01Y278110D02*
Y277717D01*
G01Y274961D02*
Y274567D01*
G01Y271811D02*
Y271417D01*
G01Y268661D02*
Y268268D01*
G01X191139Y268720D02*
Y269114D01*
G01Y278720D02*
Y279114D01*
G01Y283720D02*
Y284114D01*
G01X191983Y268720D02*
Y269114D01*
G01Y278720D02*
Y279114D01*
G01Y283720D02*
Y284114D01*
G01X192154Y284409D02*
Y284016D01*
G01Y281260D02*
Y280866D01*
G01Y278110D02*
Y277717D01*
G01Y274961D02*
Y274567D01*
G01Y271811D02*
Y271417D01*
G01Y268661D02*
Y268268D01*
G01X192667Y271417D02*
Y271811D01*
G01Y268268D02*
Y268661D01*
G01Y274567D02*
Y274961D01*
G01Y280866D02*
Y281260D01*
G01Y277717D02*
Y278110D01*
G01Y284016D02*
Y284409D01*
G01X193107Y284114D02*
Y283720D01*
G01Y279114D02*
Y278720D01*
G01Y269114D02*
Y268720D01*
G01Y273720D02*
Y274114D01*
G01X193951Y273720D02*
Y274114D01*
G01X195076D02*
Y273720D01*
G01X197588Y271417D02*
Y271811D01*
G01Y268268D02*
Y268661D01*
G01Y274567D02*
Y274961D01*
G01Y280866D02*
Y281260D01*
G01Y277717D02*
Y278110D01*
G01Y284016D02*
Y284409D01*
G01X197725Y284114D02*
Y283720D01*
G01Y279114D02*
Y278720D01*
G01Y269114D02*
Y268720D01*
G01X199693Y274114D02*
Y273720D01*
G01X192667Y284409D02*
X192677Y284508D01*
X192705Y284580D01*
X192743Y284606D01*
G01X192667Y281260D02*
X192677Y281358D01*
X192705Y281430D01*
X192743Y281457D01*
G01X192667Y278110D02*
X192677Y278209D01*
X192705Y278281D01*
X192743Y278307D01*
G01X192667Y274961D02*
X192677Y275059D01*
X192705Y275131D01*
X192743Y275157D01*
G01X192667Y271811D02*
X192677Y271909D01*
X192705Y271981D01*
X192743Y272008D01*
G01X192667Y268661D02*
X192677Y268760D01*
X192705Y268832D01*
X192743Y268858D01*
G01X193107Y284114D02*
X193185Y284705D01*
G01X193107Y279114D02*
X193185Y279705D01*
G01X193107Y269114D02*
X193185Y269705D01*
G01X195076Y274114D02*
X195154Y274705D01*
G01X191983Y284114D02*
X192255Y284705D01*
G01X191983Y279114D02*
X192255Y279705D01*
G01X193951Y274114D02*
X194224Y274705D01*
G01X191983Y269114D02*
X192255Y269705D01*
G01X197311Y283130D02*
X197450Y283326D01*
X197588Y283523D01*
X197725Y283720D01*
G01X197311Y278130D02*
X197450Y278326D01*
X197588Y278523D01*
X197725Y278720D01*
G01X191565Y284705D02*
X191139Y284114D01*
G01X191565Y279705D02*
X191139Y279114D01*
G01X199279Y273130D02*
X199419Y273326D01*
X199556Y273523D01*
X199693Y273720D01*
G01X197311Y268130D02*
X197450Y268326D01*
X197588Y268523D01*
X197725Y268720D01*
G01X193534Y274705D02*
X193107Y274114D01*
G01X191565Y269705D02*
X191139Y269114D01*
G01X203575Y345973D02*
X203632Y345833D01*
X203637Y345593D01*
G01X203601Y345272D02*
X203637Y345596D01*
X203631Y345837D01*
X203575Y345973D01*
G01X203547Y344896D02*
X208268Y340255D01*
G01Y341358D02*
X203543Y346004D01*
G01X208268Y339626D02*
Y341358D01*
G01X203601Y345274D02*
X203547Y344896D01*
G01X186516Y553346D02*
Y533268D01*
G01X204858Y600689D02*
X208268Y598720D01*
G01X192743Y610591D02*
X192705Y610617D01*
X192677Y610689D01*
X192667Y610787D01*
G01X192743Y613740D02*
X192705Y613767D01*
X192677Y613839D01*
X192667Y613937D01*
G01X192743Y616890D02*
X192705Y616916D01*
X192677Y616988D01*
X192667Y617087D01*
G01X192743Y620039D02*
X192705Y620066D01*
X192677Y620138D01*
X192667Y620236D01*
G01X192743Y623189D02*
X192705Y623215D01*
X192677Y623287D01*
X192667Y623386D01*
G01X201575Y603642D02*
X199606Y605610D01*
G01X191565Y608642D02*
X191139Y609232D01*
G01X191565Y613642D02*
X191139Y614232D01*
G01X191565Y618642D02*
X191139Y619232D01*
G01X191565Y623642D02*
X191139Y624232D01*
G01X197725Y609626D02*
X197588Y609824D01*
X197450Y610020D01*
X197311Y610217D01*
G01X197725Y614626D02*
X197588Y614824D01*
X197450Y615020D01*
X197311Y615217D01*
G01X197725Y619626D02*
X197588Y619824D01*
X197450Y620020D01*
X197311Y620217D01*
G01X197725Y624626D02*
X197588Y624824D01*
X197450Y625020D01*
X197311Y625217D01*
G01X192255Y608642D02*
X191983Y609232D01*
G01X204858Y600689D02*
X201575D01*
G01X197311Y608642D02*
X191565D01*
G01X191139Y609232D02*
X197725D01*
G01X191139Y609626D02*
X197725D01*
G01X197311Y610217D02*
X191565D01*
G01X197341Y610591D02*
X191256D01*
G01X197588Y610787D02*
X190976D01*
G01Y611181D02*
X197588D01*
G01X197341Y611378D02*
X191256D01*
G01X197311Y613642D02*
X191565D01*
G01X197341Y613740D02*
X191256D01*
G01X197588Y613937D02*
X190976D01*
G01X191139Y614232D02*
X197725D01*
G01X190976Y614331D02*
X197588D01*
G01X197341Y614528D02*
X191256D01*
G01X191139Y614626D02*
X197725D01*
G01X197311Y615217D02*
X191565D01*
G01X197341Y616890D02*
X191256D01*
G01X197588Y617087D02*
X190976D01*
G01Y617480D02*
X197588D01*
G01X197341Y617677D02*
X191256D01*
G01X197311Y618642D02*
X191565D01*
G01X191139Y619232D02*
X197725D01*
G01X191139Y619626D02*
X197725D01*
G01X197341Y620039D02*
X191256D01*
G01X197311Y620217D02*
X191565D01*
G01X197588Y620236D02*
X190976D01*
G01Y620630D02*
X197588D01*
G01X197341Y620827D02*
X191256D01*
G01X197341Y623189D02*
X191256D01*
G01X192255Y613642D02*
X191983Y614232D01*
G01X192255Y618642D02*
X191983Y619232D01*
G01X192255Y623642D02*
X191983Y624232D01*
G01X197588Y611181D02*
X197556Y611278D01*
X197468Y611350D01*
X197341Y611378D01*
G01X197588Y614331D02*
X197556Y614428D01*
X197468Y614500D01*
X197341Y614528D01*
G01X197588Y617480D02*
X197556Y617577D01*
X197468Y617649D01*
X197341Y617677D01*
G01X197588Y620630D02*
X197556Y620727D01*
X197468Y620799D01*
X197341Y620827D01*
G01X197588Y623780D02*
X197556Y623876D01*
X197468Y623948D01*
X197341Y623976D01*
G01X192154Y610787D02*
X192156Y610749D01*
X192164Y610712D01*
X192177Y610678D01*
X192194Y610648D01*
X192215Y610624D01*
X192239Y610606D01*
X192265Y610594D01*
X192292Y610591D01*
G01X192154Y613937D02*
X192156Y613899D01*
X192164Y613862D01*
X192177Y613828D01*
X192194Y613798D01*
X192215Y613773D01*
X192239Y613755D01*
X192265Y613744D01*
X192292Y613740D01*
G01X192154Y617087D02*
X192156Y617048D01*
X192164Y617011D01*
X192177Y616978D01*
X192194Y616947D01*
X192215Y616923D01*
X192239Y616905D01*
X192265Y616894D01*
X192292Y616890D01*
G01X192154Y620236D02*
X192156Y620198D01*
X192164Y620161D01*
X192177Y620127D01*
X192194Y620097D01*
X192215Y620072D01*
X192239Y620054D01*
X192265Y620043D01*
X192292Y620039D01*
G01X192154Y623386D02*
X192156Y623348D01*
X192164Y623311D01*
X192177Y623277D01*
X192194Y623246D01*
X192215Y623222D01*
X192239Y623204D01*
X192265Y623193D01*
X192292Y623189D01*
G01X190976Y623780D02*
Y623386D01*
G01Y620630D02*
Y620236D01*
G01Y617480D02*
Y617087D01*
G01Y614331D02*
Y613937D01*
G01Y611181D02*
Y610787D01*
G01X191139Y609232D02*
Y609626D01*
G01Y614232D02*
Y614626D01*
G01Y619232D02*
Y619626D01*
G01Y624232D02*
Y624626D01*
G01X191983Y609232D02*
Y609626D01*
G01Y614232D02*
Y614626D01*
G01Y619232D02*
Y619626D01*
G01Y624232D02*
Y624626D01*
G01X192154Y623780D02*
Y623386D01*
G01Y620630D02*
Y620236D01*
G01Y617480D02*
Y617087D01*
G01Y614331D02*
Y613937D01*
G01Y611181D02*
Y610787D01*
G01X192667D02*
Y611181D01*
G01Y617087D02*
Y617480D01*
G01Y613937D02*
Y614331D01*
G01Y620236D02*
Y620630D01*
G01Y623386D02*
Y623780D01*
G01X193107Y624626D02*
Y624232D01*
G01Y619626D02*
Y619232D01*
G01Y614626D02*
Y614232D01*
G01Y609626D02*
Y609232D01*
G01X197588Y610787D02*
Y611181D01*
G01Y617087D02*
Y617480D01*
G01Y613937D02*
Y614331D01*
G01Y620236D02*
Y620630D01*
G01Y623386D02*
Y623780D01*
G01X197725Y624626D02*
Y624232D01*
G01Y619626D02*
Y619232D01*
G01Y614626D02*
Y614232D01*
G01Y609626D02*
Y609232D01*
G01X199606Y605610D02*
Y738248D01*
G01X200394Y635827D02*
Y604823D01*
G01X200453Y738642D02*
Y605217D01*
G01X201575Y600689D02*
Y743169D01*
G01X203543Y593524D02*
Y600689D01*
G01X208268Y598720D02*
Y596988D01*
G01X197341Y610591D02*
X197468Y610618D01*
X197557Y610691D01*
X197588Y610787D01*
G01X197341Y613740D02*
X197468Y613768D01*
X197557Y613841D01*
X197588Y613937D01*
G01X197341Y616890D02*
X197468Y616917D01*
X197557Y616990D01*
X197588Y617087D01*
G01X197341Y620039D02*
X197468Y620067D01*
X197557Y620140D01*
X197588Y620236D01*
G01X197341Y623189D02*
X197468Y623217D01*
X197557Y623289D01*
X197588Y623386D01*
G01X192292Y611378D02*
X192265Y611374D01*
X192239Y611363D01*
X192215Y611345D01*
X192194Y611320D01*
X192177Y611291D01*
X192164Y611257D01*
X192156Y611220D01*
X192154Y611181D01*
G01X192292Y614528D02*
X192265Y614524D01*
X192239Y614513D01*
X192215Y614494D01*
X192194Y614470D01*
X192177Y614440D01*
X192164Y614406D01*
X192156Y614370D01*
X192154Y614331D01*
G01X192292Y617677D02*
X192265Y617673D01*
X192239Y617662D01*
X192215Y617644D01*
X192194Y617619D01*
X192177Y617590D01*
X192164Y617556D01*
X192156Y617519D01*
X192154Y617480D01*
G01X192292Y620827D02*
X192265Y620823D01*
X192239Y620812D01*
X192215Y620794D01*
X192194Y620769D01*
X192177Y620739D01*
X192164Y620706D01*
X192156Y620669D01*
X192154Y620630D01*
G01X192292Y623976D02*
X192265Y623972D01*
X192239Y623961D01*
X192215Y623943D01*
X192194Y623919D01*
X192177Y623889D01*
X192164Y623855D01*
X192156Y623819D01*
X192154Y623780D01*
G01X197588Y623386D02*
X190976D01*
G01X197311Y623642D02*
X191565D01*
G01X190976Y623780D02*
X197588D01*
G01X197341Y623976D02*
X191256D01*
G01X191139Y624232D02*
X197725D01*
G01X191139Y624626D02*
X197725D01*
G01X197311Y625217D02*
X191565D01*
G01X203602Y593065D02*
X203547Y593450D01*
G01X193107Y609232D02*
X193185Y608642D01*
G01X193107Y614232D02*
X193185Y613642D01*
G01X193107Y619232D02*
X193185Y618642D01*
G01X193107Y624232D02*
X193185Y623642D01*
G01X192667Y617480D02*
X192677Y617579D01*
X192705Y617651D01*
X192743Y617677D01*
G01X192667Y614331D02*
X192677Y614429D01*
X192705Y614501D01*
X192743Y614528D01*
G01X193107Y624626D02*
X193185Y625217D01*
G01X193107Y619626D02*
X193185Y620217D01*
G01X193107Y614626D02*
X193185Y615217D01*
G01X193107Y609626D02*
X193185Y610217D01*
G01X203575Y592374D02*
X203632Y592513D01*
X203637Y592754D01*
G01X203575Y592374D02*
X203631Y592508D01*
X203638Y592744D01*
X203601Y593072D01*
G01X191983Y624626D02*
X192255Y625217D01*
G01X191983Y619626D02*
X192255Y620217D01*
G01X191983Y614626D02*
X192255Y615217D01*
G01X191983Y609626D02*
X192255Y610217D01*
G01X197311Y623642D02*
X197450Y623838D01*
X197588Y624035D01*
X197725Y624232D01*
G01X197311Y618642D02*
X197450Y618838D01*
X197588Y619035D01*
X197725Y619232D01*
G01X197311Y613642D02*
X197450Y613838D01*
X197588Y614035D01*
X197725Y614232D01*
G01X197311Y608642D02*
X197450Y608838D01*
X197588Y609035D01*
X197725Y609232D01*
G01X191565Y625217D02*
X191139Y624626D01*
G01X191565Y620217D02*
X191139Y619626D01*
G01X191565Y615217D02*
X191139Y614626D01*
G01X191565Y610217D02*
X191139Y609626D01*
G01X201575Y602657D02*
X199606Y600689D01*
G01X208268Y598091D02*
X203547Y593450D01*
G01X208268Y596988D02*
X203543Y592343D01*
G01X192743Y623976D02*
X192705Y623950D01*
X192677Y623878D01*
X192667Y623780D01*
G01X192743Y620827D02*
X192705Y620800D01*
X192677Y620728D01*
X192667Y620630D01*
G01X192743Y611378D02*
X192705Y611352D01*
X192677Y611279D01*
X192667Y611181D01*
G01X192743Y626339D02*
X192705Y626365D01*
X192677Y626437D01*
X192667Y626535D01*
G01X192743Y629488D02*
X192705Y629515D01*
X192677Y629587D01*
X192667Y629685D01*
G01X191565Y628642D02*
X191139Y629232D01*
G01X197725Y629626D02*
X197588Y629824D01*
X197450Y630020D01*
X197311Y630217D01*
G01X192255Y628642D02*
X191983Y629232D01*
G01X197588Y626929D02*
X197556Y627026D01*
X197468Y627098D01*
X197341Y627126D01*
G01X192154Y626535D02*
X192156Y626497D01*
X192164Y626460D01*
X192177Y626426D01*
X192194Y626396D01*
X192215Y626372D01*
X192239Y626354D01*
X192265Y626343D01*
X192292Y626339D01*
G01X192154Y629685D02*
X192156Y629647D01*
X192164Y629610D01*
X192177Y629576D01*
X192194Y629546D01*
X192215Y629521D01*
X192239Y629503D01*
X192265Y629492D01*
X192292Y629488D01*
G01X190976Y626929D02*
Y626535D01*
G01X191139Y629232D02*
Y629626D01*
G01X191983Y629232D02*
Y629626D01*
G01X192154Y626929D02*
Y626535D01*
G01X192667D02*
Y626929D01*
G01X193107Y629626D02*
Y629232D01*
G01X197588Y626535D02*
Y626929D01*
G01X197725Y629626D02*
Y629232D01*
G01X192292Y627126D02*
X192265Y627122D01*
X192239Y627111D01*
X192215Y627093D01*
X192194Y627068D01*
X192177Y627039D01*
X192164Y627005D01*
X192156Y626968D01*
X192154Y626929D01*
G01X197341Y626339D02*
X191256D01*
G01X197588Y626535D02*
X190976D01*
G01Y626929D02*
X197588D01*
G01X197341Y627126D02*
X191256D01*
G01X197311Y628642D02*
X191565D01*
G01X191139Y629232D02*
X197725D01*
G01X197341Y629488D02*
X191256D01*
G01X193107Y629232D02*
X193185Y628642D01*
G01X193107Y629626D02*
X193185Y630217D01*
G01X197341Y626339D02*
X197468Y626366D01*
X197557Y626439D01*
X197588Y626535D01*
G01X197341Y629488D02*
X197468Y629516D01*
X197557Y629589D01*
X197588Y629685D01*
G01X191983Y629626D02*
X192255Y630217D01*
G01X197311Y628642D02*
X197450Y628838D01*
X197588Y629035D01*
X197725Y629232D01*
G01X191565Y630217D02*
X191139Y629626D01*
G01X192743Y627126D02*
X192705Y627100D01*
X192677Y627027D01*
X192667Y626929D01*
G01X193407Y646518D02*
X193400Y646522D01*
X193394Y646533D01*
X193389Y646551D01*
X193383Y646576D01*
X193380Y646605D01*
X193376Y646639D01*
X193375Y646676D01*
X193374Y646715D01*
G01X193407Y649667D02*
X193400Y649671D01*
X193394Y649682D01*
X193389Y649700D01*
X193383Y649725D01*
X193380Y649755D01*
X193376Y649789D01*
X193375Y649825D01*
X193374Y649864D01*
G01X193407Y652817D02*
X193400Y652821D01*
X193394Y652832D01*
X193389Y652850D01*
X193383Y652875D01*
X193380Y652904D01*
X193376Y652938D01*
X193375Y652975D01*
X193374Y653014D01*
G01X193407Y655967D02*
X193400Y655970D01*
X193394Y655981D01*
X193389Y656000D01*
X193383Y656024D01*
X193380Y656054D01*
X193376Y656088D01*
X193375Y656124D01*
X193374Y656163D01*
G01X193407Y659116D02*
X193400Y659120D01*
X193394Y659131D01*
X193389Y659149D01*
X193383Y659174D01*
X193380Y659204D01*
X193376Y659237D01*
X193375Y659274D01*
X193374Y659313D01*
G01X192743Y648386D02*
X192705Y648412D01*
X192677Y648484D01*
X192667Y648583D01*
G01X192743Y651535D02*
X192705Y651562D01*
X192677Y651634D01*
X192667Y651732D01*
G01X192743Y654685D02*
X192705Y654711D01*
X192677Y654783D01*
X192667Y654882D01*
G01X192743Y657835D02*
X192705Y657861D01*
X192677Y657933D01*
X192667Y658031D01*
G01X192743Y660984D02*
X192705Y661011D01*
X192677Y661083D01*
X192667Y661181D01*
G01X192743Y664134D02*
X192705Y664160D01*
X192677Y664232D01*
X192667Y664331D01*
G01X192743Y667283D02*
X192705Y667310D01*
X192677Y667382D01*
X192667Y667480D01*
G01X191565Y668642D02*
X191139Y669232D01*
G01X191497Y663642D02*
X191074Y664232D01*
G01X192370Y646518D02*
X192341Y646522D01*
X192313Y646533D01*
X192288Y646551D01*
X192265Y646576D01*
X192247Y646605D01*
X192233Y646639D01*
X192225Y646676D01*
X192222Y646715D01*
G01X192370Y649667D02*
X192341Y649671D01*
X192313Y649682D01*
X192288Y649700D01*
X192265Y649725D01*
X192247Y649755D01*
X192233Y649789D01*
X192225Y649825D01*
X192222Y649864D01*
G01X192370Y652817D02*
X192341Y652821D01*
X192313Y652832D01*
X192288Y652850D01*
X192265Y652875D01*
X192247Y652904D01*
X192233Y652938D01*
X192225Y652975D01*
X192222Y653014D01*
G01X192370Y655967D02*
X192341Y655970D01*
X192313Y655981D01*
X192288Y656000D01*
X192265Y656024D01*
X192247Y656054D01*
X192233Y656088D01*
X192225Y656124D01*
X192222Y656163D01*
G01X192370Y659116D02*
X192341Y659120D01*
X192313Y659131D01*
X192288Y659149D01*
X192265Y659174D01*
X192247Y659204D01*
X192233Y659237D01*
X192225Y659274D01*
X192222Y659313D01*
G01X192743Y670433D02*
X192705Y670459D01*
X192677Y670531D01*
X192667Y670630D01*
G01X192743Y673583D02*
X192705Y673609D01*
X192677Y673681D01*
X192667Y673780D01*
G01X192743Y676732D02*
X192705Y676759D01*
X192677Y676831D01*
X192667Y676929D01*
G01X192743Y679882D02*
X192705Y679908D01*
X192677Y679980D01*
X192667Y680079D01*
G01X192743Y683031D02*
X192705Y683058D01*
X192677Y683130D01*
X192667Y683228D01*
G01X192743Y686181D02*
X192705Y686207D01*
X192677Y686280D01*
X192667Y686378D01*
G01X192743Y689331D02*
X192705Y689357D01*
X192677Y689429D01*
X192667Y689528D01*
G01X192743Y692480D02*
X192705Y692507D01*
X192677Y692579D01*
X192667Y692677D01*
G01X192743Y695630D02*
X192705Y695656D01*
X192677Y695728D01*
X192667Y695827D01*
G01X192743Y698780D02*
X192705Y698806D01*
X192677Y698878D01*
X192667Y698976D01*
G01X192743Y701929D02*
X192705Y701956D01*
X192677Y702028D01*
X192667Y702126D01*
G01X191565Y673642D02*
X191139Y674232D01*
G01X193534Y678642D02*
X193107Y679232D01*
G01X191565Y683642D02*
X191139Y684232D01*
G01X191565Y688642D02*
X191139Y689232D01*
G01X191565Y693642D02*
X191139Y694232D01*
G01X191565Y698642D02*
X191139Y699232D01*
G01X197725Y669626D02*
X197588Y669824D01*
X197450Y670020D01*
X197311Y670217D01*
G01X197725Y674626D02*
X197588Y674824D01*
X197450Y675020D01*
X197311Y675217D01*
G01X199693Y679626D02*
X199556Y679824D01*
X199419Y680020D01*
X199279Y680217D01*
G01X197725Y684626D02*
X197588Y684824D01*
X197450Y685020D01*
X197311Y685217D01*
G01X197725Y689626D02*
X197588Y689824D01*
X197450Y690020D01*
X197311Y690217D01*
G01X197725Y694626D02*
X197588Y694824D01*
X197450Y695020D01*
X197311Y695217D01*
G01X197725Y699626D02*
X197588Y699824D01*
X197450Y700020D01*
X197311Y700217D01*
G01X197816Y664626D02*
X197681Y664823D01*
X197546Y665020D01*
X197410Y665217D01*
G01X192255Y663642D02*
X191983Y664232D01*
G01X192255Y668642D02*
X191983Y669232D01*
G01X192255Y673642D02*
X191983Y674232D01*
G01X194224Y678642D02*
X193951Y679232D01*
G01X192255Y683642D02*
X191983Y684232D01*
G01X192255Y688642D02*
X191983Y689232D01*
G01X192255Y693642D02*
X191983Y694232D01*
G01X192255Y698642D02*
X191983Y699232D01*
G01X197598Y647699D02*
X197565Y647798D01*
X197476Y647869D01*
X197350Y647896D01*
G01X197598Y650848D02*
X197565Y650948D01*
X197476Y651019D01*
X197350Y651045D01*
G01X197598Y653998D02*
X197565Y654097D01*
X197476Y654168D01*
X197350Y654195D01*
G01X197598Y657148D02*
X197565Y657247D01*
X197476Y657318D01*
X197350Y657344D01*
G01X197598Y660297D02*
X197565Y660396D01*
X197476Y660467D01*
X197350Y660494D01*
G01X197588Y645827D02*
X197556Y645924D01*
X197468Y645996D01*
X197341Y646024D01*
G01X197588Y648976D02*
X197556Y649073D01*
X197468Y649145D01*
X197341Y649173D01*
G01X197588Y652126D02*
X197556Y652223D01*
X197468Y652295D01*
X197341Y652323D01*
G01X197588Y655276D02*
X197556Y655372D01*
X197468Y655444D01*
X197341Y655472D01*
G01X197588Y658425D02*
X197556Y658522D01*
X197468Y658594D01*
X197341Y658622D01*
G01X197588Y661575D02*
X197556Y661672D01*
X197468Y661744D01*
X197341Y661772D01*
G01X197588Y664724D02*
X197556Y664821D01*
X197468Y664893D01*
X197341Y664921D01*
G01X197588Y667874D02*
X197556Y667971D01*
X197468Y668043D01*
X197341Y668071D01*
G01X197588Y671024D02*
X197556Y671120D01*
X197468Y671193D01*
X197341Y671220D01*
G01X197588Y674173D02*
X197556Y674270D01*
X197468Y674342D01*
X197341Y674370D01*
G01X197588Y677323D02*
X197556Y677420D01*
X197468Y677492D01*
X197341Y677520D01*
G01X197588Y680472D02*
X197556Y680569D01*
X197468Y680641D01*
X197341Y680669D01*
G01X197588Y683622D02*
X197556Y683719D01*
X197468Y683791D01*
X197341Y683819D01*
G01X197588Y686772D02*
X197556Y686869D01*
X197468Y686941D01*
X197341Y686969D01*
G01X197588Y689921D02*
X197556Y690018D01*
X197468Y690090D01*
X197341Y690118D01*
G01X197588Y696220D02*
X197556Y696317D01*
X197468Y696389D01*
X197341Y696417D01*
G01X197588Y699370D02*
X197556Y699467D01*
X197468Y699539D01*
X197341Y699567D01*
G01X192154Y648583D02*
X192156Y648544D01*
X192164Y648507D01*
X192177Y648474D01*
X192194Y648443D01*
X192215Y648419D01*
X192239Y648401D01*
X192265Y648390D01*
X192292Y648386D01*
G01X192154Y651732D02*
X192156Y651694D01*
X192164Y651657D01*
X192177Y651623D01*
X192194Y651593D01*
X192215Y651569D01*
X192239Y651550D01*
X192265Y651539D01*
X192292Y651535D01*
G01X192154Y654882D02*
X192156Y654844D01*
X192164Y654807D01*
X192177Y654773D01*
X192194Y654743D01*
X192215Y654718D01*
X192239Y654700D01*
X192265Y654689D01*
X192292Y654685D01*
G01X192154Y658031D02*
X192156Y657993D01*
X192164Y657956D01*
X192177Y657922D01*
X192194Y657892D01*
X192215Y657868D01*
X192239Y657850D01*
X192265Y657839D01*
X192292Y657835D01*
G01X192154Y661181D02*
X192156Y661143D01*
X192164Y661106D01*
X192177Y661072D01*
X192194Y661042D01*
X192215Y661017D01*
X192239Y660999D01*
X192265Y660988D01*
X192292Y660984D01*
G01X192154Y664331D02*
X192156Y664293D01*
X192164Y664256D01*
X192177Y664222D01*
X192194Y664191D01*
X192215Y664167D01*
X192239Y664149D01*
X192265Y664138D01*
X192292Y664134D01*
G01X192154Y667480D02*
X192156Y667442D01*
X192164Y667405D01*
X192177Y667371D01*
X192194Y667341D01*
X192215Y667317D01*
X192239Y667298D01*
X192265Y667287D01*
X192292Y667283D01*
G01X192154Y670630D02*
X192156Y670592D01*
X192164Y670555D01*
X192177Y670521D01*
X192194Y670491D01*
X192215Y670466D01*
X192239Y670448D01*
X192265Y670437D01*
X192292Y670433D01*
G01X192154Y673780D02*
X192156Y673741D01*
X192164Y673704D01*
X192177Y673670D01*
X192194Y673640D01*
X192215Y673616D01*
X192239Y673598D01*
X192265Y673587D01*
X192292Y673583D01*
G01X192154Y676929D02*
X192156Y676891D01*
X192164Y676854D01*
X192177Y676820D01*
X192194Y676790D01*
X192215Y676765D01*
X192239Y676747D01*
X192265Y676736D01*
X192292Y676732D01*
G01X192154Y680079D02*
X192156Y680041D01*
X192164Y680004D01*
X192177Y679970D01*
X192194Y679939D01*
X192215Y679915D01*
X192239Y679897D01*
X192265Y679886D01*
X192292Y679882D01*
G01X192154Y683228D02*
X192156Y683190D01*
X192164Y683153D01*
X192177Y683119D01*
X192194Y683089D01*
X192215Y683065D01*
X192239Y683046D01*
X192265Y683035D01*
X192292Y683031D01*
G01X192154Y686378D02*
X192156Y686340D01*
X192164Y686303D01*
X192177Y686269D01*
X192194Y686239D01*
X192215Y686214D01*
X192239Y686196D01*
X192265Y686185D01*
X192292Y686181D01*
G01X192154Y689528D02*
X192156Y689489D01*
X192164Y689452D01*
X192177Y689419D01*
X192194Y689388D01*
X192215Y689364D01*
X192239Y689346D01*
X192265Y689335D01*
X192292Y689331D01*
G01X192154Y692677D02*
X192156Y692639D01*
X192164Y692602D01*
X192177Y692568D01*
X192194Y692538D01*
X192215Y692513D01*
X192239Y692495D01*
X192265Y692484D01*
X192292Y692480D01*
G01X192154Y695827D02*
X192156Y695789D01*
X192164Y695752D01*
X192177Y695718D01*
X192194Y695687D01*
X192215Y695663D01*
X192239Y695645D01*
X192265Y695634D01*
X192292Y695630D01*
G01X192154Y698976D02*
X192156Y698938D01*
X192164Y698901D01*
X192177Y698867D01*
X192194Y698837D01*
X192215Y698813D01*
X192239Y698794D01*
X192265Y698783D01*
X192292Y698780D01*
G01X192154Y702126D02*
X192156Y702088D01*
X192164Y702051D01*
X192177Y702017D01*
X192194Y701987D01*
X192215Y701962D01*
X192239Y701944D01*
X192265Y701933D01*
X192292Y701929D01*
G01X190976Y699370D02*
Y698976D01*
G01Y702520D02*
Y702126D01*
G01Y696220D02*
Y695827D01*
G01Y689921D02*
Y689528D01*
G01Y693071D02*
Y692677D01*
G01Y686772D02*
Y686378D01*
G01Y680472D02*
Y680079D01*
G01Y683622D02*
Y683228D01*
G01Y677323D02*
Y676929D01*
G01Y674173D02*
Y673780D01*
G01Y671024D02*
Y670630D01*
G01Y667874D02*
Y667480D01*
G01Y664724D02*
Y664331D01*
G01Y661575D02*
Y661181D01*
G01Y658425D02*
Y658031D01*
G01Y652126D02*
Y651732D01*
G01Y655276D02*
Y654882D01*
G01Y648976D02*
Y648583D01*
G01Y645827D02*
Y645433D01*
G01X191074Y664232D02*
Y664626D01*
G01X191139Y669232D02*
Y669626D01*
G01Y674232D02*
Y674626D01*
G01Y684232D02*
Y684626D01*
G01Y689232D02*
Y689626D01*
G01Y694232D02*
Y694626D01*
G01Y699232D02*
Y699626D01*
G01X191280Y646715D02*
Y647699D01*
G01Y649864D02*
Y650848D01*
G01Y653014D02*
Y653998D01*
G01Y659313D02*
Y660297D01*
G01Y656163D02*
Y657148D01*
G01X191983Y664232D02*
Y664626D01*
G01Y669232D02*
Y669626D01*
G01Y674232D02*
Y674626D01*
G01Y684232D02*
Y684626D01*
G01Y689232D02*
Y689626D01*
G01Y694232D02*
Y694626D01*
G01Y699232D02*
Y699626D01*
G01X192154Y699370D02*
Y698976D01*
G01Y702520D02*
Y702126D01*
G01Y696220D02*
Y695827D01*
G01Y689921D02*
Y689528D01*
G01Y693071D02*
Y692677D01*
G01Y686772D02*
Y686378D01*
G01Y680472D02*
Y680079D01*
G01Y683622D02*
Y683228D01*
G01Y677323D02*
Y676929D01*
G01Y674173D02*
Y673780D01*
G01Y671024D02*
Y670630D01*
G01Y667874D02*
Y667480D01*
G01Y664724D02*
Y664331D01*
G01Y661575D02*
Y661181D01*
G01Y658425D02*
Y658031D01*
G01Y652126D02*
Y651732D01*
G01Y655276D02*
Y654882D01*
G01Y648976D02*
Y648583D01*
G01Y645827D02*
Y645433D01*
G01X192222Y646715D02*
Y647699D01*
G01Y649864D02*
Y650848D01*
G01Y653014D02*
Y653998D01*
G01Y659313D02*
Y660297D01*
G01Y656163D02*
Y657148D01*
G01X192667Y645433D02*
Y645827D01*
G01Y648583D02*
Y648976D01*
G01Y651732D02*
Y652126D01*
G01Y654882D02*
Y655276D01*
G01Y658031D02*
Y658425D01*
G01Y664331D02*
Y664724D01*
G01Y661181D02*
Y661575D01*
G01Y667480D02*
Y667874D01*
G01Y673780D02*
Y674173D01*
G01Y670630D02*
Y671024D01*
G01Y676929D02*
Y677323D01*
G01Y680079D02*
Y680472D01*
G01Y683228D02*
Y683622D01*
G01Y686378D02*
Y686772D01*
G01Y689528D02*
Y689921D01*
G01Y692677D02*
Y693071D01*
G01Y695827D02*
Y696220D01*
G01Y698976D02*
Y699370D01*
G01Y702126D02*
Y702520D01*
G01X193107Y699626D02*
Y699232D01*
G01Y694626D02*
Y694232D01*
G01Y689626D02*
Y689232D01*
G01Y684626D02*
Y684232D01*
G01Y674626D02*
Y674232D01*
G01Y669626D02*
Y669232D01*
G01Y664626D02*
Y664232D01*
G01Y679232D02*
Y679626D01*
G01X193374Y646715D02*
Y647699D01*
G01Y649864D02*
Y650848D01*
G01Y653014D02*
Y653998D01*
G01Y659313D02*
Y660297D01*
G01Y656163D02*
Y657148D01*
G01X193951Y679232D02*
Y679626D01*
G01X195076D02*
Y679232D01*
G01X195106Y662854D02*
Y661673D01*
G01X197588Y645433D02*
Y645827D01*
G01Y648583D02*
Y648976D01*
G01Y651732D02*
Y652126D01*
G01Y654882D02*
Y655276D01*
G01Y658031D02*
Y658425D01*
G01Y664331D02*
Y664724D01*
G01Y661181D02*
Y661575D01*
G01Y667480D02*
Y667874D01*
G01Y673780D02*
Y674173D01*
G01Y670630D02*
Y671024D01*
G01Y676929D02*
Y677323D01*
G01Y680079D02*
Y680472D01*
G01Y683228D02*
Y683622D01*
G01Y686378D02*
Y686772D01*
G01Y689528D02*
Y689921D01*
G01Y692677D02*
Y693071D01*
G01Y695827D02*
Y696220D01*
G01Y698976D02*
Y699370D01*
G01Y702126D02*
Y702520D01*
G01X197598Y660297D02*
Y659313D01*
G01Y657148D02*
Y656163D01*
G01Y653998D02*
Y653014D01*
G01Y647699D02*
Y646715D01*
G01Y650848D02*
Y649864D01*
G01X197725Y699626D02*
Y699232D01*
G01Y694626D02*
Y694232D01*
G01Y689626D02*
Y689232D01*
G01Y684626D02*
Y684232D01*
G01Y674626D02*
Y674232D01*
G01Y669626D02*
Y669232D01*
G01X197816Y664626D02*
Y664232D01*
G01X199693Y679626D02*
Y679232D01*
G01X200394Y739035D02*
Y668130D01*
G01X200563D02*
Y662650D01*
G01X193374Y660297D02*
X193375Y660335D01*
X193376Y660372D01*
X193380Y660406D01*
X193383Y660437D01*
X193389Y660461D01*
X193394Y660479D01*
X193400Y660490D01*
X193407Y660494D01*
G01X193374Y657148D02*
X193375Y657186D01*
X193376Y657223D01*
X193380Y657257D01*
X193383Y657287D01*
X193389Y657311D01*
X193394Y657330D01*
X193400Y657341D01*
X193407Y657344D01*
G01X193374Y653998D02*
X193375Y654036D01*
X193376Y654073D01*
X193380Y654107D01*
X193383Y654137D01*
X193389Y654162D01*
X193394Y654180D01*
X193400Y654191D01*
X193407Y654195D01*
G01X193374Y650848D02*
X193375Y650887D01*
X193376Y650924D01*
X193380Y650957D01*
X193383Y650988D01*
X193389Y651012D01*
X193394Y651030D01*
X193400Y651041D01*
X193407Y651045D01*
G01X193374Y647699D02*
X193375Y647737D01*
X193376Y647774D01*
X193380Y647808D01*
X193383Y647838D01*
X193389Y647863D01*
X193394Y647881D01*
X193400Y647892D01*
X193407Y647896D01*
G01X192292Y646024D02*
X192265Y646020D01*
X192239Y646009D01*
X192215Y645991D01*
X192194Y645966D01*
X192177Y645936D01*
X192164Y645902D01*
X192156Y645866D01*
X192154Y645827D01*
G01X192292Y649173D02*
X192265Y649169D01*
X192239Y649158D01*
X192215Y649140D01*
X192194Y649115D01*
X192177Y649086D01*
X192164Y649052D01*
X192156Y649015D01*
X192154Y648976D01*
G01X192292Y652323D02*
X192265Y652319D01*
X192239Y652308D01*
X192215Y652290D01*
X192194Y652265D01*
X192177Y652235D01*
X192164Y652202D01*
X192156Y652165D01*
X192154Y652126D01*
G01X197588Y645433D02*
X190976D01*
G01Y645827D02*
X197588D01*
G01X197341Y646024D02*
X191256D01*
G01X191542Y646518D02*
X197350D01*
G01X191280Y646715D02*
X197598D01*
G01Y647699D02*
X191280D01*
G01X191542Y647896D02*
X197350D01*
G01X197341Y648386D02*
X191256D01*
G01X197588Y648583D02*
X190976D01*
G01Y648976D02*
X197588D01*
G01X197341Y649173D02*
X191256D01*
G01X191542Y649667D02*
X197350D01*
G01X191280Y649864D02*
X197598D01*
G01Y650848D02*
X191280D01*
G01X191542Y651045D02*
X197350D01*
G01X197341Y651535D02*
X191256D01*
G01X197588Y651732D02*
X190976D01*
G01Y652126D02*
X197588D01*
G01X197341Y652323D02*
X191256D01*
G01X191542Y652817D02*
X197350D01*
G01X191280Y653014D02*
X197598D01*
G01Y653998D02*
X191280D01*
G01X191542Y654195D02*
X197350D01*
G01X197341Y654685D02*
X191256D01*
G01X197588Y654882D02*
X190976D01*
G01Y655276D02*
X197588D01*
G01X197341Y655472D02*
X191256D01*
G01X191542Y655967D02*
X197350D01*
G01X191280Y656163D02*
X197598D01*
G01Y657148D02*
X191280D01*
G01X191542Y657344D02*
X197350D01*
G01X197341Y657835D02*
X191256D01*
G01X197588Y658031D02*
X190976D01*
G01Y658425D02*
X197588D01*
G01X197341Y658622D02*
X191256D01*
G01X191542Y659116D02*
X197350D01*
G01X191280Y659313D02*
X197598D01*
G01Y660297D02*
X191280D01*
G01X191542Y660494D02*
X197350D01*
G01X197341Y660984D02*
X191256D01*
G01X197588Y661181D02*
X190976D01*
G01Y661575D02*
X197588D01*
G01X197341Y661772D02*
X191256D01*
G01X195106Y662854D02*
X201575D01*
G01X197410Y663642D02*
X191497D01*
G01X197341Y664134D02*
X191256D01*
G01X191074Y664232D02*
X197816D01*
G01X197588Y664331D02*
X190976D01*
G01X191074Y664626D02*
X197816D01*
G01X190976Y664724D02*
X197588D01*
G01X197341Y664921D02*
X191256D01*
G01X197410Y665217D02*
X191497D01*
G01X197341Y667283D02*
X191256D01*
G01X197588Y667480D02*
X190976D01*
G01Y667874D02*
X197588D01*
G01X197341Y668071D02*
X191256D01*
G01X197311Y668642D02*
X191565D01*
G01X191139Y669232D02*
X197725D01*
G01X191139Y669626D02*
X197725D01*
G01X197311Y670217D02*
X191565D01*
G01X197341Y670433D02*
X191256D01*
G01X197588Y670630D02*
X190976D01*
G01Y671024D02*
X197588D01*
G01X197341Y671220D02*
X191256D01*
G01X197341Y673583D02*
X191256D01*
G01X197311Y673642D02*
X191565D01*
G01X197588Y673780D02*
X190976D01*
G01Y674173D02*
X197588D01*
G01X191139Y674232D02*
X197725D01*
G01X197341Y674370D02*
X191256D01*
G01X191139Y674626D02*
X197725D01*
G01X197311Y675217D02*
X191565D01*
G01X197341Y676732D02*
X191256D01*
G01X197588Y676929D02*
X190976D01*
G01Y677323D02*
X197588D01*
G01X197341Y677520D02*
X191256D01*
G01X199279Y678642D02*
X193534D01*
G01X193107Y679232D02*
X199693D01*
G01X193107Y679626D02*
X199693D01*
G01X197341Y679882D02*
X191256D01*
G01X197588Y680079D02*
X190976D01*
G01X199279Y680217D02*
X193534D01*
G01X190976Y680472D02*
X197588D01*
G01X197341Y680669D02*
X191256D01*
G01X197341Y683031D02*
X191256D01*
G01X197588Y683228D02*
X190976D01*
G01Y683622D02*
X197588D01*
G01X197311Y683642D02*
X191565D01*
G01X197341Y683819D02*
X191256D01*
G01X191139Y684232D02*
X197725D01*
G01X191139Y684626D02*
X197725D01*
G01X197311Y685217D02*
X191565D01*
G01X197341Y686181D02*
X191256D01*
G01X197588Y686378D02*
X190976D01*
G01Y686772D02*
X197588D01*
G01X197341Y686969D02*
X191256D01*
G01X197311Y688642D02*
X191565D01*
G01X191139Y689232D02*
X197725D01*
G01X197341Y689331D02*
X191256D01*
G01X197588Y689528D02*
X190976D01*
G01X191139Y689626D02*
X197725D01*
G01X190976Y689921D02*
X197588D01*
G01X197341Y690118D02*
X191256D01*
G01X197311Y690217D02*
X191565D01*
G01X197341Y692480D02*
X191256D01*
G01X197588Y692677D02*
X190976D01*
G01Y693071D02*
X197588D01*
G01X197341Y693268D02*
X191256D01*
G01X197311Y693642D02*
X191565D01*
G01X191139Y694232D02*
X197725D01*
G01X191139Y694626D02*
X197725D01*
G01X197311Y695217D02*
X191565D01*
G01X197341Y695630D02*
X191256D01*
G01X197588Y695827D02*
X190976D01*
G01Y696220D02*
X197588D01*
G01X197341Y696417D02*
X191256D01*
G01X197311Y698642D02*
X191565D01*
G01X197341Y698780D02*
X191256D01*
G01X197588Y698976D02*
X190976D01*
G01X191139Y699232D02*
X197725D01*
G01X190976Y699370D02*
X197588D01*
G01X197341Y699567D02*
X191256D01*
G01X191139Y699626D02*
X197725D01*
G01X197341Y693268D02*
X197467Y693240D01*
X197557Y693167D01*
X197588Y693071D01*
G01X193107Y664232D02*
X193185Y663642D01*
G01X193107Y669232D02*
X193185Y668642D01*
G01X193107Y674232D02*
X193185Y673642D01*
G01X193107Y684232D02*
X193185Y683642D01*
G01X193107Y689232D02*
X193185Y688642D01*
G01X195076Y679232D02*
X195154Y678642D01*
G01X193107Y694232D02*
X193185Y693642D01*
G01X193107Y699232D02*
X193185Y698642D01*
G01X192222Y660297D02*
X192225Y660335D01*
X192233Y660372D01*
X192247Y660406D01*
X192265Y660437D01*
X192288Y660461D01*
X192313Y660479D01*
X192341Y660490D01*
X192370Y660494D01*
G01X192222Y657148D02*
X192225Y657186D01*
X192233Y657223D01*
X192247Y657257D01*
X192265Y657287D01*
X192288Y657311D01*
X192313Y657330D01*
X192341Y657341D01*
X192370Y657344D01*
G01X192222Y653998D02*
X192225Y654036D01*
X192233Y654073D01*
X192247Y654107D01*
X192265Y654137D01*
X192288Y654162D01*
X192313Y654180D01*
X192341Y654191D01*
X192370Y654195D01*
G01X192222Y650848D02*
X192225Y650887D01*
X192233Y650924D01*
X192247Y650957D01*
X192265Y650988D01*
X192288Y651012D01*
X192313Y651030D01*
X192341Y651041D01*
X192370Y651045D01*
G01X192222Y647699D02*
X192225Y647737D01*
X192233Y647774D01*
X192247Y647808D01*
X192265Y647838D01*
X192288Y647863D01*
X192313Y647881D01*
X192341Y647892D01*
X192370Y647896D01*
G01X192667Y699370D02*
X192677Y699469D01*
X192705Y699541D01*
X192743Y699567D01*
G01X192667Y696220D02*
X192677Y696319D01*
X192705Y696391D01*
X192743Y696417D01*
G01X192667Y693071D02*
X192677Y693169D01*
X192705Y693241D01*
X192743Y693268D01*
G01X192667Y689921D02*
X192677Y690020D01*
X192705Y690092D01*
X192743Y690118D01*
G01X192667Y686772D02*
X192677Y686870D01*
X192705Y686942D01*
X192743Y686969D01*
G01X192667Y683622D02*
X192677Y683720D01*
X192705Y683793D01*
X192743Y683819D01*
G01X192667Y680472D02*
X192677Y680571D01*
X192705Y680643D01*
X192743Y680669D01*
G01X192667Y677323D02*
X192677Y677421D01*
X192705Y677493D01*
X192743Y677520D01*
G01X192667Y674173D02*
X192677Y674272D01*
X192705Y674344D01*
X192743Y674370D01*
G01X192667Y671024D02*
X192677Y671122D01*
X192705Y671194D01*
X192743Y671220D01*
G01X192667Y667874D02*
X192677Y667972D01*
X192705Y668044D01*
X192743Y668071D01*
G01X192667Y664724D02*
X192677Y664823D01*
X192705Y664895D01*
X192743Y664921D01*
G01X192667Y661575D02*
X192677Y661673D01*
X192705Y661745D01*
X192743Y661772D01*
G01X192667Y658425D02*
X192677Y658524D01*
X192705Y658596D01*
X192743Y658622D01*
G01X192667Y652126D02*
X192677Y652224D01*
X192705Y652296D01*
X192743Y652323D01*
G01X192667Y648976D02*
X192677Y649075D01*
X192705Y649147D01*
X192743Y649173D01*
G01X192667Y645827D02*
X192677Y645925D01*
X192705Y645997D01*
X192743Y646024D01*
G01X193107Y699626D02*
X193185Y700217D01*
G01X193107Y694626D02*
X193185Y695217D01*
G01X193107Y689626D02*
X193185Y690217D01*
G01X193107Y684626D02*
X193185Y685217D01*
G01X193107Y674626D02*
X193185Y675217D01*
G01X193107Y669626D02*
X193185Y670217D01*
G01X195076Y679626D02*
X195154Y680217D01*
G01X193107Y664626D02*
X193185Y665217D01*
G01X197341Y648386D02*
X197468Y648413D01*
X197557Y648486D01*
X197588Y648583D01*
G01X197341Y651535D02*
X197468Y651563D01*
X197557Y651636D01*
X197588Y651732D01*
G01X197341Y654685D02*
X197468Y654713D01*
X197557Y654785D01*
X197588Y654882D01*
G01X197341Y657835D02*
X197468Y657862D01*
X197557Y657935D01*
X197588Y658031D01*
G01X197341Y660984D02*
X197468Y661012D01*
X197557Y661085D01*
X197588Y661181D01*
G01X197341Y664134D02*
X197468Y664161D01*
X197557Y664234D01*
X197588Y664331D01*
G01X197341Y667283D02*
X197468Y667311D01*
X197557Y667384D01*
X197588Y667480D01*
G01X197341Y670433D02*
X197468Y670461D01*
X197557Y670533D01*
X197588Y670630D01*
G01X197341Y673583D02*
X197468Y673610D01*
X197557Y673683D01*
X197588Y673780D01*
G01X197341Y676732D02*
X197468Y676760D01*
X197557Y676833D01*
X197588Y676929D01*
G01X197341Y679882D02*
X197468Y679909D01*
X197557Y679982D01*
X197588Y680079D01*
G01X197341Y683031D02*
X197468Y683059D01*
X197557Y683132D01*
X197588Y683228D01*
G01X197341Y686181D02*
X197468Y686209D01*
X197557Y686281D01*
X197588Y686378D01*
G01X197341Y689331D02*
X197468Y689358D01*
X197557Y689431D01*
X197588Y689528D01*
G01X197341Y695630D02*
X197468Y695657D01*
X197557Y695730D01*
X197588Y695827D01*
G01X197341Y698780D02*
X197468Y698807D01*
X197557Y698880D01*
X197588Y698976D01*
G01X197341Y701929D02*
X197468Y701957D01*
X197557Y702030D01*
X197588Y702126D01*
G01X197350Y646518D02*
X197477Y646545D01*
X197567Y646618D01*
X197598Y646715D01*
G01X197350Y649667D02*
X197477Y649695D01*
X197567Y649767D01*
X197598Y649864D01*
G01X197350Y652817D02*
X197477Y652844D01*
X197567Y652917D01*
X197598Y653014D01*
G01X197350Y655967D02*
X197477Y655994D01*
X197567Y656067D01*
X197598Y656163D01*
G01X197350Y659116D02*
X197477Y659144D01*
X197567Y659216D01*
X197598Y659313D01*
G01X192292Y655472D02*
X192265Y655469D01*
X192239Y655457D01*
X192215Y655439D01*
X192194Y655415D01*
X192177Y655385D01*
X192164Y655351D01*
X192156Y655315D01*
X192154Y655276D01*
G01X192292Y658622D02*
X192265Y658618D01*
X192239Y658607D01*
X192215Y658589D01*
X192194Y658564D01*
X192177Y658535D01*
X192164Y658501D01*
X192156Y658464D01*
X192154Y658425D01*
G01X192292Y661772D02*
X192265Y661768D01*
X192239Y661757D01*
X192215Y661739D01*
X192194Y661714D01*
X192177Y661684D01*
X192164Y661650D01*
X192156Y661614D01*
X192154Y661575D01*
G01X192292Y664921D02*
X192265Y664917D01*
X192239Y664906D01*
X192215Y664888D01*
X192194Y664863D01*
X192177Y664834D01*
X192164Y664800D01*
X192156Y664763D01*
X192154Y664724D01*
G01X192292Y668071D02*
X192265Y668067D01*
X192239Y668056D01*
X192215Y668038D01*
X192194Y668013D01*
X192177Y667983D01*
X192164Y667950D01*
X192156Y667913D01*
X192154Y667874D01*
G01X192292Y671220D02*
X192265Y671217D01*
X192239Y671206D01*
X192215Y671187D01*
X192194Y671163D01*
X192177Y671133D01*
X192164Y671099D01*
X192156Y671063D01*
X192154Y671024D01*
G01X192292Y674370D02*
X192265Y674366D01*
X192239Y674355D01*
X192215Y674337D01*
X192194Y674312D01*
X192177Y674283D01*
X192164Y674249D01*
X192156Y674212D01*
X192154Y674173D01*
G01X192292Y677520D02*
X192265Y677516D01*
X192239Y677505D01*
X192215Y677487D01*
X192194Y677462D01*
X192177Y677432D01*
X192164Y677398D01*
X192156Y677362D01*
X192154Y677323D01*
G01X192292Y680669D02*
X192265Y680665D01*
X192239Y680654D01*
X192215Y680636D01*
X192194Y680611D01*
X192177Y680582D01*
X192164Y680548D01*
X192156Y680511D01*
X192154Y680472D01*
G01X192292Y683819D02*
X192265Y683815D01*
X192239Y683804D01*
X192215Y683786D01*
X192194Y683761D01*
X192177Y683731D01*
X192164Y683698D01*
X192156Y683661D01*
X192154Y683622D01*
G01X192292Y686969D02*
X192265Y686965D01*
X192239Y686954D01*
X192215Y686935D01*
X192194Y686911D01*
X192177Y686881D01*
X192164Y686847D01*
X192156Y686811D01*
X192154Y686772D01*
G01X192292Y690118D02*
X192265Y690114D01*
X192239Y690103D01*
X192215Y690085D01*
X192194Y690060D01*
X192177Y690031D01*
X192164Y689997D01*
X192156Y689960D01*
X192154Y689921D01*
G01X192292Y693268D02*
X192265Y693264D01*
X192239Y693253D01*
X192215Y693235D01*
X192194Y693210D01*
X192177Y693180D01*
X192164Y693146D01*
X192156Y693110D01*
X192154Y693071D01*
G01X192292Y696417D02*
X192265Y696413D01*
X192239Y696402D01*
X192215Y696384D01*
X192194Y696359D01*
X192177Y696330D01*
X192164Y696296D01*
X192156Y696259D01*
X192154Y696220D01*
G01X192292Y699567D02*
X192265Y699563D01*
X192239Y699552D01*
X192215Y699534D01*
X192194Y699509D01*
X192177Y699480D01*
X192164Y699446D01*
X192156Y699409D01*
X192154Y699370D01*
G01X197311Y700217D02*
X191565D01*
G01X197341Y701929D02*
X191256D01*
G01X197588Y702126D02*
X190976D01*
G01X197588Y692677D02*
X197555Y692578D01*
X197467Y692507D01*
X197341Y692480D01*
G01X191983Y699626D02*
X192255Y700217D01*
G01X191983Y694626D02*
X192255Y695217D01*
G01X191983Y689626D02*
X192255Y690217D01*
G01X191983Y684626D02*
X192255Y685217D01*
G01X193951Y679626D02*
X194224Y680217D01*
G01X191983Y674626D02*
X192255Y675217D01*
G01X191983Y669626D02*
X192255Y670217D01*
G01X191983Y664626D02*
X192255Y665217D01*
G01X197410Y663642D02*
X197546Y663838D01*
X197681Y664035D01*
X197816Y664232D01*
G01X197311Y698642D02*
X197450Y698838D01*
X197588Y699035D01*
X197725Y699232D01*
G01X197311Y693642D02*
X197450Y693838D01*
X197588Y694035D01*
X197725Y694232D01*
G01X197311Y688642D02*
X197450Y688838D01*
X197588Y689035D01*
X197725Y689232D01*
G01X197311Y683642D02*
X197450Y683838D01*
X197588Y684035D01*
X197725Y684232D01*
G01X199279Y678642D02*
X199419Y678838D01*
X199556Y679035D01*
X199693Y679232D01*
G01X197311Y673642D02*
X197450Y673838D01*
X197588Y674035D01*
X197725Y674232D01*
G01X191565Y700217D02*
X191139Y699626D01*
G01X191565Y695217D02*
X191139Y694626D01*
G01X191565Y690217D02*
X191139Y689626D01*
G01X191565Y685217D02*
X191139Y684626D01*
G01X193534Y680217D02*
X193107Y679626D01*
G01X191565Y675217D02*
X191139Y674626D01*
G01X191565Y670217D02*
X191139Y669626D01*
G01X197311Y668642D02*
X197450Y668838D01*
X197588Y669035D01*
X197725Y669232D01*
G01X191497Y665217D02*
X191074Y664626D01*
G01X201575Y663661D02*
X199606Y661693D01*
G01X192743Y655472D02*
X192705Y655446D01*
X192677Y655374D01*
X192667Y655276D01*
G01X193407Y643368D02*
X193400Y643372D01*
X193394Y643383D01*
X193389Y643401D01*
X193383Y643426D01*
X193380Y643456D01*
X193376Y643489D01*
X193375Y643526D01*
X193374Y643565D01*
G01X192743Y632638D02*
X192705Y632664D01*
X192677Y632736D01*
X192667Y632835D01*
G01X192743Y635787D02*
X192705Y635814D01*
X192677Y635886D01*
X192667Y635984D01*
G01X192743Y638937D02*
X192705Y638963D01*
X192677Y639035D01*
X192667Y639134D01*
G01X192743Y642087D02*
X192705Y642113D01*
X192677Y642185D01*
X192667Y642283D01*
G01X192743Y645236D02*
X192705Y645263D01*
X192677Y645335D01*
X192667Y645433D01*
G01X199606Y642165D02*
X201575Y640197D01*
G01X191565Y633642D02*
X191139Y634232D01*
G01X191497Y638642D02*
X191074Y639232D01*
G01X197725Y634626D02*
X197588Y634824D01*
X197450Y635020D01*
X197311Y635217D01*
G01X197816Y639626D02*
X197681Y639823D01*
X197546Y640020D01*
X197410Y640217D01*
G01X192370Y643368D02*
X192341Y643372D01*
X192313Y643383D01*
X192288Y643401D01*
X192265Y643426D01*
X192247Y643456D01*
X192233Y643489D01*
X192225Y643526D01*
X192222Y643565D01*
G01X192255Y633642D02*
X191983Y634232D01*
G01X192255Y638642D02*
X191983Y639232D01*
G01X197598Y644549D02*
X197565Y644648D01*
X197476Y644719D01*
X197350Y644746D01*
G01X197588Y630079D02*
X197556Y630176D01*
X197468Y630248D01*
X197341Y630276D01*
G01X197588Y633228D02*
X197556Y633325D01*
X197468Y633397D01*
X197341Y633425D01*
G01X197588Y636378D02*
X197556Y636475D01*
X197468Y636547D01*
X197341Y636575D01*
G01X197588Y639528D02*
X197556Y639624D01*
X197468Y639696D01*
X197341Y639724D01*
G01X197588Y642677D02*
X197556Y642774D01*
X197468Y642846D01*
X197341Y642874D01*
G01X192154Y632835D02*
X192156Y632796D01*
X192164Y632759D01*
X192177Y632726D01*
X192194Y632695D01*
X192215Y632671D01*
X192239Y632653D01*
X192265Y632642D01*
X192292Y632638D01*
G01X192154Y635984D02*
X192156Y635946D01*
X192164Y635909D01*
X192177Y635875D01*
X192194Y635845D01*
X192215Y635820D01*
X192239Y635802D01*
X192265Y635791D01*
X192292Y635787D01*
G01X192154Y639134D02*
X192156Y639096D01*
X192164Y639059D01*
X192177Y639025D01*
X192194Y638994D01*
X192215Y638970D01*
X192239Y638952D01*
X192265Y638941D01*
X192292Y638937D01*
G01X192154Y642283D02*
X192156Y642245D01*
X192164Y642208D01*
X192177Y642174D01*
X192194Y642144D01*
X192215Y642120D01*
X192239Y642102D01*
X192265Y642091D01*
X192292Y642087D01*
G01X192154Y645433D02*
X192156Y645395D01*
X192164Y645358D01*
X192177Y645324D01*
X192194Y645294D01*
X192215Y645269D01*
X192239Y645251D01*
X192265Y645240D01*
X192292Y645236D01*
G01X190976Y642677D02*
Y642283D01*
G01Y639528D02*
Y639134D01*
G01Y636378D02*
Y635984D01*
G01Y633228D02*
Y632835D01*
G01Y630079D02*
Y629685D01*
G01X191074Y639232D02*
Y639626D01*
G01X191139Y634232D02*
Y634626D01*
G01X191280Y643565D02*
Y644549D01*
G01X191983Y634232D02*
Y634626D01*
G01Y639232D02*
Y639626D01*
G01X192154Y642677D02*
Y642283D01*
G01Y639528D02*
Y639134D01*
G01Y636378D02*
Y635984D01*
G01Y633228D02*
Y632835D01*
G01Y630079D02*
Y629685D01*
G01X192222Y643565D02*
Y644549D01*
G01X192667Y629685D02*
Y630079D01*
G01Y635984D02*
Y636378D01*
G01Y632835D02*
Y633228D01*
G01Y639134D02*
Y639528D01*
G01Y642283D02*
Y642677D01*
G01X193107Y639626D02*
Y639232D01*
G01Y634626D02*
Y634232D01*
G01X193374Y643565D02*
Y644549D01*
G01X195106Y642185D02*
Y641004D01*
G01X197588Y629685D02*
Y630079D01*
G01Y635984D02*
Y636378D01*
G01Y632835D02*
Y633228D01*
G01Y639134D02*
Y639528D01*
G01Y642283D02*
Y642677D01*
G01X197598Y644549D02*
Y643565D01*
G01X197725Y634626D02*
Y634232D01*
G01X197816Y639626D02*
Y639232D01*
G01X200394Y641004D02*
Y662854D01*
G01X200563Y641208D02*
Y635827D01*
G01X193374Y644549D02*
X193375Y644587D01*
X193376Y644624D01*
X193380Y644658D01*
X193383Y644689D01*
X193389Y644713D01*
X193394Y644731D01*
X193400Y644742D01*
X193407Y644746D01*
G01X192292Y630276D02*
X192265Y630272D01*
X192239Y630261D01*
X192215Y630243D01*
X192194Y630218D01*
X192177Y630188D01*
X192164Y630154D01*
X192156Y630118D01*
X192154Y630079D01*
G01X192292Y633425D02*
X192265Y633421D01*
X192239Y633410D01*
X192215Y633392D01*
X192194Y633367D01*
X192177Y633338D01*
X192164Y633304D01*
X192156Y633267D01*
X192154Y633228D01*
G01X192292Y636575D02*
X192265Y636571D01*
X192239Y636560D01*
X192215Y636542D01*
X192194Y636517D01*
X192177Y636487D01*
X192164Y636454D01*
X192156Y636417D01*
X192154Y636378D01*
G01X192292Y639724D02*
X192265Y639720D01*
X192239Y639709D01*
X192215Y639691D01*
X192194Y639667D01*
X192177Y639637D01*
X192164Y639603D01*
X192156Y639567D01*
X192154Y639528D01*
G01X192292Y642874D02*
X192265Y642870D01*
X192239Y642859D01*
X192215Y642841D01*
X192194Y642816D01*
X192177Y642787D01*
X192164Y642753D01*
X192156Y642716D01*
X192154Y642677D01*
G01X191139Y629626D02*
X197725D01*
G01X197588Y629685D02*
X190976D01*
G01Y630079D02*
X197588D01*
G01X197311Y630217D02*
X191565D01*
G01X197341Y630276D02*
X191256D01*
G01X197341Y632638D02*
X191256D01*
G01X197588Y632835D02*
X190976D01*
G01Y633228D02*
X197588D01*
G01X197341Y633425D02*
X191256D01*
G01X197311Y633642D02*
X191565D01*
G01X191139Y634232D02*
X197725D01*
G01X191139Y634626D02*
X197725D01*
G01X197311Y635217D02*
X191565D01*
G01X197341Y635787D02*
X191256D01*
G01X197588Y635984D02*
X190976D01*
G01Y636378D02*
X197588D01*
G01X197341Y636575D02*
X191256D01*
G01X197410Y638642D02*
X191497D01*
G01X197341Y638937D02*
X191256D01*
G01X197588Y639134D02*
X190976D01*
G01X191074Y639232D02*
X197816D01*
G01X190976Y639528D02*
X197588D01*
G01X191074Y639626D02*
X197816D01*
G01X197341Y639724D02*
X191256D01*
G01X197410Y640217D02*
X191497D01*
G01X201575Y641004D02*
X195106D01*
G01X197341Y642087D02*
X191256D01*
G01X197588Y642283D02*
X190976D01*
G01Y642677D02*
X197588D01*
G01X197341Y642874D02*
X191256D01*
G01X191542Y643368D02*
X197350D01*
G01X191280Y643565D02*
X197598D01*
G01Y644549D02*
X191280D01*
G01X191542Y644746D02*
X197350D01*
G01X197341Y645236D02*
X191256D01*
G01X193107Y634232D02*
X193185Y633642D01*
G01X193107Y639232D02*
X193185Y638642D01*
G01X192222Y644549D02*
X192225Y644587D01*
X192233Y644624D01*
X192247Y644658D01*
X192265Y644689D01*
X192288Y644713D01*
X192313Y644731D01*
X192341Y644742D01*
X192370Y644746D01*
G01X192667Y642677D02*
X192677Y642776D01*
X192705Y642848D01*
X192743Y642874D01*
G01X192667Y633228D02*
X192677Y633327D01*
X192705Y633399D01*
X192743Y633425D01*
G01X192667Y630079D02*
X192677Y630177D01*
X192705Y630249D01*
X192743Y630276D01*
G01X193107Y639626D02*
X193185Y640217D01*
G01X193107Y634626D02*
X193185Y635217D01*
G01X197341Y632638D02*
X197468Y632665D01*
X197557Y632738D01*
X197588Y632835D01*
G01X197341Y635787D02*
X197468Y635815D01*
X197557Y635888D01*
X197588Y635984D01*
G01X197341Y638937D02*
X197468Y638965D01*
X197557Y639037D01*
X197588Y639134D01*
G01X197341Y642087D02*
X197468Y642114D01*
X197557Y642187D01*
X197588Y642283D01*
G01X197341Y645236D02*
X197468Y645264D01*
X197557Y645337D01*
X197588Y645433D01*
G01X197350Y643368D02*
X197477Y643396D01*
X197567Y643468D01*
X197598Y643565D01*
G01X191983Y639626D02*
X192255Y640217D01*
G01X191983Y634626D02*
X192255Y635217D01*
G01X197410Y638642D02*
X197546Y638838D01*
X197681Y639035D01*
X197816Y639232D01*
G01X197311Y633642D02*
X197450Y633838D01*
X197588Y634035D01*
X197725Y634232D01*
G01X191497Y640217D02*
X191074Y639626D01*
G01X191565Y635217D02*
X191139Y634626D01*
G01X192743Y639724D02*
X192705Y639698D01*
X192677Y639626D01*
X192667Y639528D01*
G01X192743Y636575D02*
X192705Y636548D01*
X192677Y636476D01*
X192667Y636378D01*
G01X192743Y708228D02*
X192705Y708255D01*
X192677Y708327D01*
X192667Y708425D01*
G01X192743Y711378D02*
X192705Y711404D01*
X192677Y711476D01*
X192667Y711575D01*
G01X192743Y714528D02*
X192705Y714554D01*
X192677Y714626D01*
X192667Y714724D01*
G01X192743Y717677D02*
X192705Y717704D01*
X192677Y717776D01*
X192667Y717874D01*
G01X192743Y720827D02*
X192705Y720853D01*
X192677Y720925D01*
X192667Y721024D01*
G01X192743Y723976D02*
X192705Y724003D01*
X192677Y724075D01*
X192667Y724173D01*
G01X192743Y727126D02*
X192705Y727152D01*
X192677Y727224D01*
X192667Y727323D01*
G01X192743Y730276D02*
X192705Y730302D01*
X192677Y730374D01*
X192667Y730472D01*
G01X192743Y733425D02*
X192705Y733452D01*
X192677Y733524D01*
X192667Y733622D01*
G01X199606Y743169D02*
X201575Y741201D01*
G01X191565Y708642D02*
X191139Y709232D01*
G01X191565Y713642D02*
X191139Y714232D01*
G01X193534Y718642D02*
X193107Y719232D01*
G01X191565Y723642D02*
X191139Y724232D01*
G01X191565Y728642D02*
X191139Y729232D01*
G01X191565Y733642D02*
X191139Y734232D01*
G01X197725Y709626D02*
X197588Y709824D01*
X197450Y710020D01*
X197311Y710217D01*
G01X197725Y714626D02*
X197588Y714824D01*
X197450Y715020D01*
X197311Y715217D01*
G01X199693Y719626D02*
X199556Y719824D01*
X199419Y720020D01*
X199279Y720217D01*
G01X197725Y724626D02*
X197588Y724824D01*
X197450Y725020D01*
X197311Y725217D01*
G01X197725Y729626D02*
X197588Y729824D01*
X197450Y730020D01*
X197311Y730217D01*
G01X197725Y734626D02*
X197588Y734824D01*
X197450Y735020D01*
X197311Y735217D01*
G01X192255Y708642D02*
X191983Y709232D01*
G01X192255Y713642D02*
X191983Y714232D01*
G01X194224Y718642D02*
X193951Y719232D01*
G01X192255Y723642D02*
X191983Y724232D01*
G01X192255Y728642D02*
X191983Y729232D01*
G01X192255Y733642D02*
X191983Y734232D01*
G01X197588Y705669D02*
X197556Y705766D01*
X197468Y705838D01*
X197341Y705866D01*
G01X197588Y708819D02*
X197556Y708916D01*
X197468Y708988D01*
X197341Y709016D01*
G01X197588Y711969D02*
X197556Y712065D01*
X197468Y712137D01*
X197341Y712165D01*
G01X197588Y715118D02*
X197556Y715215D01*
X197468Y715287D01*
X197341Y715315D01*
G01X197588Y718268D02*
X197556Y718365D01*
X197468Y718437D01*
X197341Y718465D01*
G01X197588Y724567D02*
X197556Y724664D01*
X197468Y724736D01*
X197341Y724764D01*
G01X197588Y727717D02*
X197556Y727813D01*
X197468Y727885D01*
X197341Y727913D01*
G01X197588Y730866D02*
X197556Y730963D01*
X197468Y731035D01*
X197341Y731063D01*
G01X197588Y734016D02*
X197556Y734113D01*
X197468Y734185D01*
X197341Y734213D01*
G01X192154Y708425D02*
X192156Y708387D01*
X192164Y708350D01*
X192177Y708316D01*
X192194Y708286D01*
X192215Y708261D01*
X192239Y708243D01*
X192265Y708232D01*
X192292Y708228D01*
G01X192154Y711575D02*
X192156Y711537D01*
X192164Y711500D01*
X192177Y711466D01*
X192194Y711435D01*
X192215Y711411D01*
X192239Y711393D01*
X192265Y711382D01*
X192292Y711378D01*
G01X192154Y714724D02*
X192156Y714686D01*
X192164Y714649D01*
X192177Y714615D01*
X192194Y714585D01*
X192215Y714561D01*
X192239Y714543D01*
X192265Y714531D01*
X192292Y714528D01*
G01X192154Y717874D02*
X192156Y717836D01*
X192164Y717799D01*
X192177Y717765D01*
X192194Y717735D01*
X192215Y717710D01*
X192239Y717692D01*
X192265Y717681D01*
X192292Y717677D01*
G01X192154Y721024D02*
X192156Y720985D01*
X192164Y720948D01*
X192177Y720915D01*
X192194Y720884D01*
X192215Y720860D01*
X192239Y720842D01*
X192265Y720831D01*
X192292Y720827D01*
G01X192154Y724173D02*
X192156Y724135D01*
X192164Y724098D01*
X192177Y724064D01*
X192194Y724034D01*
X192215Y724009D01*
X192239Y723991D01*
X192265Y723980D01*
X192292Y723976D01*
G01X192154Y727323D02*
X192156Y727285D01*
X192164Y727248D01*
X192177Y727214D01*
X192194Y727183D01*
X192215Y727159D01*
X192239Y727141D01*
X192265Y727130D01*
X192292Y727126D01*
G01X192154Y730472D02*
X192156Y730434D01*
X192164Y730397D01*
X192177Y730363D01*
X192194Y730333D01*
X192215Y730309D01*
X192239Y730291D01*
X192265Y730280D01*
X192292Y730276D01*
G01X192154Y733622D02*
X192156Y733584D01*
X192164Y733547D01*
X192177Y733513D01*
X192194Y733483D01*
X192215Y733458D01*
X192239Y733440D01*
X192265Y733429D01*
X192292Y733425D01*
G01X190976Y734016D02*
Y733622D01*
G01Y727717D02*
Y727323D01*
G01Y730866D02*
Y730472D01*
G01Y724567D02*
Y724173D01*
G01Y721417D02*
Y721024D01*
G01Y718268D02*
Y717874D01*
G01Y715118D02*
Y714724D01*
G01Y708819D02*
Y708425D01*
G01Y711969D02*
Y711575D01*
G01Y705669D02*
Y705276D01*
G01X191139Y709232D02*
Y709626D01*
G01Y714232D02*
Y714626D01*
G01Y724232D02*
Y724626D01*
G01Y729232D02*
Y729626D01*
G01Y734232D02*
Y734626D01*
G01X191983Y709232D02*
Y709626D01*
G01Y714232D02*
Y714626D01*
G01Y724232D02*
Y724626D01*
G01Y729232D02*
Y729626D01*
G01Y734232D02*
Y734626D01*
G01X192154Y734016D02*
Y733622D01*
G01Y727717D02*
Y727323D01*
G01Y730866D02*
Y730472D01*
G01Y724567D02*
Y724173D01*
G01Y721417D02*
Y721024D01*
G01Y718268D02*
Y717874D01*
G01Y715118D02*
Y714724D01*
G01Y708819D02*
Y708425D01*
G01Y711969D02*
Y711575D01*
G01Y705669D02*
Y705276D01*
G01X192667D02*
Y705669D01*
G01Y708425D02*
Y708819D01*
G01Y711575D02*
Y711969D01*
G01Y714724D02*
Y715118D01*
G01Y721024D02*
Y721417D01*
G01Y717874D02*
Y718268D01*
G01Y724173D02*
Y724567D01*
G01Y727323D02*
Y727717D01*
G01Y730472D02*
Y730866D01*
G01Y733622D02*
Y734016D01*
G01X193107Y734626D02*
Y734232D01*
G01Y724626D02*
Y724232D01*
G01Y714626D02*
Y714232D01*
G01Y709626D02*
Y709232D01*
G01Y729232D02*
Y729626D01*
G01Y719232D02*
Y719626D01*
G01X193951Y719232D02*
Y719626D01*
G01X195076D02*
Y719232D01*
G01X197588Y705276D02*
Y705669D01*
G01Y708425D02*
Y708819D01*
G01Y711575D02*
Y711969D01*
G01Y714724D02*
Y715118D01*
G01Y721024D02*
Y721417D01*
G01Y717874D02*
Y718268D01*
G01Y724173D02*
Y724567D01*
G01Y727323D02*
Y727717D01*
G01Y730472D02*
Y730866D01*
G01Y733622D02*
Y734016D01*
G01X197725Y734626D02*
Y734232D01*
G01Y729626D02*
Y729232D01*
G01Y724626D02*
Y724232D01*
G01Y714626D02*
Y714232D01*
G01Y709626D02*
Y709232D01*
G01X199693Y719626D02*
Y719232D01*
G01X203543Y743169D02*
Y750335D01*
G01X208268Y745138D02*
Y746870D01*
G01X197341Y721614D02*
X197467Y721587D01*
X197557Y721514D01*
X197588Y721417D01*
G01X193107Y709232D02*
X193185Y708642D01*
G01X193107Y714232D02*
X193185Y713642D01*
G01X193107Y724232D02*
X193185Y723642D01*
G01Y728642D02*
X193107Y729232D01*
G01X195076Y719232D02*
X195154Y718642D01*
G01X193107Y734232D02*
X193185Y733642D01*
G01X192667Y734016D02*
X192677Y734114D01*
X192705Y734186D01*
X192743Y734213D01*
G01X192667Y730866D02*
X192677Y730965D01*
X192705Y731037D01*
X192743Y731063D01*
G01X192667Y727717D02*
X192677Y727815D01*
X192705Y727887D01*
X192743Y727913D01*
G01X192667Y724567D02*
X192677Y724665D01*
X192705Y724737D01*
X192743Y724764D01*
G01X192667Y721417D02*
X192677Y721516D01*
X192705Y721588D01*
X192743Y721614D01*
G01X192667Y718268D02*
X192677Y718366D01*
X192705Y718438D01*
X192743Y718465D01*
G01X192667Y715118D02*
X192677Y715217D01*
X192705Y715289D01*
X192743Y715315D01*
G01X192667Y711969D02*
X192677Y712067D01*
X192705Y712139D01*
X192743Y712165D01*
G01X192667Y708819D02*
X192677Y708917D01*
X192705Y708989D01*
X192743Y709016D01*
G01X192667Y705669D02*
X192677Y705768D01*
X192705Y705840D01*
X192743Y705866D01*
G01X193107Y734626D02*
X193185Y735217D01*
G01Y730217D02*
X193107Y729626D01*
G01Y724626D02*
X193185Y725217D01*
G01X193107Y714626D02*
X193185Y715217D01*
G01X193107Y709626D02*
X193185Y710217D01*
G01X195076Y719626D02*
X195154Y720217D01*
G01X192292Y705866D02*
X192265Y705862D01*
X192239Y705851D01*
X192215Y705833D01*
X192194Y705808D01*
X192177Y705779D01*
X192164Y705745D01*
X192156Y705708D01*
X192154Y705669D01*
G01X192292Y709016D02*
X192265Y709012D01*
X192239Y709001D01*
X192215Y708983D01*
X192194Y708958D01*
X192177Y708928D01*
X192164Y708894D01*
X192156Y708858D01*
X192154Y708819D01*
G01X192292Y712165D02*
X192265Y712161D01*
X192239Y712150D01*
X192215Y712132D01*
X192194Y712107D01*
X192177Y712078D01*
X192164Y712044D01*
X192156Y712007D01*
X192154Y711969D01*
G01X192292Y715315D02*
X192265Y715311D01*
X192239Y715300D01*
X192215Y715282D01*
X192194Y715257D01*
X192177Y715228D01*
X192164Y715194D01*
X192156Y715157D01*
X192154Y715118D01*
G01X192292Y718465D02*
X192265Y718461D01*
X192239Y718450D01*
X192215Y718431D01*
X192194Y718407D01*
X192177Y718377D01*
X192164Y718343D01*
X192156Y718307D01*
X192154Y718268D01*
G01X192292Y721614D02*
X192265Y721610D01*
X192239Y721599D01*
X192215Y721581D01*
X192194Y721556D01*
X192177Y721527D01*
X192164Y721493D01*
X192156Y721456D01*
X192154Y721417D01*
G01X192292Y724764D02*
X192265Y724760D01*
X192239Y724749D01*
X192215Y724731D01*
X192194Y724706D01*
X192177Y724676D01*
X192164Y724643D01*
X192156Y724606D01*
X192154Y724567D01*
G01X192292Y727913D02*
X192265Y727909D01*
X192239Y727898D01*
X192215Y727880D01*
X192194Y727856D01*
X192177Y727826D01*
X192164Y727792D01*
X192156Y727756D01*
X192154Y727717D01*
G01X197588Y705276D02*
X190976D01*
G01Y705669D02*
X197588D01*
G01X197341Y705866D02*
X191256D01*
G01X197341Y708228D02*
X191256D01*
G01X197588Y708425D02*
X190976D01*
G01X197311Y708642D02*
X191565D01*
G01X190976Y708819D02*
X197588D01*
G01X197341Y709016D02*
X191256D01*
G01X191139Y709232D02*
X197725D01*
G01X191139Y709626D02*
X197725D01*
G01X197311Y710217D02*
X191565D01*
G01X197341Y711378D02*
X191256D01*
G01X197588Y711575D02*
X190976D01*
G01Y711969D02*
X197588D01*
G01X197341Y712165D02*
X191256D01*
G01X197311Y713642D02*
X191565D01*
G01X191139Y714232D02*
X197725D01*
G01X197341Y714528D02*
X191256D01*
G01X191139Y714626D02*
X197725D01*
G01X197588Y714724D02*
X190976D01*
G01Y715118D02*
X197588D01*
G01X197311Y715217D02*
X191565D01*
G01X197341Y715315D02*
X191256D01*
G01X197341Y717677D02*
X191256D01*
G01X197588Y717874D02*
X190976D01*
G01Y718268D02*
X197588D01*
G01X197341Y718465D02*
X191256D01*
G01X199279Y718642D02*
X193534D01*
G01X193107Y719232D02*
X199693D01*
G01X193107Y719626D02*
X199693D01*
G01X199279Y720217D02*
X193534D01*
G01X197341Y720827D02*
X191256D01*
G01X197588Y721024D02*
X190976D01*
G01Y721417D02*
X197588D01*
G01X197341Y721614D02*
X191256D01*
G01X197311Y723642D02*
X191565D01*
G01X197341Y723976D02*
X191256D01*
G01X197588Y724173D02*
X190976D01*
G01X191139Y724232D02*
X197725D01*
G01X190976Y724567D02*
X197588D01*
G01X191139Y724626D02*
X197725D01*
G01X197341Y724764D02*
X191256D01*
G01X197311Y725217D02*
X191565D01*
G01X197341Y727126D02*
X191256D01*
G01X197588Y727323D02*
X190976D01*
G01Y727717D02*
X197588D01*
G01X197341Y727913D02*
X191256D01*
G01X197311Y728642D02*
X191565D01*
G01X191139Y729232D02*
X197725D01*
G01X191139Y729626D02*
X197725D01*
G01X197311Y730217D02*
X191565D01*
G01X197341Y730276D02*
X191256D01*
G01X197588Y730472D02*
X190976D01*
G01Y730866D02*
X197588D01*
G01X197341Y731063D02*
X191256D01*
G01X197341Y733425D02*
X191256D01*
G01X197588Y733622D02*
X190976D01*
G01X197311Y733642D02*
X191565D01*
G01X190976Y734016D02*
X197588D01*
G01X197341Y734213D02*
X191256D01*
G01X191139Y734232D02*
X197725D01*
G01X191139Y734626D02*
X197725D01*
G01X197311Y735217D02*
X191565D01*
G01X204858Y743169D02*
X201575D01*
G01X197588Y721024D02*
X197555Y720924D01*
X197467Y720854D01*
X197341Y720827D01*
G01X191983Y734626D02*
X192255Y735217D01*
G01X191983Y729626D02*
X192255Y730217D01*
G01X191983Y724626D02*
X192255Y725217D01*
G01X193951Y719626D02*
X194224Y720217D01*
G01X191983Y714626D02*
X192255Y715217D01*
G01X191983Y709626D02*
X192255Y710217D01*
G01X197341Y708228D02*
X197468Y708256D01*
X197557Y708329D01*
X197588Y708425D01*
G01X197341Y711378D02*
X197468Y711406D01*
X197557Y711478D01*
X197588Y711575D01*
G01X197341Y714528D02*
X197468Y714555D01*
X197557Y714628D01*
X197588Y714724D01*
G01X197341Y717677D02*
X197468Y717705D01*
X197557Y717778D01*
X197588Y717874D01*
G01X197341Y723976D02*
X197468Y724004D01*
X197557Y724077D01*
X197588Y724173D01*
G01X197341Y727126D02*
X197468Y727154D01*
X197557Y727226D01*
X197588Y727323D01*
G01X197341Y730276D02*
X197468Y730303D01*
X197557Y730376D01*
X197588Y730472D01*
G01X197341Y733425D02*
X197468Y733453D01*
X197557Y733526D01*
X197588Y733622D01*
G01X192292Y731063D02*
X192265Y731059D01*
X192239Y731048D01*
X192215Y731030D01*
X192194Y731005D01*
X192177Y730976D01*
X192164Y730942D01*
X192156Y730905D01*
X192154Y730866D01*
G01X192292Y734213D02*
X192265Y734209D01*
X192239Y734198D01*
X192215Y734180D01*
X192194Y734155D01*
X192177Y734125D01*
X192164Y734091D01*
X192156Y734055D01*
X192154Y734016D01*
G01X197311Y733642D02*
X197450Y733838D01*
X197588Y734035D01*
X197725Y734232D01*
G01X197311Y728642D02*
X197450Y728838D01*
X197588Y729035D01*
X197725Y729232D01*
G01X197311Y723642D02*
X197450Y723838D01*
X197588Y724035D01*
X197725Y724232D01*
G01X199279Y718642D02*
X199419Y718838D01*
X199556Y719035D01*
X199693Y719232D01*
G01X197311Y713642D02*
X197450Y713838D01*
X197588Y714035D01*
X197725Y714232D01*
G01X197311Y708642D02*
X197450Y708838D01*
X197588Y709035D01*
X197725Y709232D01*
G01X191565Y735217D02*
X191139Y734626D01*
G01X191565Y730217D02*
X191139Y729626D01*
G01X191565Y725217D02*
X191139Y724626D01*
G01X193534Y720217D02*
X193107Y719626D01*
G01X191565Y715217D02*
X191139Y714626D01*
G01X191565Y710217D02*
X191139Y709626D01*
G01X199606Y738248D02*
X201575Y740217D01*
G01X204858Y743169D02*
X208268Y745138D01*
G01X203547Y750408D02*
X208268Y745767D01*
G01Y746870D02*
X203543Y751516D01*
G01X203575Y751485D02*
X203632Y751344D01*
X203637Y751105D01*
G01X203601Y750784D02*
X203637Y751107D01*
X203631Y751348D01*
X203575Y751485D01*
G01X203601Y750785D02*
X203547Y750408D01*
G01X192743Y705079D02*
X192705Y705105D01*
X192677Y705177D01*
X192667Y705276D01*
G01X191565Y703642D02*
X191139Y704232D01*
G01X197725Y704626D02*
X197588Y704824D01*
X197450Y705020D01*
X197311Y705217D01*
G01X192255Y703642D02*
X191983Y704232D01*
G01X197588Y702520D02*
X197556Y702617D01*
X197468Y702689D01*
X197341Y702717D01*
G01X192154Y705276D02*
X192156Y705237D01*
X192164Y705200D01*
X192177Y705167D01*
X192194Y705136D01*
X192215Y705112D01*
X192239Y705094D01*
X192265Y705083D01*
X192292Y705079D01*
G01X191139Y704232D02*
Y704626D01*
G01X191983Y704232D02*
Y704626D01*
G01X193107D02*
Y704232D01*
G01X197725Y704626D02*
Y704232D01*
G01X193107D02*
X193185Y703642D01*
G01X192667Y702520D02*
X192677Y702618D01*
X192705Y702690D01*
X192743Y702717D01*
G01X193107Y704626D02*
X193185Y705217D01*
G01X192292Y702717D02*
X192265Y702713D01*
X192239Y702702D01*
X192215Y702683D01*
X192194Y702659D01*
X192177Y702629D01*
X192164Y702595D01*
X192156Y702559D01*
X192154Y702520D01*
G01X190976D02*
X197588D01*
G01X197341Y702717D02*
X191256D01*
G01X197311Y703642D02*
X191565D01*
G01X191139Y704232D02*
X197725D01*
G01X191139Y704626D02*
X197725D01*
G01X197341Y705079D02*
X191256D01*
G01X197311Y705217D02*
X191565D01*
G01X191983Y704626D02*
X192255Y705217D01*
G01X197341Y705079D02*
X197468Y705106D01*
X197557Y705179D01*
X197588Y705276D01*
G01X197311Y703642D02*
X197450Y703838D01*
X197588Y704035D01*
X197725Y704232D01*
G01X191565Y705217D02*
X191139Y704626D01*
G01X193374Y1065809D02*
X193375Y1065847D01*
X193376Y1065884D01*
X193380Y1065918D01*
X193383Y1065948D01*
X193389Y1065973D01*
X193394Y1065991D01*
X193400Y1066002D01*
X193407Y1066006D01*
G01X192222Y1065809D02*
X192225Y1065847D01*
X192233Y1065884D01*
X192247Y1065918D01*
X192265Y1065948D01*
X192288Y1065973D01*
X192313Y1065991D01*
X192341Y1066002D01*
X192370Y1066006D01*
G01X197598Y1065809D02*
X197565Y1065908D01*
X197476Y1065979D01*
X197350Y1066006D01*
G01X197598Y1065809D02*
X191280D01*
G01X191542Y1066006D02*
X197350D01*
G01X192154Y1016299D02*
X192156Y1016261D01*
X192164Y1016224D01*
X192177Y1016190D01*
X192194Y1016160D01*
X192215Y1016135D01*
X192239Y1016117D01*
X192265Y1016106D01*
X192292Y1016102D01*
G01X192154Y1019449D02*
X192156Y1019411D01*
X192164Y1019374D01*
X192177Y1019340D01*
X192194Y1019309D01*
X192215Y1019285D01*
X192239Y1019267D01*
X192265Y1019256D01*
X192292Y1019252D01*
G01X192154Y1022598D02*
X192156Y1022560D01*
X192164Y1022523D01*
X192177Y1022489D01*
X192194Y1022459D01*
X192215Y1022435D01*
X192239Y1022417D01*
X192265Y1022406D01*
X192292Y1022402D01*
G01X192154Y1025748D02*
X192156Y1025710D01*
X192164Y1025673D01*
X192177Y1025639D01*
X192194Y1025609D01*
X192215Y1025584D01*
X192239Y1025566D01*
X192265Y1025555D01*
X192292Y1025551D01*
G01X192154Y1028898D02*
X192156Y1028859D01*
X192164Y1028822D01*
X192177Y1028789D01*
X192194Y1028758D01*
X192215Y1028734D01*
X192239Y1028716D01*
X192265Y1028705D01*
X192292Y1028701D01*
G01X192154Y1032047D02*
X192156Y1032009D01*
X192164Y1031972D01*
X192177Y1031938D01*
X192194Y1031908D01*
X192215Y1031883D01*
X192239Y1031865D01*
X192265Y1031854D01*
X192292Y1031850D01*
G01X192154Y1035197D02*
X192156Y1035159D01*
X192164Y1035122D01*
X192177Y1035088D01*
X192194Y1035057D01*
X192215Y1035033D01*
X192239Y1035015D01*
X192265Y1035004D01*
X192292Y1035000D01*
G01X192154Y1038346D02*
X192156Y1038308D01*
X192164Y1038271D01*
X192177Y1038237D01*
X192194Y1038207D01*
X192215Y1038183D01*
X192239Y1038165D01*
X192265Y1038154D01*
X192292Y1038150D01*
G01X192154Y1041496D02*
X192156Y1041458D01*
X192164Y1041421D01*
X192177Y1041387D01*
X192194Y1041357D01*
X192215Y1041332D01*
X192239Y1041314D01*
X192265Y1041303D01*
X192292Y1041299D01*
G01X192154Y1044646D02*
X192156Y1044607D01*
X192164Y1044570D01*
X192177Y1044537D01*
X192194Y1044506D01*
X192215Y1044482D01*
X192239Y1044464D01*
X192265Y1044453D01*
X192292Y1044449D01*
G01X192154Y1047795D02*
X192156Y1047757D01*
X192164Y1047720D01*
X192177Y1047686D01*
X192194Y1047656D01*
X192215Y1047631D01*
X192239Y1047613D01*
X192265Y1047602D01*
X192292Y1047598D01*
G01X192154Y1050945D02*
X192156Y1050907D01*
X192164Y1050870D01*
X192177Y1050836D01*
X192194Y1050806D01*
X192215Y1050781D01*
X192239Y1050763D01*
X192265Y1050752D01*
X192292Y1050748D01*
G01X192154Y1054094D02*
X192156Y1054056D01*
X192164Y1054019D01*
X192177Y1053985D01*
X192194Y1053955D01*
X192215Y1053931D01*
X192239Y1053913D01*
X192265Y1053902D01*
X192292Y1053898D01*
G01X192154Y1057244D02*
X192156Y1057206D01*
X192164Y1057169D01*
X192177Y1057135D01*
X192194Y1057105D01*
X192215Y1057080D01*
X192239Y1057062D01*
X192265Y1057051D01*
X192292Y1057047D01*
G01X192154Y1060394D02*
X192156Y1060356D01*
X192164Y1060319D01*
X192177Y1060285D01*
X192194Y1060254D01*
X192215Y1060230D01*
X192239Y1060212D01*
X192265Y1060201D01*
X192292Y1060197D01*
G01X192154Y1063543D02*
X192156Y1063505D01*
X192164Y1063468D01*
X192177Y1063434D01*
X192194Y1063404D01*
X192215Y1063380D01*
X192239Y1063361D01*
X192265Y1063350D01*
X192292Y1063346D01*
G01X190976Y1063937D02*
Y1063543D01*
G01Y1060787D02*
Y1060394D01*
G01Y1054488D02*
Y1054094D01*
G01Y1057638D02*
Y1057244D01*
G01Y1051339D02*
Y1050945D01*
G01Y1048189D02*
Y1047795D01*
G01Y1045039D02*
Y1044646D01*
G01Y1041890D02*
Y1041496D01*
G01Y1035591D02*
Y1035197D01*
G01Y1038740D02*
Y1038346D01*
G01Y1032441D02*
Y1032047D01*
G01Y1029291D02*
Y1028898D01*
G01Y1022992D02*
Y1022598D01*
G01Y1026142D02*
Y1025748D01*
G01Y1019843D02*
Y1019449D01*
G01Y1016693D02*
Y1016299D01*
G01X191074Y1044744D02*
Y1045138D01*
G01X191139Y1014744D02*
Y1015138D01*
G01Y1019744D02*
Y1020138D01*
G01Y1024744D02*
Y1025138D01*
G01Y1029744D02*
Y1030138D01*
G01Y1034744D02*
Y1035138D01*
G01Y1039744D02*
Y1040138D01*
G01X191280Y1052226D02*
Y1053211D01*
G01Y1049077D02*
Y1050061D01*
G01Y1055376D02*
Y1056360D01*
G01Y1061675D02*
Y1062659D01*
G01Y1058526D02*
Y1059510D01*
G01Y1064825D02*
Y1065809D01*
G01X191983Y1014744D02*
Y1015138D01*
G01Y1019744D02*
Y1020138D01*
G01Y1024744D02*
Y1025138D01*
G01Y1029744D02*
Y1030138D01*
G01Y1034744D02*
Y1035138D01*
G01Y1039744D02*
Y1040138D01*
G01Y1044744D02*
Y1045138D01*
G01X192154Y1063937D02*
Y1063543D01*
G01Y1060787D02*
Y1060394D01*
G01Y1054488D02*
Y1054094D01*
G01Y1057638D02*
Y1057244D01*
G01Y1051339D02*
Y1050945D01*
G01Y1048189D02*
Y1047795D01*
G01Y1045039D02*
Y1044646D01*
G01Y1041890D02*
Y1041496D01*
G01Y1035591D02*
Y1035197D01*
G01Y1038740D02*
Y1038346D01*
G01Y1032441D02*
Y1032047D01*
G01Y1029291D02*
Y1028898D01*
G01Y1022992D02*
Y1022598D01*
G01Y1026142D02*
Y1025748D01*
G01Y1019843D02*
Y1019449D01*
G01Y1016693D02*
Y1016299D01*
G01X192222Y1052226D02*
Y1053211D01*
G01Y1049077D02*
Y1050061D01*
G01Y1055376D02*
Y1056360D01*
G01Y1061675D02*
Y1062659D01*
G01Y1058526D02*
Y1059510D01*
G01Y1064825D02*
Y1065809D01*
G01X192667Y1016299D02*
Y1016693D01*
G01Y1019449D02*
Y1019843D01*
G01Y1022598D02*
Y1022992D01*
G01Y1025748D02*
Y1026142D01*
G01Y1028898D02*
Y1029291D01*
G01Y1032047D02*
Y1032441D01*
G01Y1035197D02*
Y1035591D01*
G01Y1038346D02*
Y1038740D01*
G01Y1041496D02*
Y1041890D01*
G01Y1047795D02*
Y1048189D01*
G01Y1044646D02*
Y1045039D01*
G01Y1050945D02*
Y1051339D01*
G01Y1054094D02*
Y1054488D01*
G01Y1057244D02*
Y1057638D01*
G01Y1060394D02*
Y1060787D01*
G01Y1063543D02*
Y1063937D01*
G01X193107Y1045138D02*
Y1044744D01*
G01Y1040138D02*
Y1039744D01*
G01Y1035138D02*
Y1034744D01*
G01Y1030138D02*
Y1029744D01*
G01Y1025138D02*
Y1024744D01*
G01Y1020138D02*
Y1019744D01*
G01Y1015138D02*
Y1014744D01*
G01X193374Y1052226D02*
Y1053211D01*
G01Y1049077D02*
Y1050061D01*
G01Y1055376D02*
Y1056360D01*
G01Y1061675D02*
Y1062659D01*
G01Y1058526D02*
Y1059510D01*
G01Y1064825D02*
Y1065809D01*
G01X195106Y1047697D02*
Y1046516D01*
G01X197588Y1016299D02*
Y1016693D01*
G01Y1019449D02*
Y1019843D01*
G01Y1022598D02*
Y1022992D01*
G01Y1025748D02*
Y1026142D01*
G01Y1028898D02*
Y1029291D01*
G01Y1032047D02*
Y1032441D01*
G01Y1035197D02*
Y1035591D01*
G01Y1038346D02*
Y1038740D01*
G01Y1041496D02*
Y1041890D01*
G01Y1047795D02*
Y1048189D01*
G01Y1044646D02*
Y1045039D01*
G01Y1050945D02*
Y1051339D01*
G01Y1054094D02*
Y1054488D01*
G01Y1057244D02*
Y1057638D01*
G01Y1060394D02*
Y1060787D01*
G01Y1063543D02*
Y1063937D01*
G01X197598Y1065809D02*
Y1064825D01*
G01Y1062659D02*
Y1061675D01*
G01Y1059510D02*
Y1058526D01*
G01Y1056360D02*
Y1055376D01*
G01Y1053211D02*
Y1052226D01*
G01Y1050061D02*
Y1049077D01*
G01X197725Y1040138D02*
Y1039744D01*
G01Y1035138D02*
Y1034744D01*
G01Y1030138D02*
Y1029744D01*
G01Y1025138D02*
Y1024744D01*
G01Y1020138D02*
Y1019744D01*
G01Y1015138D02*
Y1014744D01*
G01X197816Y1045138D02*
Y1044744D01*
G01X199606Y1011122D02*
Y1143760D01*
G01X200394Y1041339D02*
Y1010335D01*
G01Y1046516D02*
Y1068366D01*
G01X200453Y1144154D02*
Y1010728D01*
G01X200563Y1046720D02*
Y1041339D01*
G01X201575Y1006201D02*
Y1148681D01*
G01X193374Y1062659D02*
X193375Y1062698D01*
X193376Y1062735D01*
X193380Y1062769D01*
X193383Y1062799D01*
X193389Y1062823D01*
X193394Y1062841D01*
X193400Y1062852D01*
X193407Y1062856D01*
G01X193374Y1059510D02*
X193375Y1059548D01*
X193376Y1059585D01*
X193380Y1059619D01*
X193383Y1059649D01*
X193389Y1059674D01*
X193394Y1059692D01*
X193400Y1059703D01*
X193407Y1059707D01*
G01X193374Y1056360D02*
X193375Y1056398D01*
X193376Y1056435D01*
X193380Y1056469D01*
X193383Y1056500D01*
X193389Y1056524D01*
X193394Y1056542D01*
X193400Y1056553D01*
X193407Y1056557D01*
G01X193374Y1053211D02*
X193375Y1053249D01*
X193376Y1053286D01*
X193380Y1053320D01*
X193383Y1053350D01*
X193389Y1053374D01*
X193394Y1053393D01*
X193400Y1053404D01*
X193407Y1053407D01*
G01X193374Y1050061D02*
X193375Y1050099D01*
X193376Y1050136D01*
X193380Y1050170D01*
X193383Y1050200D01*
X193389Y1050225D01*
X193394Y1050243D01*
X193400Y1050254D01*
X193407Y1050258D01*
G01X192222Y1062659D02*
X192225Y1062698D01*
X192233Y1062735D01*
X192247Y1062769D01*
X192265Y1062799D01*
X192288Y1062823D01*
X192313Y1062841D01*
X192341Y1062852D01*
X192370Y1062856D01*
G01X192222Y1059510D02*
X192225Y1059548D01*
X192233Y1059585D01*
X192247Y1059619D01*
X192265Y1059649D01*
X192288Y1059674D01*
X192313Y1059692D01*
X192341Y1059703D01*
X192370Y1059707D01*
G01X192222Y1056360D02*
X192225Y1056398D01*
X192233Y1056435D01*
X192247Y1056469D01*
X192265Y1056500D01*
X192288Y1056524D01*
X192313Y1056542D01*
X192341Y1056553D01*
X192370Y1056557D01*
G01X192222Y1053211D02*
X192225Y1053249D01*
X192233Y1053286D01*
X192247Y1053320D01*
X192265Y1053350D01*
X192288Y1053374D01*
X192313Y1053393D01*
X192341Y1053404D01*
X192370Y1053407D01*
G01X192222Y1050061D02*
X192225Y1050099D01*
X192233Y1050136D01*
X192247Y1050170D01*
X192265Y1050200D01*
X192288Y1050225D01*
X192313Y1050243D01*
X192341Y1050254D01*
X192370Y1050258D01*
G01X192667Y1063937D02*
X192677Y1064035D01*
X192705Y1064107D01*
X192743Y1064134D01*
G01X192667Y1057638D02*
X192677Y1057736D01*
X192705Y1057808D01*
X192743Y1057835D01*
G01X192667Y1054488D02*
X192677Y1054587D01*
X192705Y1054659D01*
X192743Y1054685D01*
G01X192667Y1051339D02*
X192677Y1051437D01*
X192705Y1051509D01*
X192743Y1051535D01*
G01X192667Y1048189D02*
X192677Y1048287D01*
X192705Y1048359D01*
X192743Y1048386D01*
G01X192667Y1038740D02*
X192677Y1038839D01*
X192705Y1038911D01*
X192743Y1038937D01*
G01X192667Y1035591D02*
X192677Y1035689D01*
X192705Y1035761D01*
X192743Y1035787D01*
G01X192667Y1022992D02*
X192677Y1023091D01*
X192705Y1023163D01*
X192743Y1023189D01*
G01X192667Y1019843D02*
X192677Y1019941D01*
X192705Y1020013D01*
X192743Y1020039D01*
G01X193107Y1045138D02*
X193185Y1045728D01*
G01X193107Y1040138D02*
X193185Y1040728D01*
G01X193107Y1035138D02*
X193185Y1035728D01*
G01X193107Y1030138D02*
X193185Y1030728D01*
G01X193107Y1025138D02*
X193185Y1025728D01*
G01X193107Y1020138D02*
X193185Y1020728D01*
G01X193107Y1015138D02*
X193185Y1015728D01*
G01X191983Y1045138D02*
X192255Y1045728D01*
G01X191983Y1040138D02*
X192255Y1040728D01*
G01X191983Y1035138D02*
X192255Y1035728D01*
G01X191983Y1030138D02*
X192255Y1030728D01*
G01X191983Y1025138D02*
X192255Y1025728D01*
G01X191983Y1020138D02*
X192255Y1020728D01*
G01X191983Y1015138D02*
X192255Y1015728D01*
G01X193107Y1014744D02*
X193185Y1014154D01*
G01X193107Y1019744D02*
X193185Y1019154D01*
G01X193107Y1024744D02*
X193185Y1024154D01*
G01X193107Y1029744D02*
X193185Y1029154D01*
G01X193107Y1034744D02*
X193185Y1034154D01*
G01X193107Y1039744D02*
X193185Y1039154D01*
G01X193107Y1044744D02*
X193185Y1044154D01*
G01X197410D02*
X197546Y1044350D01*
X197681Y1044546D01*
X197816Y1044744D01*
G01X197311Y1039154D02*
X197450Y1039350D01*
X197588Y1039546D01*
X197725Y1039744D01*
G01X197311Y1034154D02*
X197450Y1034350D01*
X197588Y1034546D01*
X197725Y1034744D01*
G01X197311Y1029154D02*
X197450Y1029350D01*
X197588Y1029546D01*
X197725Y1029744D01*
G01X197311Y1024154D02*
X197450Y1024350D01*
X197588Y1024546D01*
X197725Y1024744D01*
G01X197311Y1019154D02*
X197450Y1019350D01*
X197588Y1019546D01*
X197725Y1019744D01*
G01X197311Y1014154D02*
X197450Y1014350D01*
X197588Y1014546D01*
X197725Y1014744D01*
G01X191497Y1045728D02*
X191074Y1045138D01*
G01X191565Y1040728D02*
X191139Y1040138D01*
G01X191565Y1035728D02*
X191139Y1035138D01*
G01X191565Y1030728D02*
X191139Y1030138D01*
G01X191565Y1025728D02*
X191139Y1025138D01*
G01X191565Y1020728D02*
X191139Y1020138D01*
G01X191565Y1015728D02*
X191139Y1015138D01*
G01X201575Y1008169D02*
X199606Y1006201D01*
G01X192743Y1060984D02*
X192705Y1060958D01*
X192677Y1060885D01*
X192667Y1060787D01*
G01X192743Y1045236D02*
X192705Y1045210D01*
X192677Y1045137D01*
X192667Y1045039D01*
G01X191565Y1014154D02*
X191139Y1014744D01*
G01X191565Y1019154D02*
X191139Y1019744D01*
G01X191565Y1024154D02*
X191139Y1024744D01*
G01X191565Y1029154D02*
X191139Y1029744D01*
G01X191565Y1034154D02*
X191139Y1034744D01*
G01X191565Y1039154D02*
X191139Y1039744D01*
G01X191497Y1044154D02*
X191074Y1044744D01*
G01X197725Y1015138D02*
X197588Y1015335D01*
X197450Y1015532D01*
X197311Y1015728D01*
G01X197725Y1020138D02*
X197588Y1020335D01*
X197450Y1020532D01*
X197311Y1020728D01*
G01X197725Y1025138D02*
X197588Y1025335D01*
X197450Y1025532D01*
X197311Y1025728D01*
G01X197725Y1030138D02*
X197588Y1030335D01*
X197450Y1030532D01*
X197311Y1030728D01*
G01X197725Y1035138D02*
X197588Y1035335D01*
X197450Y1035532D01*
X197311Y1035728D01*
G01X197725Y1040138D02*
X197588Y1040335D01*
X197450Y1040532D01*
X197311Y1040728D01*
G01X197816Y1045138D02*
X197681Y1045335D01*
X197546Y1045532D01*
X197410Y1045728D01*
G01X192255Y1014154D02*
X191983Y1014744D01*
G01X192255Y1019154D02*
X191983Y1019744D01*
G01X192255Y1024154D02*
X191983Y1024744D01*
G01X192255Y1029154D02*
X191983Y1029744D01*
G01X192255Y1034154D02*
X191983Y1034744D01*
G01X192255Y1039154D02*
X191983Y1039744D01*
G01X192255Y1044154D02*
X191983Y1044744D01*
G01X197598Y1050061D02*
X197565Y1050160D01*
X197476Y1050231D01*
X197350Y1050258D01*
G01X197598Y1053211D02*
X197565Y1053310D01*
X197476Y1053381D01*
X197350Y1053407D01*
G01X197598Y1056360D02*
X197565Y1056459D01*
X197476Y1056530D01*
X197350Y1056557D01*
G01X197598Y1059510D02*
X197565Y1059609D01*
X197476Y1059680D01*
X197350Y1059707D01*
G01X197598Y1062659D02*
X197565Y1062759D01*
X197476Y1062830D01*
X197350Y1062856D01*
G01X197588Y1016693D02*
X197556Y1016790D01*
X197468Y1016862D01*
X197341Y1016890D01*
G01X197588Y1019843D02*
X197556Y1019939D01*
X197468Y1020011D01*
X197341Y1020039D01*
G01X197588Y1022992D02*
X197556Y1023089D01*
X197468Y1023161D01*
X197341Y1023189D01*
G01X197588Y1026142D02*
X197556Y1026239D01*
X197468Y1026311D01*
X197341Y1026339D01*
G01X197588Y1029291D02*
X197556Y1029388D01*
X197468Y1029460D01*
X197341Y1029488D01*
G01X197588Y1032441D02*
X197556Y1032538D01*
X197468Y1032610D01*
X197341Y1032638D01*
G01X197588Y1035591D02*
X197556Y1035687D01*
X197468Y1035759D01*
X197341Y1035787D01*
G01X197588Y1038740D02*
X197556Y1038837D01*
X197468Y1038909D01*
X197341Y1038937D01*
G01X197588Y1041890D02*
X197556Y1041987D01*
X197468Y1042059D01*
X197341Y1042087D01*
G01X197588Y1045039D02*
X197556Y1045136D01*
X197468Y1045208D01*
X197341Y1045236D01*
G01X197588Y1048189D02*
X197556Y1048286D01*
X197468Y1048358D01*
X197341Y1048386D01*
G01X197588Y1051339D02*
X197556Y1051435D01*
X197468Y1051507D01*
X197341Y1051535D01*
G01X197588Y1054488D02*
X197556Y1054585D01*
X197468Y1054657D01*
X197341Y1054685D01*
G01X197588Y1057638D02*
X197556Y1057735D01*
X197468Y1057807D01*
X197341Y1057835D01*
G01X197588Y1060787D02*
X197556Y1060884D01*
X197468Y1060956D01*
X197341Y1060984D01*
G01X197588Y1063937D02*
X197556Y1064034D01*
X197468Y1064106D01*
X197341Y1064134D01*
G01X192743Y1042087D02*
X192705Y1042060D01*
X192677Y1041988D01*
X192667Y1041890D01*
G01X192743Y1032638D02*
X192705Y1032611D01*
X192677Y1032539D01*
X192667Y1032441D01*
G01X192743Y1029488D02*
X192705Y1029462D01*
X192677Y1029389D01*
X192667Y1029291D01*
G01X192743Y1026339D02*
X192705Y1026312D01*
X192677Y1026240D01*
X192667Y1026142D01*
G01X192743Y1016890D02*
X192705Y1016863D01*
X192677Y1016791D01*
X192667Y1016693D01*
G01X192743Y1016102D02*
X192705Y1016129D01*
X192677Y1016201D01*
X192667Y1016299D01*
G01X192743Y1019252D02*
X192705Y1019278D01*
X192677Y1019350D01*
X192667Y1019449D01*
G01X192743Y1022402D02*
X192705Y1022428D01*
X192677Y1022500D01*
X192667Y1022598D01*
G01X192743Y1025551D02*
X192705Y1025578D01*
X192677Y1025650D01*
X192667Y1025748D01*
G01X192743Y1028701D02*
X192705Y1028727D01*
X192677Y1028799D01*
X192667Y1028898D01*
G01X192743Y1031850D02*
X192705Y1031877D01*
X192677Y1031949D01*
X192667Y1032047D01*
G01X192743Y1035000D02*
X192705Y1035026D01*
X192677Y1035098D01*
X192667Y1035197D01*
G01X192743Y1038150D02*
X192705Y1038176D01*
X192677Y1038248D01*
X192667Y1038346D01*
G01X192743Y1041299D02*
X192705Y1041326D01*
X192677Y1041398D01*
X192667Y1041496D01*
G01X201575Y1009154D02*
X199606Y1011122D01*
G01Y1047677D02*
X201575Y1045709D01*
G01X193407Y1048880D02*
X193400Y1048884D01*
X193394Y1048895D01*
X193389Y1048913D01*
X193383Y1048938D01*
X193380Y1048967D01*
X193376Y1049001D01*
X193375Y1049038D01*
X193374Y1049077D01*
G01X193407Y1052030D02*
X193400Y1052033D01*
X193394Y1052044D01*
X193389Y1052063D01*
X193383Y1052087D01*
X193380Y1052117D01*
X193376Y1052151D01*
X193375Y1052187D01*
X193374Y1052226D01*
G01X193407Y1055179D02*
X193400Y1055183D01*
X193394Y1055194D01*
X193389Y1055212D01*
X193383Y1055237D01*
X193380Y1055267D01*
X193376Y1055300D01*
X193375Y1055337D01*
X193374Y1055376D01*
G01X193407Y1058329D02*
X193400Y1058333D01*
X193394Y1058344D01*
X193389Y1058362D01*
X193383Y1058387D01*
X193380Y1058416D01*
X193376Y1058450D01*
X193375Y1058487D01*
X193374Y1058526D01*
G01X193407Y1061478D02*
X193400Y1061482D01*
X193394Y1061493D01*
X193389Y1061511D01*
X193383Y1061536D01*
X193380Y1061566D01*
X193376Y1061600D01*
X193375Y1061636D01*
X193374Y1061675D01*
G01X193407Y1064628D02*
X193400Y1064632D01*
X193394Y1064643D01*
X193389Y1064661D01*
X193383Y1064686D01*
X193380Y1064715D01*
X193376Y1064749D01*
X193375Y1064786D01*
X193374Y1064825D01*
G01X192743Y1044449D02*
X192705Y1044475D01*
X192677Y1044547D01*
X192667Y1044646D01*
G01X192743Y1047598D02*
X192705Y1047625D01*
X192677Y1047697D01*
X192667Y1047795D01*
G01X192743Y1050748D02*
X192705Y1050774D01*
X192677Y1050846D01*
X192667Y1050945D01*
G01X192743Y1053898D02*
X192705Y1053924D01*
X192677Y1053996D01*
X192667Y1054094D01*
G01X192743Y1057047D02*
X192705Y1057074D01*
X192677Y1057146D01*
X192667Y1057244D01*
G01X192743Y1060197D02*
X192705Y1060223D01*
X192677Y1060295D01*
X192667Y1060394D01*
G01X192743Y1063346D02*
X192705Y1063373D01*
X192677Y1063445D01*
X192667Y1063543D01*
G01X204858Y1006201D02*
X201575D01*
G01X197341Y1016102D02*
X197468Y1016130D01*
X197557Y1016203D01*
X197588Y1016299D01*
G01X192292Y1016890D02*
X192265Y1016886D01*
X192239Y1016875D01*
X192215Y1016857D01*
X192194Y1016832D01*
X192177Y1016802D01*
X192164Y1016769D01*
X192156Y1016732D01*
X192154Y1016693D01*
G01X192292Y1020039D02*
X192265Y1020035D01*
X192239Y1020024D01*
X192215Y1020006D01*
X192194Y1019981D01*
X192177Y1019952D01*
X192164Y1019918D01*
X192156Y1019881D01*
X192154Y1019843D01*
G01X192292Y1023189D02*
X192265Y1023185D01*
X192239Y1023174D01*
X192215Y1023156D01*
X192194Y1023131D01*
X192177Y1023102D01*
X192164Y1023068D01*
X192156Y1023031D01*
X192154Y1022992D01*
G01X192292Y1026339D02*
X192265Y1026335D01*
X192239Y1026324D01*
X192215Y1026306D01*
X192194Y1026281D01*
X192177Y1026251D01*
X192164Y1026217D01*
X192156Y1026181D01*
X192154Y1026142D01*
G01X192292Y1029488D02*
X192265Y1029484D01*
X192239Y1029473D01*
X192215Y1029455D01*
X192194Y1029430D01*
X192177Y1029401D01*
X192164Y1029367D01*
X192156Y1029330D01*
X192154Y1029291D01*
G01X192292Y1032638D02*
X192265Y1032634D01*
X192239Y1032623D01*
X192215Y1032605D01*
X192194Y1032580D01*
X192177Y1032550D01*
X192164Y1032517D01*
X192156Y1032480D01*
X192154Y1032441D01*
G01X192292Y1035787D02*
X192265Y1035783D01*
X192239Y1035772D01*
X192215Y1035754D01*
X192194Y1035730D01*
X192177Y1035700D01*
X192164Y1035666D01*
X192156Y1035630D01*
X192154Y1035591D01*
G01X192292Y1038937D02*
X192265Y1038933D01*
X192239Y1038922D01*
X192215Y1038904D01*
X192194Y1038879D01*
X192177Y1038850D01*
X192164Y1038816D01*
X192156Y1038779D01*
X192154Y1038740D01*
G01X197311Y1014154D02*
X191565D01*
G01X191139Y1014744D02*
X197725D01*
G01X191139Y1015138D02*
X197725D01*
G01X197311Y1015728D02*
X191565D01*
G01X197341Y1016102D02*
X191256D01*
G01X197588Y1016299D02*
X190976D01*
G01Y1016693D02*
X197588D01*
G01X197341Y1016890D02*
X191256D01*
G01X197311Y1019154D02*
X191565D01*
G01X197341Y1019252D02*
X191256D01*
G01X197588Y1019449D02*
X190976D01*
G01X191139Y1019744D02*
X197725D01*
G01X190976Y1019843D02*
X197588D01*
G01X197341Y1020039D02*
X191256D01*
G01X191139Y1020138D02*
X197725D01*
G01X197311Y1020728D02*
X191565D01*
G01X197341Y1022402D02*
X191256D01*
G01X197588Y1022598D02*
X190976D01*
G01Y1022992D02*
X197588D01*
G01X197341Y1023189D02*
X191256D01*
G01X197311Y1024154D02*
X191565D01*
G01X191139Y1024744D02*
X197725D01*
G01X191139Y1025138D02*
X197725D01*
G01X197341Y1025551D02*
X191256D01*
G01X197311Y1025728D02*
X191565D01*
G01X197588Y1025748D02*
X190976D01*
G01Y1026142D02*
X197588D01*
G01X197341Y1026339D02*
X191256D01*
G01X197341Y1028701D02*
X191256D01*
G01X197588Y1028898D02*
X190976D01*
G01X197311Y1029154D02*
X191565D01*
G01X190976Y1029291D02*
X197588D01*
G01X197341Y1029488D02*
X191256D01*
G01X191139Y1029744D02*
X197725D01*
G01X191139Y1030138D02*
X197725D01*
G01X197311Y1030728D02*
X191565D01*
G01X197341Y1031850D02*
X191256D01*
G01X197588Y1032047D02*
X190976D01*
G01Y1032441D02*
X197588D01*
G01X197341Y1032638D02*
X191256D01*
G01X197311Y1034154D02*
X191565D01*
G01X191139Y1034744D02*
X197725D01*
G01X197341Y1035000D02*
X191256D01*
G01X191139Y1035138D02*
X197725D01*
G01X197588Y1035197D02*
X190976D01*
G01Y1035591D02*
X197588D01*
G01X197311Y1035728D02*
X191565D01*
G01X197341Y1035787D02*
X191256D01*
G01X197341Y1038150D02*
X191256D01*
G01X197588Y1038346D02*
X190976D01*
G01Y1038740D02*
X197588D01*
G01X197341Y1038937D02*
X191256D01*
G01X197311Y1039154D02*
X191565D01*
G01X191139Y1039744D02*
X197725D01*
G01X191139Y1040138D02*
X197725D01*
G01X197311Y1040728D02*
X191565D01*
G01X197341Y1041299D02*
X191256D01*
G01X197588Y1041496D02*
X190976D01*
G01Y1041890D02*
X197588D01*
G01X197341Y1042087D02*
X191256D01*
G01X197410Y1044154D02*
X191497D01*
G01X197341Y1044449D02*
X191256D01*
G01X197588Y1044646D02*
X190976D01*
G01X191074Y1044744D02*
X197816D01*
G01X190976Y1045039D02*
X197588D01*
G01X191074Y1045138D02*
X197816D01*
G01X197341Y1045236D02*
X191256D01*
G01X197410Y1045728D02*
X191497D01*
G01X201575Y1046516D02*
X195106D01*
G01X197341Y1047598D02*
X191256D01*
G01X197588Y1047795D02*
X190976D01*
G01Y1048189D02*
X197588D01*
G01X197341Y1048386D02*
X191256D01*
G01X191542Y1048880D02*
X197350D01*
G01X191280Y1049077D02*
X197598D01*
G01Y1050061D02*
X191280D01*
G01X191542Y1050258D02*
X197350D01*
G01X197341Y1050748D02*
X191256D01*
G01X197588Y1050945D02*
X190976D01*
G01Y1051339D02*
X197588D01*
G01X197341Y1051535D02*
X191256D01*
G01X191542Y1052030D02*
X197350D01*
G01X191280Y1052226D02*
X197598D01*
G01Y1053211D02*
X191280D01*
G01X191542Y1053407D02*
X197350D01*
G01X197341Y1053898D02*
X191256D01*
G01X197588Y1054094D02*
X190976D01*
G01Y1054488D02*
X197588D01*
G01X197341Y1054685D02*
X191256D01*
G01X191542Y1055179D02*
X197350D01*
G01X191280Y1055376D02*
X197598D01*
G01Y1056360D02*
X191280D01*
G01X191542Y1056557D02*
X197350D01*
G01X197341Y1057047D02*
X191256D01*
G01X197588Y1057244D02*
X190976D01*
G01Y1057638D02*
X197588D01*
G01X197341Y1057835D02*
X191256D01*
G01X191542Y1058329D02*
X197350D01*
G01X191280Y1058526D02*
X197598D01*
G01Y1059510D02*
X191280D01*
G01X191542Y1059707D02*
X197350D01*
G01X197341Y1060197D02*
X191256D01*
G01X197588Y1060394D02*
X190976D01*
G01Y1060787D02*
X197588D01*
G01X197341Y1060984D02*
X191256D01*
G01X191542Y1061478D02*
X197350D01*
G01X191280Y1061675D02*
X197598D01*
G01Y1062659D02*
X191280D01*
G01X191542Y1062856D02*
X197350D01*
G01X197341Y1063346D02*
X191256D01*
G01X197588Y1063543D02*
X190976D01*
G01Y1063937D02*
X197588D01*
G01X197341Y1064134D02*
X191256D01*
G01X191542Y1064628D02*
X197350D01*
G01X191280Y1064825D02*
X197598D01*
G01X192370Y1048880D02*
X192341Y1048884D01*
X192313Y1048895D01*
X192288Y1048913D01*
X192265Y1048938D01*
X192247Y1048967D01*
X192233Y1049001D01*
X192225Y1049038D01*
X192222Y1049077D01*
G01X192370Y1052030D02*
X192341Y1052033D01*
X192313Y1052044D01*
X192288Y1052063D01*
X192265Y1052087D01*
X192247Y1052117D01*
X192233Y1052151D01*
X192225Y1052187D01*
X192222Y1052226D01*
G01X192370Y1055179D02*
X192341Y1055183D01*
X192313Y1055194D01*
X192288Y1055212D01*
X192265Y1055237D01*
X192247Y1055267D01*
X192233Y1055300D01*
X192225Y1055337D01*
X192222Y1055376D01*
G01X192370Y1058329D02*
X192341Y1058333D01*
X192313Y1058344D01*
X192288Y1058362D01*
X192265Y1058387D01*
X192247Y1058416D01*
X192233Y1058450D01*
X192225Y1058487D01*
X192222Y1058526D01*
G01X192370Y1061478D02*
X192341Y1061482D01*
X192313Y1061493D01*
X192288Y1061511D01*
X192265Y1061536D01*
X192247Y1061566D01*
X192233Y1061600D01*
X192225Y1061636D01*
X192222Y1061675D01*
G01X192370Y1064628D02*
X192341Y1064632D01*
X192313Y1064643D01*
X192288Y1064661D01*
X192265Y1064686D01*
X192247Y1064715D01*
X192233Y1064749D01*
X192225Y1064786D01*
X192222Y1064825D01*
G01X197341Y1019252D02*
X197468Y1019280D01*
X197557Y1019352D01*
X197588Y1019449D01*
G01X197341Y1022402D02*
X197468Y1022429D01*
X197557Y1022502D01*
X197588Y1022598D01*
G01X197341Y1025551D02*
X197468Y1025579D01*
X197557Y1025652D01*
X197588Y1025748D01*
G01X197341Y1028701D02*
X197468Y1028728D01*
X197557Y1028801D01*
X197588Y1028898D01*
G01X197341Y1031850D02*
X197468Y1031878D01*
X197557Y1031951D01*
X197588Y1032047D01*
G01X197341Y1035000D02*
X197468Y1035028D01*
X197557Y1035100D01*
X197588Y1035197D01*
G01X197341Y1038150D02*
X197468Y1038177D01*
X197557Y1038250D01*
X197588Y1038346D01*
G01X197341Y1041299D02*
X197468Y1041327D01*
X197557Y1041400D01*
X197588Y1041496D01*
G01X197341Y1044449D02*
X197468Y1044476D01*
X197557Y1044549D01*
X197588Y1044646D01*
G01X197341Y1047598D02*
X197468Y1047626D01*
X197557Y1047699D01*
X197588Y1047795D01*
G01X197341Y1050748D02*
X197468Y1050776D01*
X197557Y1050848D01*
X197588Y1050945D01*
G01X197341Y1053898D02*
X197468Y1053925D01*
X197557Y1053998D01*
X197588Y1054094D01*
G01X197341Y1057047D02*
X197468Y1057075D01*
X197557Y1057148D01*
X197588Y1057244D01*
G01X197341Y1060197D02*
X197468Y1060224D01*
X197557Y1060297D01*
X197588Y1060394D01*
G01X197341Y1063346D02*
X197468Y1063374D01*
X197557Y1063447D01*
X197588Y1063543D01*
G01X197350Y1048880D02*
X197477Y1048907D01*
X197567Y1048980D01*
X197598Y1049077D01*
G01X197350Y1052030D02*
X197477Y1052057D01*
X197567Y1052130D01*
X197598Y1052226D01*
G01X197350Y1055179D02*
X197477Y1055207D01*
X197567Y1055279D01*
X197598Y1055376D01*
G01X197350Y1058329D02*
X197477Y1058356D01*
X197567Y1058429D01*
X197598Y1058526D01*
G01X197350Y1061478D02*
X197477Y1061506D01*
X197567Y1061578D01*
X197598Y1061675D01*
G01X197350Y1064628D02*
X197477Y1064656D01*
X197567Y1064728D01*
X197598Y1064825D01*
G01X192292Y1042087D02*
X192265Y1042083D01*
X192239Y1042072D01*
X192215Y1042054D01*
X192194Y1042029D01*
X192177Y1041999D01*
X192164Y1041965D01*
X192156Y1041929D01*
X192154Y1041890D01*
G01X192292Y1045236D02*
X192265Y1045232D01*
X192239Y1045221D01*
X192215Y1045203D01*
X192194Y1045178D01*
X192177Y1045149D01*
X192164Y1045115D01*
X192156Y1045078D01*
X192154Y1045039D01*
G01X192292Y1048386D02*
X192265Y1048382D01*
X192239Y1048371D01*
X192215Y1048353D01*
X192194Y1048328D01*
X192177Y1048298D01*
X192164Y1048265D01*
X192156Y1048228D01*
X192154Y1048189D01*
G01X192292Y1051535D02*
X192265Y1051531D01*
X192239Y1051520D01*
X192215Y1051502D01*
X192194Y1051478D01*
X192177Y1051448D01*
X192164Y1051414D01*
X192156Y1051378D01*
X192154Y1051339D01*
G01X192292Y1054685D02*
X192265Y1054681D01*
X192239Y1054670D01*
X192215Y1054652D01*
X192194Y1054627D01*
X192177Y1054598D01*
X192164Y1054564D01*
X192156Y1054527D01*
X192154Y1054488D01*
G01X192292Y1057835D02*
X192265Y1057831D01*
X192239Y1057820D01*
X192215Y1057802D01*
X192194Y1057777D01*
X192177Y1057747D01*
X192164Y1057713D01*
X192156Y1057677D01*
X192154Y1057638D01*
G01X192292Y1060984D02*
X192265Y1060980D01*
X192239Y1060969D01*
X192215Y1060951D01*
X192194Y1060926D01*
X192177Y1060897D01*
X192164Y1060863D01*
X192156Y1060826D01*
X192154Y1060787D01*
G01X192292Y1064134D02*
X192265Y1064130D01*
X192239Y1064119D01*
X192215Y1064101D01*
X192194Y1064076D01*
X192177Y1064046D01*
X192164Y1064013D01*
X192156Y1063976D01*
X192154Y1063937D01*
G01X203543Y999035D02*
Y1006201D01*
G01X208268Y1004232D02*
Y1002500D01*
G01X203602Y998576D02*
X203547Y998962D01*
G01X203575Y997885D02*
X203632Y998025D01*
X203637Y998265D01*
G01X203575Y997885D02*
X203631Y998020D01*
X203638Y998256D01*
X203601Y998584D01*
G01X208268Y1003603D02*
X203547Y998962D01*
G01X208268Y1002500D02*
X203543Y997854D01*
G01X204858Y1006201D02*
X208268Y1004232D01*
G01X192154Y1066693D02*
X192156Y1066655D01*
X192164Y1066618D01*
X192177Y1066584D01*
X192194Y1066554D01*
X192215Y1066529D01*
X192239Y1066511D01*
X192265Y1066500D01*
X192292Y1066496D01*
G01X192154Y1069843D02*
X192156Y1069804D01*
X192164Y1069767D01*
X192177Y1069733D01*
X192194Y1069703D01*
X192215Y1069679D01*
X192239Y1069661D01*
X192265Y1069650D01*
X192292Y1069646D01*
G01X192154Y1072992D02*
X192156Y1072954D01*
X192164Y1072917D01*
X192177Y1072883D01*
X192194Y1072853D01*
X192215Y1072828D01*
X192239Y1072810D01*
X192265Y1072799D01*
X192292Y1072795D01*
G01X192154Y1076142D02*
X192156Y1076104D01*
X192164Y1076067D01*
X192177Y1076033D01*
X192194Y1076002D01*
X192215Y1075978D01*
X192239Y1075960D01*
X192265Y1075949D01*
X192292Y1075945D01*
G01X192154Y1079291D02*
X192156Y1079253D01*
X192164Y1079216D01*
X192177Y1079182D01*
X192194Y1079152D01*
X192215Y1079128D01*
X192239Y1079109D01*
X192265Y1079098D01*
X192292Y1079094D01*
G01X192154Y1082441D02*
X192156Y1082403D01*
X192164Y1082366D01*
X192177Y1082332D01*
X192194Y1082302D01*
X192215Y1082277D01*
X192239Y1082259D01*
X192265Y1082248D01*
X192292Y1082244D01*
G01X192154Y1085591D02*
X192156Y1085552D01*
X192164Y1085515D01*
X192177Y1085481D01*
X192194Y1085451D01*
X192215Y1085427D01*
X192239Y1085409D01*
X192265Y1085398D01*
X192292Y1085394D01*
G01X192154Y1088740D02*
X192156Y1088702D01*
X192164Y1088665D01*
X192177Y1088631D01*
X192194Y1088601D01*
X192215Y1088576D01*
X192239Y1088558D01*
X192265Y1088547D01*
X192292Y1088543D01*
G01X192154Y1091890D02*
X192156Y1091852D01*
X192164Y1091815D01*
X192177Y1091781D01*
X192194Y1091750D01*
X192215Y1091726D01*
X192239Y1091708D01*
X192265Y1091697D01*
X192292Y1091693D01*
G01X192154Y1095039D02*
X192156Y1095001D01*
X192164Y1094964D01*
X192177Y1094930D01*
X192194Y1094900D01*
X192215Y1094876D01*
X192239Y1094857D01*
X192265Y1094846D01*
X192292Y1094843D01*
G01X192154Y1098189D02*
X192156Y1098151D01*
X192164Y1098114D01*
X192177Y1098080D01*
X192194Y1098050D01*
X192215Y1098025D01*
X192239Y1098007D01*
X192265Y1097996D01*
X192292Y1097992D01*
G01X192154Y1101339D02*
X192156Y1101300D01*
X192164Y1101263D01*
X192177Y1101230D01*
X192194Y1101199D01*
X192215Y1101175D01*
X192239Y1101157D01*
X192265Y1101146D01*
X192292Y1101142D01*
G01X192154Y1104488D02*
X192156Y1104450D01*
X192164Y1104413D01*
X192177Y1104379D01*
X192194Y1104349D01*
X192215Y1104324D01*
X192239Y1104306D01*
X192265Y1104295D01*
X192292Y1104291D01*
G01X190976Y1101732D02*
Y1101339D01*
G01Y1104882D02*
Y1104488D01*
G01Y1098583D02*
Y1098189D01*
G01Y1095433D02*
Y1095039D01*
G01Y1092283D02*
Y1091890D01*
G01Y1089134D02*
Y1088740D01*
G01Y1082835D02*
Y1082441D01*
G01Y1085984D02*
Y1085591D01*
G01Y1079685D02*
Y1079291D01*
G01Y1073386D02*
Y1072992D01*
G01Y1076535D02*
Y1076142D01*
G01Y1070236D02*
Y1069843D01*
G01Y1067087D02*
Y1066693D01*
G01X191074Y1069744D02*
Y1070138D01*
G01X191139Y1074744D02*
Y1075138D01*
G01Y1079744D02*
Y1080138D01*
G01Y1089744D02*
Y1090138D01*
G01Y1094744D02*
Y1095138D01*
G01Y1099744D02*
Y1100138D01*
G01Y1104744D02*
Y1105138D01*
G01X191983Y1069744D02*
Y1070138D01*
G01Y1074744D02*
Y1075138D01*
G01Y1079744D02*
Y1080138D01*
G01Y1089744D02*
Y1090138D01*
G01Y1094744D02*
Y1095138D01*
G01Y1099744D02*
Y1100138D01*
G01Y1104744D02*
Y1105138D01*
G01X192154Y1101732D02*
Y1101339D01*
G01Y1104882D02*
Y1104488D01*
G01Y1098583D02*
Y1098189D01*
G01Y1095433D02*
Y1095039D01*
G01Y1092283D02*
Y1091890D01*
G01Y1089134D02*
Y1088740D01*
G01Y1082835D02*
Y1082441D01*
G01Y1085984D02*
Y1085591D01*
G01Y1079685D02*
Y1079291D01*
G01Y1073386D02*
Y1072992D01*
G01Y1076535D02*
Y1076142D01*
G01Y1070236D02*
Y1069843D01*
G01Y1067087D02*
Y1066693D01*
G01X192667D02*
Y1067087D01*
G01Y1069843D02*
Y1070236D01*
G01Y1072992D02*
Y1073386D01*
G01Y1076142D02*
Y1076535D01*
G01Y1079291D02*
Y1079685D01*
G01Y1082441D02*
Y1082835D01*
G01Y1085591D02*
Y1085984D01*
G01Y1088740D02*
Y1089134D01*
G01Y1095039D02*
Y1095433D01*
G01Y1091890D02*
Y1092283D01*
G01Y1098189D02*
Y1098583D01*
G01Y1101339D02*
Y1101732D01*
G01Y1104488D02*
Y1104882D01*
G01X193107Y1105138D02*
Y1104744D01*
G01Y1100138D02*
Y1099744D01*
G01Y1095138D02*
Y1094744D01*
G01Y1090138D02*
Y1089744D01*
G01Y1080138D02*
Y1079744D01*
G01Y1075138D02*
Y1074744D01*
G01Y1070138D02*
Y1069744D01*
G01Y1084744D02*
Y1085138D01*
G01X193951Y1084744D02*
Y1085138D01*
G01X195076D02*
Y1084744D01*
G01X195106Y1068366D02*
Y1067185D01*
G01X197588Y1066693D02*
Y1067087D01*
G01Y1069843D02*
Y1070236D01*
G01Y1072992D02*
Y1073386D01*
G01Y1076142D02*
Y1076535D01*
G01Y1079291D02*
Y1079685D01*
G01Y1082441D02*
Y1082835D01*
G01Y1085591D02*
Y1085984D01*
G01Y1088740D02*
Y1089134D01*
G01Y1095039D02*
Y1095433D01*
G01Y1091890D02*
Y1092283D01*
G01Y1098189D02*
Y1098583D01*
G01Y1101339D02*
Y1101732D01*
G01Y1104488D02*
Y1104882D01*
G01X197725Y1105138D02*
Y1104744D01*
G01Y1100138D02*
Y1099744D01*
G01Y1095138D02*
Y1094744D01*
G01Y1090138D02*
Y1089744D01*
G01Y1080138D02*
Y1079744D01*
G01Y1075138D02*
Y1074744D01*
G01X197816Y1070138D02*
Y1069744D01*
G01X199693Y1085138D02*
Y1084744D01*
G01X200394Y1144547D02*
Y1073642D01*
G01X200563D02*
Y1068162D01*
G01X192667Y1104882D02*
X192677Y1104980D01*
X192705Y1105052D01*
X192743Y1105079D01*
G01X192667Y1101732D02*
X192677Y1101831D01*
X192705Y1101903D01*
X192743Y1101929D01*
G01X192667Y1098583D02*
X192677Y1098681D01*
X192705Y1098753D01*
X192743Y1098780D01*
G01X192667Y1095433D02*
X192677Y1095531D01*
X192705Y1095604D01*
X192743Y1095630D01*
G01X192667Y1092283D02*
X192677Y1092382D01*
X192705Y1092454D01*
X192743Y1092480D01*
G01X192667Y1089134D02*
X192677Y1089232D01*
X192705Y1089304D01*
X192743Y1089331D01*
G01X192667Y1085984D02*
X192677Y1086083D01*
X192705Y1086155D01*
X192743Y1086181D01*
G01X192667Y1082835D02*
X192677Y1082933D01*
X192705Y1083005D01*
X192743Y1083031D01*
G01X192667Y1079685D02*
X192677Y1079783D01*
X192705Y1079856D01*
X192743Y1079882D01*
G01X192667Y1076535D02*
X192677Y1076634D01*
X192705Y1076706D01*
X192743Y1076732D01*
G01X192667Y1073386D02*
X192677Y1073484D01*
X192705Y1073556D01*
X192743Y1073583D01*
G01X192667Y1070236D02*
X192677Y1070335D01*
X192705Y1070407D01*
X192743Y1070433D01*
G01X192667Y1067087D02*
X192677Y1067185D01*
X192705Y1067257D01*
X192743Y1067283D01*
G01X193107Y1105138D02*
X193185Y1105728D01*
G01X193107Y1100138D02*
X193185Y1100728D01*
G01X193107Y1095138D02*
X193185Y1095728D01*
G01X193107Y1090138D02*
X193185Y1090728D01*
G01X193107Y1080138D02*
X193185Y1080728D01*
G01X193107Y1075138D02*
X193185Y1075728D01*
G01X195076Y1085138D02*
X195154Y1085728D01*
G01X193107Y1070138D02*
X193185Y1070728D01*
G01X197588Y1098189D02*
X197555Y1098090D01*
X197467Y1098019D01*
X197341Y1097992D01*
G01X191983Y1105138D02*
X192255Y1105728D01*
G01X191983Y1100138D02*
X192255Y1100728D01*
G01X191983Y1095138D02*
X192255Y1095728D01*
G01X191983Y1090138D02*
X192255Y1090728D01*
G01X193951Y1085138D02*
X194224Y1085728D01*
G01X191983Y1080138D02*
X192255Y1080728D01*
G01X191983Y1075138D02*
X192255Y1075728D01*
G01X191983Y1070138D02*
X192255Y1070728D01*
G01X197410Y1069154D02*
X197546Y1069350D01*
X197681Y1069546D01*
X197816Y1069744D01*
G01X197311Y1104154D02*
X197450Y1104350D01*
X197588Y1104546D01*
X197725Y1104744D01*
G01X197311Y1099154D02*
X197450Y1099350D01*
X197588Y1099546D01*
X197725Y1099744D01*
G01X197311Y1094154D02*
X197450Y1094350D01*
X197588Y1094546D01*
X197725Y1094744D01*
G01X197311Y1089154D02*
X197450Y1089350D01*
X197588Y1089546D01*
X197725Y1089744D01*
G01X199279Y1084154D02*
X199419Y1084350D01*
X199556Y1084546D01*
X199693Y1084744D01*
G01X197311Y1079154D02*
X197450Y1079350D01*
X197588Y1079546D01*
X197725Y1079744D01*
G01X197311Y1074154D02*
X197450Y1074350D01*
X197588Y1074546D01*
X197725Y1074744D01*
G01X191497Y1070728D02*
X191074Y1070138D01*
G01X191565Y1105728D02*
X191139Y1105138D01*
G01X191565Y1100728D02*
X191139Y1100138D01*
G01X191565Y1095728D02*
X191139Y1095138D01*
G01X191565Y1090728D02*
X191139Y1090138D01*
G01X193534Y1085728D02*
X193107Y1085138D01*
G01X191565Y1080728D02*
X191139Y1080138D01*
G01X191565Y1075728D02*
X191139Y1075138D01*
G01X193107Y1069744D02*
X193185Y1069154D01*
G01X193107Y1074744D02*
X193185Y1074154D01*
G01X193107Y1079744D02*
X193185Y1079154D01*
G01X193107Y1089744D02*
X193185Y1089154D01*
G01X193107Y1094744D02*
X193185Y1094154D01*
G01X195076Y1084744D02*
X195154Y1084154D01*
G01X193107Y1099744D02*
X193185Y1099154D01*
G01X193107Y1104744D02*
X193185Y1104154D01*
G01X201575Y1069173D02*
X199606Y1067205D01*
G01X192255Y1069154D02*
X191983Y1069744D01*
G01X192255Y1074154D02*
X191983Y1074744D01*
G01X192255Y1079154D02*
X191983Y1079744D01*
G01X194224Y1084154D02*
X193951Y1084744D01*
G01X192255Y1089154D02*
X191983Y1089744D01*
G01X192255Y1094154D02*
X191983Y1094744D01*
G01X192255Y1099154D02*
X191983Y1099744D01*
G01X192255Y1104154D02*
X191983Y1104744D01*
G01X197588Y1067087D02*
X197556Y1067183D01*
X197468Y1067256D01*
X197341Y1067283D01*
G01X197588Y1070236D02*
X197556Y1070333D01*
X197468Y1070405D01*
X197341Y1070433D01*
G01X197588Y1073386D02*
X197556Y1073483D01*
X197468Y1073555D01*
X197341Y1073583D01*
G01X197588Y1076535D02*
X197556Y1076632D01*
X197468Y1076704D01*
X197341Y1076732D01*
G01X197588Y1079685D02*
X197556Y1079782D01*
X197468Y1079854D01*
X197341Y1079882D01*
G01X197588Y1082835D02*
X197556Y1082931D01*
X197468Y1083004D01*
X197341Y1083031D01*
G01X197588Y1085984D02*
X197556Y1086081D01*
X197468Y1086153D01*
X197341Y1086181D01*
G01X197588Y1089134D02*
X197556Y1089231D01*
X197468Y1089303D01*
X197341Y1089331D01*
G01X197588Y1092283D02*
X197556Y1092380D01*
X197468Y1092452D01*
X197341Y1092480D01*
G01X197588Y1095433D02*
X197556Y1095530D01*
X197468Y1095602D01*
X197341Y1095630D01*
G01X197588Y1101732D02*
X197556Y1101829D01*
X197468Y1101901D01*
X197341Y1101929D01*
G01X197588Y1104882D02*
X197556Y1104979D01*
X197468Y1105051D01*
X197341Y1105079D01*
G01X191565Y1074154D02*
X191139Y1074744D01*
G01X191565Y1079154D02*
X191139Y1079744D01*
G01X193534Y1084154D02*
X193107Y1084744D01*
G01X191565Y1089154D02*
X191139Y1089744D01*
G01X191565Y1094154D02*
X191139Y1094744D01*
G01X191565Y1099154D02*
X191139Y1099744D01*
G01X191565Y1104154D02*
X191139Y1104744D01*
G01X191497Y1069154D02*
X191074Y1069744D01*
G01X197725Y1075138D02*
X197588Y1075335D01*
X197450Y1075532D01*
X197311Y1075728D01*
G01X197725Y1080138D02*
X197588Y1080335D01*
X197450Y1080532D01*
X197311Y1080728D01*
G01X199693Y1085138D02*
X199556Y1085335D01*
X199419Y1085532D01*
X199279Y1085728D01*
G01X197725Y1090138D02*
X197588Y1090335D01*
X197450Y1090532D01*
X197311Y1090728D01*
G01X197725Y1095138D02*
X197588Y1095335D01*
X197450Y1095532D01*
X197311Y1095728D01*
G01X197725Y1100138D02*
X197588Y1100335D01*
X197450Y1100532D01*
X197311Y1100728D01*
G01X197725Y1105138D02*
X197588Y1105335D01*
X197450Y1105532D01*
X197311Y1105728D01*
G01X197816Y1070138D02*
X197681Y1070335D01*
X197546Y1070532D01*
X197410Y1070728D01*
G01X192743Y1066496D02*
X192705Y1066522D01*
X192677Y1066594D01*
X192667Y1066693D01*
G01X192743Y1069646D02*
X192705Y1069672D01*
X192677Y1069744D01*
X192667Y1069843D01*
G01X192743Y1072795D02*
X192705Y1072822D01*
X192677Y1072894D01*
X192667Y1072992D01*
G01X192743Y1075945D02*
X192705Y1075971D01*
X192677Y1076043D01*
X192667Y1076142D01*
G01X192743Y1079094D02*
X192705Y1079121D01*
X192677Y1079193D01*
X192667Y1079291D01*
G01X192743Y1082244D02*
X192705Y1082270D01*
X192677Y1082343D01*
X192667Y1082441D01*
G01X192743Y1085394D02*
X192705Y1085420D01*
X192677Y1085492D01*
X192667Y1085591D01*
G01X192743Y1088543D02*
X192705Y1088570D01*
X192677Y1088642D01*
X192667Y1088740D01*
G01X192743Y1091693D02*
X192705Y1091719D01*
X192677Y1091791D01*
X192667Y1091890D01*
G01X192743Y1094843D02*
X192705Y1094869D01*
X192677Y1094941D01*
X192667Y1095039D01*
G01X192743Y1097992D02*
X192705Y1098019D01*
X192677Y1098091D01*
X192667Y1098189D01*
G01X192743Y1101142D02*
X192705Y1101168D01*
X192677Y1101240D01*
X192667Y1101339D01*
G01X192743Y1104291D02*
X192705Y1104318D01*
X192677Y1104390D01*
X192667Y1104488D01*
G01X197341Y1066496D02*
X191256D01*
G01X197588Y1066693D02*
X190976D01*
G01Y1067087D02*
X197588D01*
G01X197341Y1067283D02*
X191256D01*
G01X195106Y1068366D02*
X201575D01*
G01X197410Y1069154D02*
X191497D01*
G01X197341Y1069646D02*
X191256D01*
G01X191074Y1069744D02*
X197816D01*
G01X197588Y1069843D02*
X190976D01*
G01X191074Y1070138D02*
X197816D01*
G01X190976Y1070236D02*
X197588D01*
G01X197341Y1070433D02*
X191256D01*
G01X197410Y1070728D02*
X191497D01*
G01X197341Y1072795D02*
X191256D01*
G01X197588Y1072992D02*
X190976D01*
G01Y1073386D02*
X197588D01*
G01X197341Y1073583D02*
X191256D01*
G01X197311Y1074154D02*
X191565D01*
G01X191139Y1074744D02*
X197725D01*
G01X191139Y1075138D02*
X197725D01*
G01X197311Y1075728D02*
X191565D01*
G01X197341Y1075945D02*
X191256D01*
G01X197588Y1076142D02*
X190976D01*
G01Y1076535D02*
X197588D01*
G01X197341Y1076732D02*
X191256D01*
G01X197341Y1079094D02*
X191256D01*
G01X197311Y1079154D02*
X191565D01*
G01X197588Y1079291D02*
X190976D01*
G01Y1079685D02*
X197588D01*
G01X191139Y1079744D02*
X197725D01*
G01X197341Y1079882D02*
X191256D01*
G01X191139Y1080138D02*
X197725D01*
G01X197311Y1080728D02*
X191565D01*
G01X197341Y1082244D02*
X191256D01*
G01X197588Y1082441D02*
X190976D01*
G01Y1082835D02*
X197588D01*
G01X197341Y1098780D02*
X197467Y1098752D01*
X197557Y1098679D01*
X197588Y1098583D01*
G01X197341Y1066496D02*
X197468Y1066524D01*
X197557Y1066596D01*
X197588Y1066693D01*
G01X197341Y1069646D02*
X197468Y1069673D01*
X197557Y1069746D01*
X197588Y1069843D01*
G01X197341Y1072795D02*
X197468Y1072823D01*
X197557Y1072896D01*
X197588Y1072992D01*
G01X197341Y1075945D02*
X197468Y1075972D01*
X197557Y1076045D01*
X197588Y1076142D01*
G01X197341Y1079094D02*
X197468Y1079122D01*
X197557Y1079195D01*
X197588Y1079291D01*
G01X197341Y1082244D02*
X197468Y1082272D01*
X197557Y1082344D01*
X197588Y1082441D01*
G01X197341Y1085394D02*
X197468Y1085421D01*
X197557Y1085494D01*
X197588Y1085591D01*
G01X197341Y1088543D02*
X197468Y1088571D01*
X197557Y1088644D01*
X197588Y1088740D01*
G01X197341Y1091693D02*
X197468Y1091720D01*
X197557Y1091793D01*
X197588Y1091890D01*
G01X197341Y1094843D02*
X197468Y1094870D01*
X197557Y1094943D01*
X197588Y1095039D01*
G01X192292Y1067283D02*
X192265Y1067280D01*
X192239Y1067269D01*
X192215Y1067250D01*
X192194Y1067226D01*
X192177Y1067196D01*
X192164Y1067162D01*
X192156Y1067126D01*
X192154Y1067087D01*
G01X192292Y1070433D02*
X192265Y1070429D01*
X192239Y1070418D01*
X192215Y1070400D01*
X192194Y1070375D01*
X192177Y1070346D01*
X192164Y1070312D01*
X192156Y1070275D01*
X192154Y1070236D01*
G01X192292Y1073583D02*
X192265Y1073579D01*
X192239Y1073568D01*
X192215Y1073550D01*
X192194Y1073525D01*
X192177Y1073495D01*
X192164Y1073461D01*
X192156Y1073425D01*
X192154Y1073386D01*
G01X192292Y1076732D02*
X192265Y1076728D01*
X192239Y1076717D01*
X192215Y1076699D01*
X192194Y1076674D01*
X192177Y1076645D01*
X192164Y1076611D01*
X192156Y1076574D01*
X192154Y1076535D01*
G01X192292Y1079882D02*
X192265Y1079878D01*
X192239Y1079867D01*
X192215Y1079849D01*
X192194Y1079824D01*
X192177Y1079794D01*
X192164Y1079761D01*
X192156Y1079724D01*
X192154Y1079685D01*
G01X192292Y1083031D02*
X192265Y1083028D01*
X192239Y1083017D01*
X192215Y1082998D01*
X192194Y1082974D01*
X192177Y1082944D01*
X192164Y1082910D01*
X192156Y1082874D01*
X192154Y1082835D01*
G01X192292Y1086181D02*
X192265Y1086177D01*
X192239Y1086166D01*
X192215Y1086148D01*
X192194Y1086123D01*
X192177Y1086094D01*
X192164Y1086060D01*
X192156Y1086023D01*
X192154Y1085984D01*
G01X192292Y1089331D02*
X192265Y1089327D01*
X192239Y1089316D01*
X192215Y1089298D01*
X192194Y1089273D01*
X192177Y1089243D01*
X192164Y1089209D01*
X192156Y1089173D01*
X192154Y1089134D01*
G01X192292Y1092480D02*
X192265Y1092476D01*
X192239Y1092465D01*
X192215Y1092447D01*
X192194Y1092422D01*
X192177Y1092393D01*
X192164Y1092359D01*
X192156Y1092322D01*
X192154Y1092283D01*
G01X192292Y1095630D02*
X192265Y1095626D01*
X192239Y1095615D01*
X192215Y1095597D01*
X192194Y1095572D01*
X192177Y1095543D01*
X192164Y1095509D01*
X192156Y1095472D01*
X192154Y1095433D01*
G01X192292Y1098780D02*
X192265Y1098776D01*
X192239Y1098765D01*
X192215Y1098746D01*
X192194Y1098722D01*
X192177Y1098692D01*
X192164Y1098658D01*
X192156Y1098622D01*
X192154Y1098583D01*
G01X192292Y1101929D02*
X192265Y1101925D01*
X192239Y1101914D01*
X192215Y1101896D01*
X192194Y1101871D01*
X192177Y1101842D01*
X192164Y1101808D01*
X192156Y1101771D01*
X192154Y1101732D01*
G01X192292Y1105079D02*
X192265Y1105075D01*
X192239Y1105064D01*
X192215Y1105046D01*
X192194Y1105021D01*
X192177Y1104991D01*
X192164Y1104957D01*
X192156Y1104921D01*
X192154Y1104882D01*
G01X197341Y1083031D02*
X191256D01*
G01X199279Y1084154D02*
X193534D01*
G01X193107Y1084744D02*
X199693D01*
G01X193107Y1085138D02*
X199693D01*
G01X197341Y1085394D02*
X191256D01*
G01X197588Y1085591D02*
X190976D01*
G01X199279Y1085728D02*
X193534D01*
G01X190976Y1085984D02*
X197588D01*
G01X197341Y1086181D02*
X191256D01*
G01X197341Y1088543D02*
X191256D01*
G01X197588Y1088740D02*
X190976D01*
G01Y1089134D02*
X197588D01*
G01X197311Y1089154D02*
X191565D01*
G01X197341Y1089331D02*
X191256D01*
G01X191139Y1089744D02*
X197725D01*
G01X191139Y1090138D02*
X197725D01*
G01X197311Y1090728D02*
X191565D01*
G01X197341Y1091693D02*
X191256D01*
G01X197588Y1091890D02*
X190976D01*
G01Y1092283D02*
X197588D01*
G01X197341Y1092480D02*
X191256D01*
G01X197311Y1094154D02*
X191565D01*
G01X191139Y1094744D02*
X197725D01*
G01X197341Y1094843D02*
X191256D01*
G01X197588Y1095039D02*
X190976D01*
G01X191139Y1095138D02*
X197725D01*
G01X190976Y1095433D02*
X197588D01*
G01X197341Y1095630D02*
X191256D01*
G01X197311Y1095728D02*
X191565D01*
G01X197341Y1097992D02*
X191256D01*
G01X197588Y1098189D02*
X190976D01*
G01Y1098583D02*
X197588D01*
G01X197341Y1098780D02*
X191256D01*
G01X197311Y1099154D02*
X191565D01*
G01X191139Y1099744D02*
X197725D01*
G01X191139Y1100138D02*
X197725D01*
G01X197311Y1100728D02*
X191565D01*
G01X197341Y1101142D02*
X191256D01*
G01X197588Y1101339D02*
X190976D01*
G01Y1101732D02*
X197588D01*
G01X197341Y1101929D02*
X191256D01*
G01X197311Y1104154D02*
X191565D01*
G01X197341Y1104291D02*
X191256D01*
G01X197588Y1104488D02*
X190976D01*
G01X191139Y1104744D02*
X197725D01*
G01X190976Y1104882D02*
X197588D01*
G01X197341Y1105079D02*
X191256D01*
G01X191139Y1105138D02*
X197725D01*
G01X197341Y1101142D02*
X197468Y1101169D01*
X197557Y1101242D01*
X197588Y1101339D01*
G01X197341Y1104291D02*
X197468Y1104319D01*
X197557Y1104392D01*
X197588Y1104488D01*
G01X192154Y1126535D02*
X192156Y1126497D01*
X192164Y1126460D01*
X192177Y1126426D01*
X192194Y1126396D01*
X192215Y1126372D01*
X192239Y1126354D01*
X192265Y1126343D01*
X192292Y1126339D01*
G01X192154Y1129685D02*
X192156Y1129647D01*
X192164Y1129610D01*
X192177Y1129576D01*
X192194Y1129546D01*
X192215Y1129521D01*
X192239Y1129503D01*
X192265Y1129492D01*
X192292Y1129488D01*
G01X192154Y1132835D02*
X192156Y1132796D01*
X192164Y1132759D01*
X192177Y1132726D01*
X192194Y1132695D01*
X192215Y1132671D01*
X192239Y1132653D01*
X192265Y1132642D01*
X192292Y1132638D01*
G01X192154Y1135984D02*
X192156Y1135946D01*
X192164Y1135909D01*
X192177Y1135875D01*
X192194Y1135845D01*
X192215Y1135820D01*
X192239Y1135802D01*
X192265Y1135791D01*
X192292Y1135787D01*
G01X192154Y1139134D02*
X192156Y1139096D01*
X192164Y1139059D01*
X192177Y1139025D01*
X192194Y1138994D01*
X192215Y1138970D01*
X192239Y1138952D01*
X192265Y1138941D01*
X192292Y1138937D01*
G01X190976Y1136378D02*
Y1135984D01*
G01Y1133228D02*
Y1132835D01*
G01Y1130079D02*
Y1129685D01*
G01Y1126929D02*
Y1126535D01*
G01X191139Y1129744D02*
Y1130138D01*
G01Y1134744D02*
Y1135138D01*
G01X191983Y1129744D02*
Y1130138D01*
G01Y1134744D02*
Y1135138D01*
G01X192154Y1136378D02*
Y1135984D01*
G01Y1133228D02*
Y1132835D01*
G01Y1130079D02*
Y1129685D01*
G01Y1126929D02*
Y1126535D01*
G01X192667D02*
Y1126929D01*
G01Y1132835D02*
Y1133228D01*
G01Y1129685D02*
Y1130079D01*
G01Y1135984D02*
Y1136378D01*
G01X193107Y1130138D02*
Y1129744D01*
G01Y1134744D02*
Y1135138D01*
G01X197588Y1126535D02*
Y1126929D01*
G01Y1132835D02*
Y1133228D01*
G01Y1129685D02*
Y1130079D01*
G01Y1135984D02*
Y1136378D01*
G01X197725Y1135138D02*
Y1134744D01*
G01Y1130138D02*
Y1129744D01*
G01X192667Y1136378D02*
X192677Y1136476D01*
X192705Y1136548D01*
X192743Y1136575D01*
G01X192667Y1133228D02*
X192677Y1133327D01*
X192705Y1133399D01*
X192743Y1133425D01*
G01X192667Y1130079D02*
X192677Y1130177D01*
X192705Y1130249D01*
X192743Y1130276D01*
G01X192667Y1126929D02*
X192677Y1127028D01*
X192705Y1127100D01*
X192743Y1127126D01*
G01X193185Y1135728D02*
X193107Y1135138D01*
G01Y1130138D02*
X193185Y1130728D01*
G01X197588Y1126535D02*
X197555Y1126436D01*
X197467Y1126365D01*
X197341Y1126339D01*
G01X191983Y1135138D02*
X192255Y1135728D01*
G01X191983Y1130138D02*
X192255Y1130728D01*
G01X197311Y1134154D02*
X197450Y1134350D01*
X197588Y1134546D01*
X197725Y1134744D01*
G01X197311Y1129154D02*
X197450Y1129350D01*
X197588Y1129546D01*
X197725Y1129744D01*
G01X191565Y1135728D02*
X191139Y1135138D01*
G01X191565Y1130728D02*
X191139Y1130138D01*
G01X193107Y1129744D02*
X193185Y1129154D01*
G01Y1134154D02*
X193107Y1134744D01*
G01X192255Y1129154D02*
X191983Y1129744D01*
G01X192255Y1134154D02*
X191983Y1134744D01*
G01X197588Y1130079D02*
X197556Y1130176D01*
X197468Y1130248D01*
X197341Y1130276D01*
G01X197588Y1133228D02*
X197556Y1133325D01*
X197468Y1133397D01*
X197341Y1133425D01*
G01X197588Y1136378D02*
X197556Y1136475D01*
X197468Y1136547D01*
X197341Y1136575D01*
G01X191565Y1129154D02*
X191139Y1129744D01*
G01X191565Y1134154D02*
X191139Y1134744D01*
G01X197725Y1130138D02*
X197588Y1130335D01*
X197450Y1130532D01*
X197311Y1130728D01*
G01X197725Y1135138D02*
X197588Y1135335D01*
X197450Y1135532D01*
X197311Y1135728D01*
G01X192743Y1126339D02*
X192705Y1126365D01*
X192677Y1126437D01*
X192667Y1126535D01*
G01X192743Y1129488D02*
X192705Y1129515D01*
X192677Y1129587D01*
X192667Y1129685D01*
G01X192743Y1132638D02*
X192705Y1132664D01*
X192677Y1132736D01*
X192667Y1132835D01*
G01X192743Y1135787D02*
X192705Y1135814D01*
X192677Y1135886D01*
X192667Y1135984D01*
G01X192743Y1138937D02*
X192705Y1138963D01*
X192677Y1139035D01*
X192667Y1139134D01*
G01X197341Y1127126D02*
X197467Y1127098D01*
X197557Y1127026D01*
X197588Y1126929D01*
G01X199279Y1125728D02*
X193534D01*
G01X197341Y1126339D02*
X191256D01*
G01X197588Y1126535D02*
X190976D01*
G01Y1126929D02*
X197588D01*
G01X197341Y1127126D02*
X191256D01*
G01X197311Y1129154D02*
X191565D01*
G01X197341Y1129488D02*
X191256D01*
G01X197588Y1129685D02*
X190976D01*
G01X191139Y1129744D02*
X197725D01*
G01X190976Y1130079D02*
X197588D01*
G01X191139Y1130138D02*
X197725D01*
G01X197341Y1130276D02*
X191256D01*
G01X197311Y1130728D02*
X191565D01*
G01X197341Y1132638D02*
X191256D01*
G01X197588Y1132835D02*
X190976D01*
G01Y1133228D02*
X197588D01*
G01X197341Y1133425D02*
X191256D01*
G01X197311Y1134154D02*
X191565D01*
G01X191139Y1134744D02*
X197725D01*
G01X191139Y1135138D02*
X197725D01*
G01X197311Y1135728D02*
X191565D01*
G01X197341Y1135787D02*
X191256D01*
G01X197588Y1135984D02*
X190976D01*
G01Y1136378D02*
X197588D01*
G01X197341Y1136575D02*
X191256D01*
G01X197341Y1129488D02*
X197468Y1129516D01*
X197557Y1129589D01*
X197588Y1129685D01*
G01X197341Y1132638D02*
X197468Y1132665D01*
X197557Y1132738D01*
X197588Y1132835D01*
G01X197341Y1135787D02*
X197468Y1135815D01*
X197557Y1135888D01*
X197588Y1135984D01*
G01X197341Y1138937D02*
X197468Y1138965D01*
X197557Y1139037D01*
X197588Y1139134D01*
G01X192292Y1127126D02*
X192265Y1127122D01*
X192239Y1127111D01*
X192215Y1127093D01*
X192194Y1127068D01*
X192177Y1127039D01*
X192164Y1127005D01*
X192156Y1126968D01*
X192154Y1126929D01*
G01X192292Y1130276D02*
X192265Y1130272D01*
X192239Y1130261D01*
X192215Y1130243D01*
X192194Y1130218D01*
X192177Y1130188D01*
X192164Y1130154D01*
X192156Y1130118D01*
X192154Y1130079D01*
G01X192292Y1133425D02*
X192265Y1133421D01*
X192239Y1133410D01*
X192215Y1133392D01*
X192194Y1133367D01*
X192177Y1133338D01*
X192164Y1133304D01*
X192156Y1133267D01*
X192154Y1133228D01*
G01X192292Y1136575D02*
X192265Y1136571D01*
X192239Y1136560D01*
X192215Y1136542D01*
X192194Y1136517D01*
X192177Y1136487D01*
X192164Y1136454D01*
X192156Y1136417D01*
X192154Y1136378D01*
G01Y1107638D02*
X192156Y1107600D01*
X192164Y1107563D01*
X192177Y1107529D01*
X192194Y1107498D01*
X192215Y1107474D01*
X192239Y1107456D01*
X192265Y1107445D01*
X192292Y1107441D01*
G01X192154Y1110787D02*
X192156Y1110749D01*
X192164Y1110712D01*
X192177Y1110678D01*
X192194Y1110648D01*
X192215Y1110624D01*
X192239Y1110606D01*
X192265Y1110594D01*
X192292Y1110591D01*
G01X192154Y1113937D02*
X192156Y1113899D01*
X192164Y1113862D01*
X192177Y1113828D01*
X192194Y1113798D01*
X192215Y1113773D01*
X192239Y1113755D01*
X192265Y1113744D01*
X192292Y1113740D01*
G01X192154Y1117087D02*
X192156Y1117048D01*
X192164Y1117011D01*
X192177Y1116978D01*
X192194Y1116947D01*
X192215Y1116923D01*
X192239Y1116905D01*
X192265Y1116894D01*
X192292Y1116890D01*
G01X192154Y1120236D02*
X192156Y1120198D01*
X192164Y1120161D01*
X192177Y1120127D01*
X192194Y1120097D01*
X192215Y1120072D01*
X192239Y1120054D01*
X192265Y1120043D01*
X192292Y1120039D01*
G01X192154Y1123386D02*
X192156Y1123348D01*
X192164Y1123311D01*
X192177Y1123277D01*
X192194Y1123246D01*
X192215Y1123222D01*
X192239Y1123204D01*
X192265Y1123193D01*
X192292Y1123189D01*
G01X190976Y1123780D02*
Y1123386D01*
G01Y1120630D02*
Y1120236D01*
G01Y1117480D02*
Y1117087D01*
G01Y1114331D02*
Y1113937D01*
G01Y1111181D02*
Y1110787D01*
G01Y1108031D02*
Y1107638D01*
G01X191139Y1109744D02*
Y1110138D01*
G01Y1114744D02*
Y1115138D01*
G01Y1119744D02*
Y1120138D01*
G01X191983Y1109744D02*
Y1110138D01*
G01Y1114744D02*
Y1115138D01*
G01Y1119744D02*
Y1120138D01*
G01X192154Y1123780D02*
Y1123386D01*
G01Y1120630D02*
Y1120236D01*
G01Y1117480D02*
Y1117087D01*
G01Y1114331D02*
Y1113937D01*
G01Y1111181D02*
Y1110787D01*
G01Y1108031D02*
Y1107638D01*
G01X192667D02*
Y1108031D01*
G01Y1113937D02*
Y1114331D01*
G01Y1110787D02*
Y1111181D01*
G01Y1117087D02*
Y1117480D01*
G01Y1123386D02*
Y1123780D01*
G01Y1120236D02*
Y1120630D01*
G01X193107Y1120138D02*
Y1119744D01*
G01Y1115138D02*
Y1114744D01*
G01Y1110138D02*
Y1109744D01*
G01Y1124744D02*
Y1125138D01*
G01X193951Y1124744D02*
Y1125138D01*
G01X195076D02*
Y1124744D01*
G01X197588Y1107638D02*
Y1108031D01*
G01Y1113937D02*
Y1114331D01*
G01Y1110787D02*
Y1111181D01*
G01Y1117087D02*
Y1117480D01*
G01Y1123386D02*
Y1123780D01*
G01Y1120236D02*
Y1120630D01*
G01X197725Y1120138D02*
Y1119744D01*
G01Y1115138D02*
Y1114744D01*
G01Y1110138D02*
Y1109744D01*
G01X199693Y1125138D02*
Y1124744D01*
G01X192667Y1123780D02*
X192677Y1123878D01*
X192705Y1123950D01*
X192743Y1123976D01*
G01X192667Y1120630D02*
X192677Y1120728D01*
X192705Y1120800D01*
X192743Y1120827D01*
G01X192667Y1117480D02*
X192677Y1117579D01*
X192705Y1117651D01*
X192743Y1117677D01*
G01X192667Y1114331D02*
X192677Y1114429D01*
X192705Y1114501D01*
X192743Y1114528D01*
G01X192667Y1111181D02*
X192677Y1111280D01*
X192705Y1111352D01*
X192743Y1111378D01*
G01X192667Y1108031D02*
X192677Y1108130D01*
X192705Y1108202D01*
X192743Y1108228D01*
G01X193107Y1120138D02*
X193185Y1120728D01*
G01X193107Y1115138D02*
X193185Y1115728D01*
G01X195076Y1125138D02*
X195154Y1125728D01*
G01X193107Y1110138D02*
X193185Y1110728D01*
G01X193951Y1125138D02*
X194224Y1125728D01*
G01X191983Y1120138D02*
X192255Y1120728D01*
G01X191983Y1115138D02*
X192255Y1115728D01*
G01X191983Y1110138D02*
X192255Y1110728D01*
G01X199279Y1124154D02*
X199419Y1124350D01*
X199556Y1124546D01*
X199693Y1124744D01*
G01X197311Y1119154D02*
X197450Y1119350D01*
X197588Y1119546D01*
X197725Y1119744D01*
G01X197311Y1114154D02*
X197450Y1114350D01*
X197588Y1114546D01*
X197725Y1114744D01*
G01X197311Y1109154D02*
X197450Y1109350D01*
X197588Y1109546D01*
X197725Y1109744D01*
G01X193534Y1125728D02*
X193107Y1125138D01*
G01X191565Y1120728D02*
X191139Y1120138D01*
G01X191565Y1115728D02*
X191139Y1115138D01*
G01X191565Y1110728D02*
X191139Y1110138D01*
G01X193107Y1109744D02*
X193185Y1109154D01*
G01X193107Y1114744D02*
X193185Y1114154D01*
G01X193107Y1119744D02*
X193185Y1119154D01*
G01X192255Y1109154D02*
X191983Y1109744D01*
G01X192255Y1114154D02*
X191983Y1114744D01*
G01X192255Y1119154D02*
X191983Y1119744D01*
G01X194224Y1124154D02*
X193951Y1124744D01*
G01X197588Y1108031D02*
X197556Y1108128D01*
X197468Y1108200D01*
X197341Y1108228D01*
G01X197588Y1111181D02*
X197556Y1111278D01*
X197468Y1111350D01*
X197341Y1111378D01*
G01X197588Y1114331D02*
X197556Y1114428D01*
X197468Y1114500D01*
X197341Y1114528D01*
G01X197588Y1117480D02*
X197556Y1117577D01*
X197468Y1117649D01*
X197341Y1117677D01*
G01X197588Y1120630D02*
X197556Y1120727D01*
X197468Y1120799D01*
X197341Y1120827D01*
G01X197588Y1123780D02*
X197556Y1123876D01*
X197468Y1123948D01*
X197341Y1123976D01*
G01X195076Y1124744D02*
X195154Y1124154D01*
G01X191565Y1109154D02*
X191139Y1109744D01*
G01X191565Y1114154D02*
X191139Y1114744D01*
G01X191565Y1119154D02*
X191139Y1119744D01*
G01X193534Y1124154D02*
X193107Y1124744D01*
G01X197725Y1110138D02*
X197588Y1110335D01*
X197450Y1110532D01*
X197311Y1110728D01*
G01X197725Y1115138D02*
X197588Y1115335D01*
X197450Y1115532D01*
X197311Y1115728D01*
G01X197725Y1120138D02*
X197588Y1120335D01*
X197450Y1120532D01*
X197311Y1120728D01*
G01X199693Y1125138D02*
X199556Y1125335D01*
X199419Y1125532D01*
X199279Y1125728D01*
G01X192743Y1107441D02*
X192705Y1107467D01*
X192677Y1107539D01*
X192667Y1107638D01*
G01X192743Y1110591D02*
X192705Y1110617D01*
X192677Y1110689D01*
X192667Y1110787D01*
G01X192743Y1113740D02*
X192705Y1113767D01*
X192677Y1113839D01*
X192667Y1113937D01*
G01X192743Y1116890D02*
X192705Y1116916D01*
X192677Y1116988D01*
X192667Y1117087D01*
G01X192743Y1120039D02*
X192705Y1120066D01*
X192677Y1120138D01*
X192667Y1120236D01*
G01X192743Y1123189D02*
X192705Y1123215D01*
X192677Y1123287D01*
X192667Y1123386D01*
G01X192292Y1108228D02*
X192265Y1108224D01*
X192239Y1108213D01*
X192215Y1108195D01*
X192194Y1108170D01*
X192177Y1108141D01*
X192164Y1108107D01*
X192156Y1108070D01*
X192154Y1108031D01*
G01X192292Y1111378D02*
X192265Y1111374D01*
X192239Y1111363D01*
X192215Y1111345D01*
X192194Y1111320D01*
X192177Y1111291D01*
X192164Y1111257D01*
X192156Y1111220D01*
X192154Y1111181D01*
G01X192292Y1114528D02*
X192265Y1114524D01*
X192239Y1114513D01*
X192215Y1114494D01*
X192194Y1114470D01*
X192177Y1114440D01*
X192164Y1114406D01*
X192156Y1114370D01*
X192154Y1114331D01*
G01X197311Y1105728D02*
X191565D01*
G01X197341Y1107441D02*
X191256D01*
G01X197588Y1107638D02*
X190976D01*
G01Y1108031D02*
X197588D01*
G01X197341Y1108228D02*
X191256D01*
G01X197311Y1109154D02*
X191565D01*
G01X191139Y1109744D02*
X197725D01*
G01X191139Y1110138D02*
X197725D01*
G01X197341Y1110591D02*
X191256D01*
G01X197311Y1110728D02*
X191565D01*
G01X197588Y1110787D02*
X190976D01*
G01Y1111181D02*
X197588D01*
G01X197341Y1111378D02*
X191256D01*
G01X197341Y1113740D02*
X191256D01*
G01X197588Y1113937D02*
X190976D01*
G01X197311Y1114154D02*
X191565D01*
G01X190976Y1114331D02*
X197588D01*
G01X197341Y1114528D02*
X191256D01*
G01X191139Y1114744D02*
X197725D01*
G01X191139Y1115138D02*
X197725D01*
G01X197311Y1115728D02*
X191565D01*
G01X197341Y1116890D02*
X191256D01*
G01X197588Y1117087D02*
X190976D01*
G01Y1117480D02*
X197588D01*
G01X197341Y1117677D02*
X191256D01*
G01X197311Y1119154D02*
X191565D01*
G01X191139Y1119744D02*
X197725D01*
G01X197341Y1120039D02*
X191256D01*
G01X191139Y1120138D02*
X197725D01*
G01X197588Y1120236D02*
X190976D01*
G01Y1120630D02*
X197588D01*
G01X197311Y1120728D02*
X191565D01*
G01X197341Y1120827D02*
X191256D01*
G01X197341Y1123189D02*
X191256D01*
G01X197588Y1123386D02*
X190976D01*
G01Y1123780D02*
X197588D01*
G01X197341Y1123976D02*
X191256D01*
G01X199279Y1124154D02*
X193534D01*
G01X193107Y1124744D02*
X199693D01*
G01X193107Y1125138D02*
X199693D01*
G01X197341Y1107441D02*
X197468Y1107469D01*
X197557Y1107541D01*
X197588Y1107638D01*
G01X197341Y1110591D02*
X197468Y1110618D01*
X197557Y1110691D01*
X197588Y1110787D01*
G01X197341Y1113740D02*
X197468Y1113768D01*
X197557Y1113841D01*
X197588Y1113937D01*
G01X197341Y1116890D02*
X197468Y1116917D01*
X197557Y1116990D01*
X197588Y1117087D01*
G01X197341Y1120039D02*
X197468Y1120067D01*
X197557Y1120140D01*
X197588Y1120236D01*
G01X197341Y1123189D02*
X197468Y1123217D01*
X197557Y1123289D01*
X197588Y1123386D01*
G01X192292Y1117677D02*
X192265Y1117673D01*
X192239Y1117662D01*
X192215Y1117644D01*
X192194Y1117619D01*
X192177Y1117590D01*
X192164Y1117556D01*
X192156Y1117519D01*
X192154Y1117480D01*
G01X192292Y1120827D02*
X192265Y1120823D01*
X192239Y1120812D01*
X192215Y1120794D01*
X192194Y1120769D01*
X192177Y1120739D01*
X192164Y1120706D01*
X192156Y1120669D01*
X192154Y1120630D01*
G01X192292Y1123976D02*
X192265Y1123972D01*
X192239Y1123961D01*
X192215Y1123943D01*
X192194Y1123919D01*
X192177Y1123889D01*
X192164Y1123855D01*
X192156Y1123819D01*
X192154Y1123780D01*
G01X190976Y1139528D02*
Y1139134D01*
G01X191139Y1139744D02*
Y1140138D01*
G01X191983Y1139744D02*
Y1140138D01*
G01X192154Y1139528D02*
Y1139134D01*
G01X192667D02*
Y1139528D01*
G01X193107Y1140138D02*
Y1139744D01*
G01X197588Y1139134D02*
Y1139528D01*
G01X197725Y1140138D02*
Y1139744D01*
G01X203543Y1148681D02*
Y1155846D01*
G01X208268Y1150650D02*
Y1152382D01*
G01X192667Y1139528D02*
X192677Y1139626D01*
X192705Y1139698D01*
X192743Y1139724D01*
G01X203601Y1156296D02*
X203637Y1156619D01*
X203631Y1156860D01*
X203575Y1156996D01*
G01X193107Y1140138D02*
X193185Y1140728D01*
G01X203601Y1156297D02*
X203547Y1155920D01*
G01X191983Y1140138D02*
X192255Y1140728D01*
G01X197311Y1139154D02*
X197450Y1139350D01*
X197588Y1139546D01*
X197725Y1139744D01*
G01X191565Y1140728D02*
X191139Y1140138D01*
G01X199606Y1143760D02*
X201575Y1145728D01*
G01X204858Y1148681D02*
X208268Y1150650D01*
G01X192255Y1139154D02*
X191983Y1139744D01*
G01X203575Y1156996D02*
X203632Y1156856D01*
X203637Y1156617D01*
G01X197588Y1139528D02*
X197556Y1139624D01*
X197468Y1139696D01*
X197341Y1139724D01*
G01X193107Y1139744D02*
X193185Y1139154D01*
G01X191565D02*
X191139Y1139744D01*
G01X197725Y1140138D02*
X197588Y1140335D01*
X197450Y1140532D01*
X197311Y1140728D01*
G01X203547Y1155920D02*
X208268Y1151278D01*
G01Y1152382D02*
X203543Y1157028D01*
G01X199606Y1148681D02*
X201575Y1146713D01*
G01X197341Y1138937D02*
X191256D01*
G01X197588Y1139134D02*
X190976D01*
G01X197311Y1139154D02*
X191565D01*
G01X190976Y1139528D02*
X197588D01*
G01X197341Y1139724D02*
X191256D01*
G01X191139Y1139744D02*
X197725D01*
G01X191139Y1140138D02*
X197725D01*
G01X197311Y1140728D02*
X191565D01*
G01X204858Y1148681D02*
X201575D01*
G01X192292Y1139724D02*
X192265Y1139720D01*
X192239Y1139709D01*
X192215Y1139691D01*
X192194Y1139667D01*
X192177Y1139637D01*
X192164Y1139603D01*
X192156Y1139567D01*
X192154Y1139528D01*
G01X191983Y1425650D02*
X192255Y1426240D01*
G01X197311Y1429665D02*
X197450Y1429861D01*
X197588Y1430058D01*
X197725Y1430256D01*
G01X191565Y1426240D02*
X191139Y1425650D01*
G01X190976Y1428504D02*
Y1428110D01*
G01X192154Y1428504D02*
Y1428110D01*
G01X192667D02*
Y1428504D01*
G01X197588Y1428110D02*
Y1428504D01*
G01X192667D02*
X192677Y1428602D01*
X192705Y1428674D01*
X192743Y1428701D01*
G01X192667Y1425354D02*
X192677Y1425453D01*
X192705Y1425525D01*
X192743Y1425551D01*
G01X193107Y1425650D02*
X193185Y1426240D01*
G01X192154Y1428110D02*
X192156Y1428072D01*
X192164Y1428035D01*
X192177Y1428001D01*
X192194Y1427971D01*
X192215Y1427946D01*
X192239Y1427928D01*
X192265Y1427917D01*
X192292Y1427913D01*
G01X193107Y1430256D02*
X193185Y1429665D01*
G01X197588Y1425354D02*
X197556Y1425451D01*
X197468Y1425523D01*
X197341Y1425551D01*
G01X197588Y1428504D02*
X197556Y1428601D01*
X197468Y1428673D01*
X197341Y1428701D01*
G01X192255Y1429665D02*
X191983Y1430256D01*
G01X191565Y1429665D02*
X191139Y1430256D01*
G01X197725Y1425650D02*
X197588Y1425847D01*
X197450Y1426044D01*
X197311Y1426240D01*
G01X192743Y1427913D02*
X192705Y1427940D01*
X192677Y1428012D01*
X192667Y1428110D01*
G01X192292Y1425551D02*
X192265Y1425547D01*
X192239Y1425536D01*
X192215Y1425518D01*
X192194Y1425493D01*
X192177Y1425464D01*
X192164Y1425430D01*
X192156Y1425393D01*
X192154Y1425354D01*
G01X190976D02*
X197588D01*
G01X197341Y1425551D02*
X191256D01*
G01X191139Y1425650D02*
X197725D01*
G01X197311Y1426240D02*
X191565D01*
G01X197341Y1427913D02*
X191256D01*
G01X197588Y1428110D02*
X190976D01*
G01Y1428504D02*
X197588D01*
G01X197341Y1428701D02*
X191256D01*
G01X197311Y1429665D02*
X191565D01*
G01X197341Y1427913D02*
X197468Y1427941D01*
X197557Y1428014D01*
X197588Y1428110D01*
G01X192292Y1428701D02*
X192265Y1428697D01*
X192239Y1428686D01*
X192215Y1428668D01*
X192194Y1428643D01*
X192177Y1428613D01*
X192164Y1428580D01*
X192156Y1428543D01*
X192154Y1428504D01*
G01X192743Y1422402D02*
X192705Y1422375D01*
X192677Y1422303D01*
X192667Y1422205D01*
G01X191983Y1420650D02*
X192255Y1421240D01*
G01X197311Y1424665D02*
X197450Y1424861D01*
X197588Y1425058D01*
X197725Y1425256D01*
G01X197311Y1419665D02*
X197450Y1419861D01*
X197588Y1420058D01*
X197725Y1420256D01*
G01X191565Y1421240D02*
X191139Y1420650D01*
G01X201575Y1413681D02*
X199606Y1411713D01*
G01X208268Y1409115D02*
X203547Y1404474D01*
G01X208268Y1408012D02*
X203543Y1403366D01*
G01X203575Y1403397D02*
X203632Y1403537D01*
X203637Y1403777D01*
G01X203575Y1403397D02*
X203631Y1403532D01*
X203638Y1403767D01*
X203601Y1404096D01*
G01X190976Y1425354D02*
Y1424961D01*
G01Y1422205D02*
Y1421811D01*
G01X191139Y1420256D02*
Y1420650D01*
G01Y1425256D02*
Y1425650D01*
G01X191983Y1420256D02*
Y1420650D01*
G01Y1425256D02*
Y1425650D01*
G01X192154Y1425354D02*
Y1424961D01*
G01Y1422205D02*
Y1421811D01*
G01X192667D02*
Y1422205D01*
G01Y1424961D02*
Y1425354D01*
G01X193107Y1425650D02*
Y1425256D01*
G01Y1420650D02*
Y1420256D01*
G01X197588Y1421811D02*
Y1422205D01*
G01Y1424961D02*
Y1425354D01*
G01X197725Y1425650D02*
Y1425256D01*
G01Y1420650D02*
Y1420256D01*
G01X199606Y1416634D02*
Y1549272D01*
G01X200394Y1446850D02*
Y1415846D01*
G01X200453Y1549665D02*
Y1416240D01*
G01X201575Y1411713D02*
Y1554193D01*
G01X203543Y1404547D02*
Y1411713D01*
G01X208268Y1409744D02*
Y1408012D01*
G01X193107Y1420650D02*
X193185Y1421240D01*
G01X192154Y1421811D02*
X192156Y1421773D01*
X192164Y1421736D01*
X192177Y1421702D01*
X192194Y1421672D01*
X192215Y1421647D01*
X192239Y1421629D01*
X192265Y1421618D01*
X192292Y1421614D01*
G01X192154Y1424961D02*
X192156Y1424922D01*
X192164Y1424885D01*
X192177Y1424852D01*
X192194Y1424821D01*
X192215Y1424797D01*
X192239Y1424779D01*
X192265Y1424768D01*
X192292Y1424764D01*
G01X203602Y1404088D02*
X203547Y1404474D01*
G01X193107Y1420256D02*
X193185Y1419665D01*
G01X193107Y1425256D02*
X193185Y1424665D01*
G01X197588Y1422205D02*
X197556Y1422302D01*
X197468Y1422374D01*
X197341Y1422402D01*
G01X192255Y1419665D02*
X191983Y1420256D01*
G01X192255Y1424665D02*
X191983Y1425256D01*
G01X191565Y1419665D02*
X191139Y1420256D01*
G01X191565Y1424665D02*
X191139Y1425256D01*
G01X197725Y1420650D02*
X197588Y1420847D01*
X197450Y1421044D01*
X197311Y1421240D01*
G01X201575Y1414665D02*
X199606Y1416634D01*
G01X204858Y1411713D02*
X208268Y1409744D01*
G01X192743Y1421614D02*
X192705Y1421641D01*
X192677Y1421713D01*
X192667Y1421811D01*
G01X192743Y1424764D02*
X192705Y1424790D01*
X192677Y1424862D01*
X192667Y1424961D01*
G01X192292Y1422402D02*
X192265Y1422398D01*
X192239Y1422387D01*
X192215Y1422369D01*
X192194Y1422344D01*
X192177Y1422314D01*
X192164Y1422280D01*
X192156Y1422244D01*
X192154Y1422205D01*
G01X204858Y1411713D02*
X201575D01*
G01X197311Y1419665D02*
X191565D01*
G01X191139Y1420256D02*
X197725D01*
G01X191139Y1420650D02*
X197725D01*
G01X197311Y1421240D02*
X191565D01*
G01X197341Y1421614D02*
X191256D01*
G01X197588Y1421811D02*
X190976D01*
G01Y1422205D02*
X197588D01*
G01X197341Y1422402D02*
X191256D01*
G01X197311Y1424665D02*
X191565D01*
G01X197341Y1424764D02*
X191256D01*
G01X197588Y1424961D02*
X190976D01*
G01X191139Y1425256D02*
X197725D01*
G01X197341Y1421614D02*
X197468Y1421642D01*
X197557Y1421715D01*
X197588Y1421811D01*
G01X197341Y1424764D02*
X197468Y1424791D01*
X197557Y1424864D01*
X197588Y1424961D01*
G01X285438Y1490153D02*
G03I-15748J0D01*
G01X192743Y1450748D02*
X192705Y1450722D01*
X192677Y1450649D01*
X192667Y1450551D01*
G01X192743Y1447598D02*
X192705Y1447572D01*
X192677Y1447500D01*
X192667Y1447402D01*
G01X192743Y1438150D02*
X192705Y1438123D01*
X192677Y1438051D01*
X192667Y1437953D01*
G01X192743Y1435000D02*
X192705Y1434974D01*
X192677Y1434901D01*
X192667Y1434803D01*
G01X192743Y1431850D02*
X192705Y1431824D01*
X192677Y1431752D01*
X192667Y1431654D01*
G01X191983Y1450650D02*
X192255Y1451240D01*
G01X191983Y1445650D02*
X192255Y1446240D01*
G01X191983Y1440650D02*
X192255Y1441240D01*
G01X191983Y1435650D02*
X192255Y1436240D01*
G01X191983Y1430650D02*
X192255Y1431240D01*
G01X197410Y1449665D02*
X197546Y1449861D01*
X197681Y1450058D01*
X197816Y1450256D01*
G01X197311Y1444665D02*
X197450Y1444861D01*
X197588Y1445058D01*
X197725Y1445256D01*
G01X197311Y1439665D02*
X197450Y1439861D01*
X197588Y1440058D01*
X197725Y1440256D01*
G01X197311Y1434665D02*
X197450Y1434861D01*
X197588Y1435058D01*
X197725Y1435256D01*
G01X191497Y1451240D02*
X191074Y1450650D01*
G01X191565Y1446240D02*
X191139Y1445650D01*
G01X191565Y1441240D02*
X191139Y1440650D01*
G01X191565Y1436240D02*
X191139Y1435650D01*
G01X191565Y1431240D02*
X191139Y1430650D01*
G01X193107Y1450650D02*
X193185Y1451240D01*
G01X193107Y1445650D02*
X193185Y1446240D01*
G01X190976Y1463150D02*
Y1462756D01*
G01Y1460000D02*
Y1459606D01*
G01Y1453701D02*
Y1453307D01*
G01Y1456850D02*
Y1456457D01*
G01Y1450551D02*
Y1450157D01*
G01Y1447402D02*
Y1447008D01*
G01Y1444252D02*
Y1443858D01*
G01Y1441102D02*
Y1440709D01*
G01Y1437953D02*
Y1437559D01*
G01Y1434803D02*
Y1434409D01*
G01Y1431654D02*
Y1431260D01*
G01X191074Y1450256D02*
Y1450650D01*
G01X191139Y1430256D02*
Y1430650D01*
G01Y1435256D02*
Y1435650D01*
G01Y1440256D02*
Y1440650D01*
G01Y1445256D02*
Y1445650D01*
G01X191280Y1454589D02*
Y1455573D01*
G01Y1457738D02*
Y1458722D01*
G01Y1464037D02*
Y1465022D01*
G01Y1460888D02*
Y1461872D01*
G01X191983Y1430256D02*
Y1430650D01*
G01Y1435256D02*
Y1435650D01*
G01Y1440256D02*
Y1440650D01*
G01Y1445256D02*
Y1445650D01*
G01Y1450256D02*
Y1450650D01*
G01X192154Y1463150D02*
Y1462756D01*
G01Y1460000D02*
Y1459606D01*
G01Y1453701D02*
Y1453307D01*
G01Y1456850D02*
Y1456457D01*
G01Y1450551D02*
Y1450157D01*
G01Y1447402D02*
Y1447008D01*
G01Y1444252D02*
Y1443858D01*
G01Y1441102D02*
Y1440709D01*
G01Y1437953D02*
Y1437559D01*
G01Y1434803D02*
Y1434409D01*
G01Y1431654D02*
Y1431260D01*
G01X192222Y1454589D02*
Y1455573D01*
G01Y1457738D02*
Y1458722D01*
G01Y1464037D02*
Y1465022D01*
G01Y1460888D02*
Y1461872D01*
G01X192667Y1431260D02*
Y1431654D01*
G01Y1437559D02*
Y1437953D01*
G01Y1434409D02*
Y1434803D01*
G01Y1440709D02*
Y1441102D01*
G01Y1447008D02*
Y1447402D01*
G01Y1443858D02*
Y1444252D01*
G01Y1450157D02*
Y1450551D01*
G01Y1453307D02*
Y1453701D01*
G01Y1456457D02*
Y1456850D01*
G01Y1459606D02*
Y1460000D01*
G01Y1462756D02*
Y1463150D01*
G01X193107Y1450650D02*
Y1450256D01*
G01Y1445650D02*
Y1445256D01*
G01Y1440650D02*
Y1440256D01*
G01Y1435650D02*
Y1435256D01*
G01Y1430650D02*
Y1430256D01*
G01X193374Y1454589D02*
Y1455573D01*
G01Y1457738D02*
Y1458722D01*
G01Y1464037D02*
Y1465022D01*
G01Y1460888D02*
Y1461872D01*
G01X195106Y1453209D02*
Y1452028D01*
G01X197588Y1431260D02*
Y1431654D01*
G01Y1437559D02*
Y1437953D01*
G01Y1434409D02*
Y1434803D01*
G01Y1440709D02*
Y1441102D01*
G01Y1447008D02*
Y1447402D01*
G01Y1443858D02*
Y1444252D01*
G01Y1450157D02*
Y1450551D01*
G01Y1453307D02*
Y1453701D01*
G01Y1456457D02*
Y1456850D01*
G01Y1459606D02*
Y1460000D01*
G01Y1462756D02*
Y1463150D01*
G01X197598Y1465022D02*
Y1464037D01*
G01Y1461872D02*
Y1460888D01*
G01Y1458722D02*
Y1457738D01*
G01Y1455573D02*
Y1454589D01*
G01X197725Y1445650D02*
Y1445256D01*
G01Y1440650D02*
Y1440256D01*
G01Y1435650D02*
Y1435256D01*
G01Y1430650D02*
Y1430256D01*
G01X197816Y1450650D02*
Y1450256D01*
G01X200394Y1452028D02*
Y1473878D01*
G01X200563Y1452231D02*
Y1446850D01*
G01X193374Y1465022D02*
X193375Y1465060D01*
X193376Y1465097D01*
X193380Y1465131D01*
X193383Y1465161D01*
X193389Y1465185D01*
X193394Y1465204D01*
X193400Y1465215D01*
X193407Y1465219D01*
G01X193374Y1461872D02*
X193375Y1461910D01*
X193376Y1461947D01*
X193380Y1461981D01*
X193383Y1462011D01*
X193389Y1462036D01*
X193394Y1462054D01*
X193400Y1462065D01*
X193407Y1462069D01*
G01X193374Y1458722D02*
X193375Y1458761D01*
X193376Y1458798D01*
X193380Y1458831D01*
X193383Y1458862D01*
X193389Y1458886D01*
X193394Y1458904D01*
X193400Y1458915D01*
X193407Y1458919D01*
G01X193374Y1455573D02*
X193375Y1455611D01*
X193376Y1455648D01*
X193380Y1455682D01*
X193383Y1455712D01*
X193389Y1455737D01*
X193394Y1455755D01*
X193400Y1455766D01*
X193407Y1455770D01*
G01X192222Y1465022D02*
X192225Y1465060D01*
X192233Y1465097D01*
X192247Y1465131D01*
X192265Y1465161D01*
X192288Y1465185D01*
X192313Y1465204D01*
X192341Y1465215D01*
X192370Y1465219D01*
G01X192222Y1461872D02*
X192225Y1461910D01*
X192233Y1461947D01*
X192247Y1461981D01*
X192265Y1462011D01*
X192288Y1462036D01*
X192313Y1462054D01*
X192341Y1462065D01*
X192370Y1462069D01*
G01X192222Y1458722D02*
X192225Y1458761D01*
X192233Y1458798D01*
X192247Y1458831D01*
X192265Y1458862D01*
X192288Y1458886D01*
X192313Y1458904D01*
X192341Y1458915D01*
X192370Y1458919D01*
G01X192222Y1455573D02*
X192225Y1455611D01*
X192233Y1455648D01*
X192247Y1455682D01*
X192265Y1455712D01*
X192288Y1455737D01*
X192313Y1455755D01*
X192341Y1455766D01*
X192370Y1455770D01*
G01X192667Y1463150D02*
X192677Y1463248D01*
X192705Y1463320D01*
X192743Y1463346D01*
G01X192667Y1460000D02*
X192677Y1460098D01*
X192705Y1460170D01*
X192743Y1460197D01*
G01X192667Y1456850D02*
X192677Y1456949D01*
X192705Y1457021D01*
X192743Y1457047D01*
G01X192667Y1453701D02*
X192677Y1453799D01*
X192705Y1453871D01*
X192743Y1453898D01*
G01X192667Y1444252D02*
X192677Y1444350D01*
X192705Y1444422D01*
X192743Y1444449D01*
G01X192667Y1441102D02*
X192677Y1441201D01*
X192705Y1441273D01*
X192743Y1441299D01*
G01X193107Y1440650D02*
X193185Y1441240D01*
G01X193107Y1435650D02*
X193185Y1436240D01*
G01X193107Y1430650D02*
X193185Y1431240D01*
G01X192154Y1431260D02*
X192156Y1431222D01*
X192164Y1431185D01*
X192177Y1431151D01*
X192194Y1431120D01*
X192215Y1431096D01*
X192239Y1431078D01*
X192265Y1431067D01*
X192292Y1431063D01*
G01X192154Y1434409D02*
X192156Y1434371D01*
X192164Y1434334D01*
X192177Y1434300D01*
X192194Y1434270D01*
X192215Y1434246D01*
X192239Y1434228D01*
X192265Y1434217D01*
X192292Y1434213D01*
G01X192154Y1437559D02*
X192156Y1437521D01*
X192164Y1437484D01*
X192177Y1437450D01*
X192194Y1437420D01*
X192215Y1437395D01*
X192239Y1437377D01*
X192265Y1437366D01*
X192292Y1437362D01*
G01X192154Y1440709D02*
X192156Y1440670D01*
X192164Y1440633D01*
X192177Y1440600D01*
X192194Y1440569D01*
X192215Y1440545D01*
X192239Y1440527D01*
X192265Y1440516D01*
X192292Y1440512D01*
G01X192154Y1443858D02*
X192156Y1443820D01*
X192164Y1443783D01*
X192177Y1443749D01*
X192194Y1443719D01*
X192215Y1443694D01*
X192239Y1443676D01*
X192265Y1443665D01*
X192292Y1443661D01*
G01X192154Y1447008D02*
X192156Y1446970D01*
X192164Y1446933D01*
X192177Y1446899D01*
X192194Y1446869D01*
X192215Y1446844D01*
X192239Y1446826D01*
X192265Y1446815D01*
X192292Y1446811D01*
G01X192154Y1450157D02*
X192156Y1450119D01*
X192164Y1450082D01*
X192177Y1450048D01*
X192194Y1450018D01*
X192215Y1449994D01*
X192239Y1449976D01*
X192265Y1449965D01*
X192292Y1449961D01*
G01X192154Y1453307D02*
X192156Y1453269D01*
X192164Y1453232D01*
X192177Y1453198D01*
X192194Y1453168D01*
X192215Y1453143D01*
X192239Y1453125D01*
X192265Y1453114D01*
X192292Y1453110D01*
G01X192154Y1456457D02*
X192156Y1456419D01*
X192164Y1456381D01*
X192177Y1456348D01*
X192194Y1456317D01*
X192215Y1456293D01*
X192239Y1456275D01*
X192265Y1456264D01*
X192292Y1456260D01*
G01X192154Y1459606D02*
X192156Y1459568D01*
X192164Y1459531D01*
X192177Y1459497D01*
X192194Y1459467D01*
X192215Y1459443D01*
X192239Y1459424D01*
X192265Y1459413D01*
X192292Y1459409D01*
G01X192154Y1462756D02*
X192156Y1462718D01*
X192164Y1462681D01*
X192177Y1462647D01*
X192194Y1462617D01*
X192215Y1462592D01*
X192239Y1462574D01*
X192265Y1462563D01*
X192292Y1462559D01*
G01X193107Y1435256D02*
X193185Y1434665D01*
G01X193107Y1440256D02*
X193185Y1439665D01*
G01X193107Y1445256D02*
X193185Y1444665D01*
G01X193107Y1450256D02*
X193185Y1449665D01*
G01X197598Y1455573D02*
X197565Y1455672D01*
X197476Y1455743D01*
X197350Y1455770D01*
G01X197598Y1458722D02*
X197565Y1458822D01*
X197476Y1458893D01*
X197350Y1458919D01*
G01X197598Y1461872D02*
X197565Y1461971D01*
X197476Y1462042D01*
X197350Y1462069D01*
G01X197598Y1465022D02*
X197565Y1465121D01*
X197476Y1465192D01*
X197350Y1465219D01*
G01X197588Y1431654D02*
X197556Y1431750D01*
X197468Y1431822D01*
X197341Y1431850D01*
G01X197588Y1434803D02*
X197556Y1434900D01*
X197468Y1434972D01*
X197341Y1435000D01*
G01X197588Y1437953D02*
X197556Y1438050D01*
X197468Y1438122D01*
X197341Y1438150D01*
G01X197588Y1441102D02*
X197556Y1441199D01*
X197468Y1441271D01*
X197341Y1441299D01*
G01X197588Y1444252D02*
X197556Y1444349D01*
X197468Y1444421D01*
X197341Y1444449D01*
G01X197588Y1447402D02*
X197556Y1447498D01*
X197468Y1447570D01*
X197341Y1447598D01*
G01X197588Y1450551D02*
X197556Y1450648D01*
X197468Y1450720D01*
X197341Y1450748D01*
G01X197588Y1453701D02*
X197556Y1453798D01*
X197468Y1453870D01*
X197341Y1453898D01*
G01X197588Y1456850D02*
X197556Y1456947D01*
X197468Y1457019D01*
X197341Y1457047D01*
G01X197588Y1460000D02*
X197556Y1460097D01*
X197468Y1460169D01*
X197341Y1460197D01*
G01X197588Y1463150D02*
X197556Y1463246D01*
X197468Y1463319D01*
X197341Y1463346D01*
G01X192255Y1434665D02*
X191983Y1435256D01*
G01X192255Y1439665D02*
X191983Y1440256D01*
G01X192255Y1444665D02*
X191983Y1445256D01*
G01X192255Y1449665D02*
X191983Y1450256D01*
G01X191565Y1434665D02*
X191139Y1435256D01*
G01X191565Y1439665D02*
X191139Y1440256D01*
G01X191565Y1444665D02*
X191139Y1445256D01*
G01X191497Y1449665D02*
X191074Y1450256D01*
G01X197725Y1430650D02*
X197588Y1430847D01*
X197450Y1431044D01*
X197311Y1431240D01*
G01X197725Y1435650D02*
X197588Y1435847D01*
X197450Y1436044D01*
X197311Y1436240D01*
G01X197725Y1440650D02*
X197588Y1440847D01*
X197450Y1441044D01*
X197311Y1441240D01*
G01X197725Y1445650D02*
X197588Y1445847D01*
X197450Y1446044D01*
X197311Y1446240D01*
G01X197816Y1450650D02*
X197681Y1450847D01*
X197546Y1451044D01*
X197410Y1451240D01*
G01X199606Y1453189D02*
X201575Y1451220D01*
G01X193407Y1454392D02*
X193400Y1454396D01*
X193394Y1454407D01*
X193389Y1454425D01*
X193383Y1454450D01*
X193380Y1454479D01*
X193376Y1454513D01*
X193375Y1454550D01*
X193374Y1454589D01*
G01X193407Y1457541D02*
X193400Y1457545D01*
X193394Y1457556D01*
X193389Y1457574D01*
X193383Y1457599D01*
X193380Y1457629D01*
X193376Y1457663D01*
X193375Y1457699D01*
X193374Y1457738D01*
G01X193407Y1460691D02*
X193400Y1460695D01*
X193394Y1460706D01*
X193389Y1460724D01*
X193383Y1460749D01*
X193380Y1460778D01*
X193376Y1460812D01*
X193375Y1460849D01*
X193374Y1460888D01*
G01X192743Y1431063D02*
X192705Y1431089D01*
X192677Y1431161D01*
X192667Y1431260D01*
G01X192743Y1434213D02*
X192705Y1434239D01*
X192677Y1434311D01*
X192667Y1434409D01*
G01X192743Y1437362D02*
X192705Y1437389D01*
X192677Y1437461D01*
X192667Y1437559D01*
G01X192743Y1440512D02*
X192705Y1440538D01*
X192677Y1440610D01*
X192667Y1440709D01*
G01X192743Y1443661D02*
X192705Y1443688D01*
X192677Y1443760D01*
X192667Y1443858D01*
G01X192743Y1446811D02*
X192705Y1446837D01*
X192677Y1446909D01*
X192667Y1447008D01*
G01X192743Y1449961D02*
X192705Y1449987D01*
X192677Y1450059D01*
X192667Y1450157D01*
G01X192743Y1453110D02*
X192705Y1453137D01*
X192677Y1453209D01*
X192667Y1453307D01*
G01X192743Y1456260D02*
X192705Y1456286D01*
X192677Y1456358D01*
X192667Y1456457D01*
G01X192743Y1459409D02*
X192705Y1459436D01*
X192677Y1459508D01*
X192667Y1459606D01*
G01X192743Y1462559D02*
X192705Y1462585D01*
X192677Y1462657D01*
X192667Y1462756D01*
G01X193407Y1463841D02*
X193400Y1463844D01*
X193394Y1463856D01*
X193389Y1463874D01*
X193383Y1463898D01*
X193380Y1463928D01*
X193376Y1463962D01*
X193375Y1463998D01*
X193374Y1464037D01*
G01X191139Y1430256D02*
X197725D01*
G01X191139Y1430650D02*
X197725D01*
G01X197341Y1431063D02*
X191256D01*
G01X197311Y1431240D02*
X191565D01*
G01X197588Y1431260D02*
X190976D01*
G01Y1431654D02*
X197588D01*
G01X197341Y1431850D02*
X191256D01*
G01X197341Y1434213D02*
X191256D01*
G01X197588Y1434409D02*
X190976D01*
G01X197311Y1434665D02*
X191565D01*
G01X190976Y1434803D02*
X197588D01*
G01X197341Y1435000D02*
X191256D01*
G01X191139Y1435256D02*
X197725D01*
G01X191139Y1435650D02*
X197725D01*
G01X197311Y1436240D02*
X191565D01*
G01X197341Y1437362D02*
X191256D01*
G01X197588Y1437559D02*
X190976D01*
G01Y1437953D02*
X197588D01*
G01X197341Y1438150D02*
X191256D01*
G01X197311Y1439665D02*
X191565D01*
G01X191139Y1440256D02*
X197725D01*
G01X197341Y1440512D02*
X191256D01*
G01X191139Y1440650D02*
X197725D01*
G01X197588Y1440709D02*
X190976D01*
G01Y1441102D02*
X197588D01*
G01X197311Y1441240D02*
X191565D01*
G01X197341Y1441299D02*
X191256D01*
G01X197341Y1443661D02*
X191256D01*
G01X197588Y1443858D02*
X190976D01*
G01Y1444252D02*
X197588D01*
G01X197341Y1444449D02*
X191256D01*
G01X197311Y1444665D02*
X191565D01*
G01X191139Y1445256D02*
X197725D01*
G01X191139Y1445650D02*
X197725D01*
G01X197311Y1446240D02*
X191565D01*
G01X197341Y1446811D02*
X191256D01*
G01X197588Y1447008D02*
X190976D01*
G01Y1447402D02*
X197588D01*
G01X197341Y1447598D02*
X191256D01*
G01X197410Y1449665D02*
X191497D01*
G01X197341Y1449961D02*
X191256D01*
G01X197588Y1450157D02*
X190976D01*
G01X191074Y1450256D02*
X197816D01*
G01X190976Y1450551D02*
X197588D01*
G01X191074Y1450650D02*
X197816D01*
G01X197341Y1450748D02*
X191256D01*
G01X197410Y1451240D02*
X191497D01*
G01X201575Y1452028D02*
X195106D01*
G01X197341Y1453110D02*
X191256D01*
G01X197588Y1453307D02*
X190976D01*
G01Y1453701D02*
X197588D01*
G01X197341Y1453898D02*
X191256D01*
G01X191542Y1454392D02*
X197350D01*
G01X191280Y1454589D02*
X197598D01*
G01Y1455573D02*
X191280D01*
G01X191542Y1455770D02*
X197350D01*
G01X197341Y1456260D02*
X191256D01*
G01X197588Y1456457D02*
X190976D01*
G01Y1456850D02*
X197588D01*
G01X197341Y1457047D02*
X191256D01*
G01X191542Y1457541D02*
X197350D01*
G01X191280Y1457738D02*
X197598D01*
G01Y1458722D02*
X191280D01*
G01X191542Y1458919D02*
X197350D01*
G01X197341Y1459409D02*
X191256D01*
G01X197588Y1459606D02*
X190976D01*
G01Y1460000D02*
X197588D01*
G01X197341Y1460197D02*
X191256D01*
G01X191542Y1460691D02*
X197350D01*
G01X191280Y1460888D02*
X197598D01*
G01Y1461872D02*
X191280D01*
G01X191542Y1462069D02*
X197350D01*
G01X197341Y1462559D02*
X191256D01*
G01X197588Y1462756D02*
X190976D01*
G01Y1463150D02*
X197588D01*
G01X197341Y1463346D02*
X191256D01*
G01X191542Y1463841D02*
X197350D01*
G01X191280Y1464037D02*
X197598D01*
G01Y1465022D02*
X191280D01*
G01X191542Y1465219D02*
X197350D01*
G01X192370Y1454392D02*
X192341Y1454396D01*
X192313Y1454407D01*
X192288Y1454425D01*
X192265Y1454450D01*
X192247Y1454479D01*
X192233Y1454513D01*
X192225Y1454550D01*
X192222Y1454589D01*
G01X192370Y1457541D02*
X192341Y1457545D01*
X192313Y1457556D01*
X192288Y1457574D01*
X192265Y1457599D01*
X192247Y1457629D01*
X192233Y1457663D01*
X192225Y1457699D01*
X192222Y1457738D01*
G01X192370Y1460691D02*
X192341Y1460695D01*
X192313Y1460706D01*
X192288Y1460724D01*
X192265Y1460749D01*
X192247Y1460778D01*
X192233Y1460812D01*
X192225Y1460849D01*
X192222Y1460888D01*
G01X192370Y1463841D02*
X192341Y1463844D01*
X192313Y1463856D01*
X192288Y1463874D01*
X192265Y1463898D01*
X192247Y1463928D01*
X192233Y1463962D01*
X192225Y1463998D01*
X192222Y1464037D01*
G01X197341Y1431063D02*
X197468Y1431091D01*
X197557Y1431163D01*
X197588Y1431260D01*
G01X197341Y1434213D02*
X197468Y1434240D01*
X197557Y1434313D01*
X197588Y1434409D01*
G01X197341Y1437362D02*
X197468Y1437390D01*
X197557Y1437463D01*
X197588Y1437559D01*
G01X197341Y1440512D02*
X197468Y1440539D01*
X197557Y1440612D01*
X197588Y1440709D01*
G01X197341Y1443661D02*
X197468Y1443689D01*
X197557Y1443762D01*
X197588Y1443858D01*
G01X197341Y1446811D02*
X197468Y1446839D01*
X197557Y1446911D01*
X197588Y1447008D01*
G01X197341Y1449961D02*
X197468Y1449988D01*
X197557Y1450061D01*
X197588Y1450157D01*
G01X197341Y1453110D02*
X197468Y1453138D01*
X197557Y1453211D01*
X197588Y1453307D01*
G01X197341Y1456260D02*
X197468Y1456287D01*
X197557Y1456360D01*
X197588Y1456457D01*
G01X197341Y1459409D02*
X197468Y1459437D01*
X197557Y1459510D01*
X197588Y1459606D01*
G01X197341Y1462559D02*
X197468Y1462587D01*
X197557Y1462659D01*
X197588Y1462756D01*
G01X197350Y1454392D02*
X197477Y1454419D01*
X197567Y1454492D01*
X197598Y1454589D01*
G01X197350Y1457541D02*
X197477Y1457569D01*
X197567Y1457641D01*
X197598Y1457738D01*
G01X197350Y1460691D02*
X197477Y1460719D01*
X197567Y1460791D01*
X197598Y1460888D01*
G01X197350Y1463841D02*
X197477Y1463868D01*
X197567Y1463941D01*
X197598Y1464037D01*
G01X192292Y1431850D02*
X192265Y1431846D01*
X192239Y1431835D01*
X192215Y1431817D01*
X192194Y1431793D01*
X192177Y1431763D01*
X192164Y1431729D01*
X192156Y1431693D01*
X192154Y1431654D01*
G01X192292Y1435000D02*
X192265Y1434996D01*
X192239Y1434985D01*
X192215Y1434967D01*
X192194Y1434942D01*
X192177Y1434913D01*
X192164Y1434879D01*
X192156Y1434842D01*
X192154Y1434803D01*
G01X192292Y1438150D02*
X192265Y1438146D01*
X192239Y1438135D01*
X192215Y1438117D01*
X192194Y1438092D01*
X192177Y1438062D01*
X192164Y1438028D01*
X192156Y1437992D01*
X192154Y1437953D01*
G01X192292Y1441299D02*
X192265Y1441295D01*
X192239Y1441284D01*
X192215Y1441266D01*
X192194Y1441241D01*
X192177Y1441212D01*
X192164Y1441178D01*
X192156Y1441141D01*
X192154Y1441102D01*
G01X192292Y1444449D02*
X192265Y1444445D01*
X192239Y1444434D01*
X192215Y1444416D01*
X192194Y1444391D01*
X192177Y1444361D01*
X192164Y1444328D01*
X192156Y1444291D01*
X192154Y1444252D01*
G01X192292Y1447598D02*
X192265Y1447594D01*
X192239Y1447583D01*
X192215Y1447565D01*
X192194Y1447541D01*
X192177Y1447511D01*
X192164Y1447477D01*
X192156Y1447441D01*
X192154Y1447402D01*
G01X192292Y1450748D02*
X192265Y1450744D01*
X192239Y1450733D01*
X192215Y1450715D01*
X192194Y1450690D01*
X192177Y1450661D01*
X192164Y1450627D01*
X192156Y1450590D01*
X192154Y1450551D01*
G01X192292Y1453898D02*
X192265Y1453894D01*
X192239Y1453883D01*
X192215Y1453865D01*
X192194Y1453840D01*
X192177Y1453810D01*
X192164Y1453776D01*
X192156Y1453740D01*
X192154Y1453701D01*
G01X192292Y1457047D02*
X192265Y1457043D01*
X192239Y1457032D01*
X192215Y1457014D01*
X192194Y1456989D01*
X192177Y1456960D01*
X192164Y1456926D01*
X192156Y1456889D01*
X192154Y1456850D01*
G01X192292Y1460197D02*
X192265Y1460193D01*
X192239Y1460182D01*
X192215Y1460164D01*
X192194Y1460139D01*
X192177Y1460109D01*
X192164Y1460076D01*
X192156Y1460039D01*
X192154Y1460000D01*
G01X192292Y1463346D02*
X192265Y1463343D01*
X192239Y1463331D01*
X192215Y1463313D01*
X192194Y1463289D01*
X192177Y1463259D01*
X192164Y1463225D01*
X192156Y1463189D01*
X192154Y1463150D01*
G01X197311Y1499665D02*
X197450Y1499861D01*
X197588Y1500058D01*
X197725Y1500256D01*
G01X197311Y1494665D02*
X197450Y1494861D01*
X197588Y1495058D01*
X197725Y1495256D01*
G01X199279Y1489665D02*
X199419Y1489861D01*
X199556Y1490058D01*
X199693Y1490256D01*
G01X191565Y1501240D02*
X191139Y1500650D01*
G01X191565Y1496240D02*
X191139Y1495650D01*
G01X193534Y1491240D02*
X193107Y1490650D01*
G01X191565Y1486240D02*
X191139Y1485650D01*
G01X191983Y1500650D02*
X192255Y1501240D01*
G01X191983Y1495650D02*
X192255Y1496240D01*
G01X193951Y1490650D02*
X194224Y1491240D01*
G01X191983Y1485650D02*
X192255Y1486240D01*
G01X193107Y1500650D02*
X193185Y1501240D01*
G01X193107Y1495650D02*
X193185Y1496240D01*
G01X193107Y1485650D02*
X193185Y1486240D01*
G01X195076Y1490650D02*
X195154Y1491240D01*
G01X190976Y1500945D02*
Y1500551D01*
G01Y1497795D02*
Y1497402D01*
G01Y1494646D02*
Y1494252D01*
G01Y1491496D02*
Y1491102D01*
G01Y1488346D02*
Y1487953D01*
G01X191139Y1495256D02*
Y1495650D01*
G01Y1500256D02*
Y1500650D01*
G01X191983Y1495256D02*
Y1495650D01*
G01Y1500256D02*
Y1500650D01*
G01X192154Y1500945D02*
Y1500551D01*
G01Y1497795D02*
Y1497402D01*
G01Y1494646D02*
Y1494252D01*
G01Y1491496D02*
Y1491102D01*
G01Y1488346D02*
Y1487953D01*
G01X192667D02*
Y1488346D01*
G01Y1491102D02*
Y1491496D01*
G01Y1497402D02*
Y1497795D01*
G01Y1494252D02*
Y1494646D01*
G01Y1500551D02*
Y1500945D01*
G01X193107Y1500650D02*
Y1500256D01*
G01Y1495650D02*
Y1495256D01*
G01Y1490256D02*
Y1490650D01*
G01X193951Y1490256D02*
Y1490650D01*
G01X195076D02*
Y1490256D01*
G01X197588Y1487953D02*
Y1488346D01*
G01Y1491102D02*
Y1491496D01*
G01Y1497402D02*
Y1497795D01*
G01Y1494252D02*
Y1494646D01*
G01Y1500551D02*
Y1500945D01*
G01X197725Y1500650D02*
Y1500256D01*
G01Y1495650D02*
Y1495256D01*
G01X199693Y1490650D02*
Y1490256D01*
G01X192667Y1500945D02*
X192677Y1501043D01*
X192705Y1501115D01*
X192743Y1501142D01*
G01X192667Y1497795D02*
X192677Y1497894D01*
X192705Y1497966D01*
X192743Y1497992D01*
G01X192667Y1494646D02*
X192677Y1494744D01*
X192705Y1494816D01*
X192743Y1494843D01*
G01X192667Y1491496D02*
X192677Y1491594D01*
X192705Y1491667D01*
X192743Y1491693D01*
G01X192667Y1488346D02*
X192677Y1488445D01*
X192705Y1488517D01*
X192743Y1488543D01*
G01X192154Y1487953D02*
X192156Y1487915D01*
X192164Y1487878D01*
X192177Y1487844D01*
X192194Y1487813D01*
X192215Y1487789D01*
X192239Y1487771D01*
X192265Y1487760D01*
X192292Y1487756D01*
G01X192154Y1491102D02*
X192156Y1491064D01*
X192164Y1491027D01*
X192177Y1490993D01*
X192194Y1490963D01*
X192215Y1490939D01*
X192239Y1490920D01*
X192265Y1490909D01*
X192292Y1490906D01*
G01X192154Y1494252D02*
X192156Y1494214D01*
X192164Y1494177D01*
X192177Y1494143D01*
X192194Y1494113D01*
X192215Y1494088D01*
X192239Y1494070D01*
X192265Y1494059D01*
X192292Y1494055D01*
G01X192154Y1497402D02*
X192156Y1497363D01*
X192164Y1497326D01*
X192177Y1497293D01*
X192194Y1497262D01*
X192215Y1497238D01*
X192239Y1497220D01*
X192265Y1497209D01*
X192292Y1497205D01*
G01X192154Y1500551D02*
X192156Y1500513D01*
X192164Y1500476D01*
X192177Y1500442D01*
X192194Y1500412D01*
X192215Y1500387D01*
X192239Y1500369D01*
X192265Y1500358D01*
X192292Y1500354D01*
G01X193107Y1495256D02*
X193185Y1494665D01*
G01X193107Y1500256D02*
X193185Y1499665D01*
G01X195076Y1490256D02*
X195154Y1489665D01*
G01X197588Y1488346D02*
X197556Y1488443D01*
X197468Y1488515D01*
X197341Y1488543D01*
G01X197588Y1491496D02*
X197556Y1491593D01*
X197468Y1491665D01*
X197341Y1491693D01*
G01X194224Y1489665D02*
X193951Y1490256D01*
G01X192255Y1494665D02*
X191983Y1495256D01*
G01X192255Y1499665D02*
X191983Y1500256D01*
G01X197588Y1494646D02*
X197556Y1494743D01*
X197468Y1494815D01*
X197341Y1494843D01*
G01X197588Y1497795D02*
X197556Y1497892D01*
X197468Y1497964D01*
X197341Y1497992D01*
G01X197588Y1500945D02*
X197556Y1501042D01*
X197468Y1501114D01*
X197341Y1501142D01*
G01X193534Y1489665D02*
X193107Y1490256D01*
G01X191565Y1494665D02*
X191139Y1495256D01*
G01X191565Y1499665D02*
X191139Y1500256D01*
G01X197725Y1485650D02*
X197588Y1485847D01*
X197450Y1486044D01*
X197311Y1486240D01*
G01X199693Y1490650D02*
X199556Y1490847D01*
X199419Y1491044D01*
X199279Y1491240D01*
G01X197725Y1495650D02*
X197588Y1495847D01*
X197450Y1496044D01*
X197311Y1496240D01*
G01X197725Y1500650D02*
X197588Y1500847D01*
X197450Y1501044D01*
X197311Y1501240D01*
G01X192743Y1487756D02*
X192705Y1487782D01*
X192677Y1487854D01*
X192667Y1487953D01*
G01X192743Y1490906D02*
X192705Y1490932D01*
X192677Y1491004D01*
X192667Y1491102D01*
G01X192743Y1494055D02*
X192705Y1494081D01*
X192677Y1494154D01*
X192667Y1494252D01*
G01X192743Y1497205D02*
X192705Y1497231D01*
X192677Y1497303D01*
X192667Y1497402D01*
G01X192743Y1500354D02*
X192705Y1500381D01*
X192677Y1500453D01*
X192667Y1500551D01*
G01X192292Y1488543D02*
X192265Y1488539D01*
X192239Y1488528D01*
X192215Y1488510D01*
X192194Y1488485D01*
X192177Y1488456D01*
X192164Y1488422D01*
X192156Y1488385D01*
X192154Y1488346D01*
G01X192292Y1491693D02*
X192265Y1491689D01*
X192239Y1491678D01*
X192215Y1491660D01*
X192194Y1491635D01*
X192177Y1491606D01*
X192164Y1491572D01*
X192156Y1491535D01*
X192154Y1491496D01*
G01X192292Y1494843D02*
X192265Y1494839D01*
X192239Y1494828D01*
X192215Y1494809D01*
X192194Y1494785D01*
X192177Y1494755D01*
X192164Y1494721D01*
X192156Y1494685D01*
X192154Y1494646D01*
G01X192292Y1497992D02*
X192265Y1497988D01*
X192239Y1497977D01*
X192215Y1497959D01*
X192194Y1497934D01*
X192177Y1497905D01*
X192164Y1497871D01*
X192156Y1497834D01*
X192154Y1497795D01*
G01X192292Y1501142D02*
X192265Y1501138D01*
X192239Y1501127D01*
X192215Y1501109D01*
X192194Y1501084D01*
X192177Y1501054D01*
X192164Y1501020D01*
X192156Y1500984D01*
X192154Y1500945D01*
G01X197341Y1485394D02*
X191256D01*
G01X191139Y1485650D02*
X197725D01*
G01X197311Y1486240D02*
X191565D01*
G01X197341Y1487756D02*
X191256D01*
G01X197588Y1487953D02*
X190976D01*
G01Y1488346D02*
X197588D01*
G01X197341Y1488543D02*
X191256D01*
G01X199279Y1489665D02*
X193534D01*
G01X193107Y1490256D02*
X199693D01*
G01X193107Y1490650D02*
X199693D01*
G01X197341Y1490906D02*
X191256D01*
G01X197588Y1491102D02*
X190976D01*
G01X199279Y1491240D02*
X193534D01*
G01X190976Y1491496D02*
X197588D01*
G01X197341Y1491693D02*
X191256D01*
G01X197341Y1494055D02*
X191256D01*
G01X197588Y1494252D02*
X190976D01*
G01Y1494646D02*
X197588D01*
G01X197311Y1494665D02*
X191565D01*
G01X197341Y1494843D02*
X191256D01*
G01X191139Y1495256D02*
X197725D01*
G01X191139Y1495650D02*
X197725D01*
G01X197311Y1496240D02*
X191565D01*
G01X197341Y1497205D02*
X191256D01*
G01X197588Y1497402D02*
X190976D01*
G01Y1497795D02*
X197588D01*
G01X197341Y1497992D02*
X191256D01*
G01X197311Y1499665D02*
X191565D01*
G01X191139Y1500256D02*
X197725D01*
G01X197341Y1500354D02*
X191256D01*
G01X197588Y1500551D02*
X190976D01*
G01X191139Y1500650D02*
X197725D01*
G01X190976Y1500945D02*
X197588D01*
G01X197341Y1501142D02*
X191256D01*
G01X197311Y1501240D02*
X191565D01*
G01X197341Y1487756D02*
X197468Y1487783D01*
X197557Y1487856D01*
X197588Y1487953D01*
G01X197341Y1490906D02*
X197468Y1490933D01*
X197557Y1491006D01*
X197588Y1491102D01*
G01X197341Y1494055D02*
X197468Y1494083D01*
X197557Y1494156D01*
X197588Y1494252D01*
G01X197341Y1497205D02*
X197468Y1497232D01*
X197557Y1497305D01*
X197588Y1497402D01*
G01X197341Y1500354D02*
X197468Y1500382D01*
X197557Y1500455D01*
X197588Y1500551D01*
G01X197410Y1474665D02*
X197546Y1474861D01*
X197681Y1475058D01*
X197816Y1475256D01*
G01X197311Y1484665D02*
X197450Y1484861D01*
X197588Y1485058D01*
X197725Y1485256D01*
G01X197311Y1479665D02*
X197450Y1479861D01*
X197588Y1480058D01*
X197725Y1480256D01*
G01X191497Y1476240D02*
X191074Y1475650D01*
G01X191565Y1481240D02*
X191139Y1480650D01*
G01X201575Y1474685D02*
X199606Y1472717D01*
G01X192743Y1466496D02*
X192705Y1466470D01*
X192677Y1466397D01*
X192667Y1466299D01*
G01X191983Y1480650D02*
X192255Y1481240D01*
G01X191983Y1475650D02*
X192255Y1476240D01*
G01X193107Y1480650D02*
X193185Y1481240D01*
G01X193107Y1475650D02*
X193185Y1476240D01*
G01X190976Y1485197D02*
Y1484803D01*
G01Y1482047D02*
Y1481654D01*
G01Y1478898D02*
Y1478504D01*
G01Y1475748D02*
Y1475354D01*
G01Y1472598D02*
Y1472205D01*
G01Y1469449D02*
Y1469055D01*
G01Y1466299D02*
Y1465906D01*
G01X191074Y1475256D02*
Y1475650D01*
G01X191139Y1480256D02*
Y1480650D01*
G01Y1485256D02*
Y1485650D01*
G01X191280Y1467187D02*
Y1468171D01*
G01Y1470337D02*
Y1471321D01*
G01X191983Y1475256D02*
Y1475650D01*
G01Y1480256D02*
Y1480650D01*
G01Y1485256D02*
Y1485650D01*
G01X192154Y1485197D02*
Y1484803D01*
G01Y1482047D02*
Y1481654D01*
G01Y1478898D02*
Y1478504D01*
G01Y1475748D02*
Y1475354D01*
G01Y1472598D02*
Y1472205D01*
G01Y1469449D02*
Y1469055D01*
G01Y1466299D02*
Y1465906D01*
G01X192222Y1467187D02*
Y1468171D01*
G01Y1470337D02*
Y1471321D01*
G01X192667Y1469055D02*
Y1469449D01*
G01Y1465906D02*
Y1466299D01*
G01Y1472205D02*
Y1472598D01*
G01Y1478504D02*
Y1478898D01*
G01Y1475354D02*
Y1475748D01*
G01Y1481654D02*
Y1482047D01*
G01Y1484803D02*
Y1485197D01*
G01X193107Y1485650D02*
Y1485256D01*
G01Y1480650D02*
Y1480256D01*
G01Y1475650D02*
Y1475256D01*
G01X193374Y1467187D02*
Y1468171D01*
G01Y1470337D02*
Y1471321D01*
G01X195106Y1473878D02*
Y1472697D01*
G01X197588Y1469055D02*
Y1469449D01*
G01Y1465906D02*
Y1466299D01*
G01Y1472205D02*
Y1472598D01*
G01Y1478504D02*
Y1478898D01*
G01Y1475354D02*
Y1475748D01*
G01Y1481654D02*
Y1482047D01*
G01Y1484803D02*
Y1485197D01*
G01X197598Y1471321D02*
Y1470337D01*
G01Y1468171D02*
Y1467187D01*
G01X197725Y1485650D02*
Y1485256D01*
G01Y1480650D02*
Y1480256D01*
G01X197816Y1475650D02*
Y1475256D01*
G01X200394Y1550059D02*
Y1479154D01*
G01X200563D02*
Y1473674D01*
G01X193374Y1471321D02*
X193375Y1471359D01*
X193376Y1471396D01*
X193380Y1471430D01*
X193383Y1471460D01*
X193389Y1471485D01*
X193394Y1471503D01*
X193400Y1471514D01*
X193407Y1471518D01*
G01X193374Y1468171D02*
X193375Y1468209D01*
X193376Y1468246D01*
X193380Y1468280D01*
X193383Y1468311D01*
X193389Y1468335D01*
X193394Y1468353D01*
X193400Y1468364D01*
X193407Y1468368D01*
G01X192222Y1471321D02*
X192225Y1471359D01*
X192233Y1471396D01*
X192247Y1471430D01*
X192265Y1471460D01*
X192288Y1471485D01*
X192313Y1471503D01*
X192341Y1471514D01*
X192370Y1471518D01*
G01X192222Y1468171D02*
X192225Y1468209D01*
X192233Y1468246D01*
X192247Y1468280D01*
X192265Y1468311D01*
X192288Y1468335D01*
X192313Y1468353D01*
X192341Y1468364D01*
X192370Y1468368D01*
G01X192667Y1485197D02*
X192677Y1485295D01*
X192705Y1485367D01*
X192743Y1485394D01*
G01X192667Y1482047D02*
X192677Y1482146D01*
X192705Y1482218D01*
X192743Y1482244D01*
G01X192667Y1478898D02*
X192677Y1478996D01*
X192705Y1479068D01*
X192743Y1479094D01*
G01X192667Y1475748D02*
X192677Y1475846D01*
X192705Y1475919D01*
X192743Y1475945D01*
G01X192667Y1472598D02*
X192677Y1472697D01*
X192705Y1472769D01*
X192743Y1472795D01*
G01X192667Y1469449D02*
X192677Y1469547D01*
X192705Y1469619D01*
X192743Y1469646D01*
G01X192154Y1465906D02*
X192156Y1465867D01*
X192164Y1465830D01*
X192177Y1465796D01*
X192194Y1465766D01*
X192215Y1465742D01*
X192239Y1465724D01*
X192265Y1465713D01*
X192292Y1465709D01*
G01X192154Y1469055D02*
X192156Y1469017D01*
X192164Y1468980D01*
X192177Y1468946D01*
X192194Y1468916D01*
X192215Y1468891D01*
X192239Y1468873D01*
X192265Y1468862D01*
X192292Y1468858D01*
G01X192154Y1472205D02*
X192156Y1472167D01*
X192164Y1472130D01*
X192177Y1472096D01*
X192194Y1472065D01*
X192215Y1472041D01*
X192239Y1472023D01*
X192265Y1472012D01*
X192292Y1472008D01*
G01X192154Y1475354D02*
X192156Y1475316D01*
X192164Y1475279D01*
X192177Y1475245D01*
X192194Y1475215D01*
X192215Y1475191D01*
X192239Y1475172D01*
X192265Y1475161D01*
X192292Y1475157D01*
G01X192154Y1478504D02*
X192156Y1478466D01*
X192164Y1478429D01*
X192177Y1478395D01*
X192194Y1478365D01*
X192215Y1478340D01*
X192239Y1478322D01*
X192265Y1478311D01*
X192292Y1478307D01*
G01X192154Y1481654D02*
X192156Y1481615D01*
X192164Y1481578D01*
X192177Y1481544D01*
X192194Y1481514D01*
X192215Y1481490D01*
X192239Y1481472D01*
X192265Y1481461D01*
X192292Y1481457D01*
G01X192154Y1484803D02*
X192156Y1484765D01*
X192164Y1484728D01*
X192177Y1484694D01*
X192194Y1484664D01*
X192215Y1484639D01*
X192239Y1484621D01*
X192265Y1484610D01*
X192292Y1484606D01*
G01X193107Y1475256D02*
X193185Y1474665D01*
G01X193107Y1480256D02*
X193185Y1479665D01*
G01X193107Y1485256D02*
X193185Y1484665D01*
G01X197598Y1468171D02*
X197565Y1468270D01*
X197476Y1468341D01*
X197350Y1468368D01*
G01X197598Y1471321D02*
X197565Y1471420D01*
X197476Y1471491D01*
X197350Y1471518D01*
G01X197588Y1466299D02*
X197556Y1466396D01*
X197468Y1466468D01*
X197341Y1466496D01*
G01X197588Y1469449D02*
X197556Y1469546D01*
X197468Y1469618D01*
X197341Y1469646D01*
G01X197588Y1472598D02*
X197556Y1472695D01*
X197468Y1472767D01*
X197341Y1472795D01*
G01X197588Y1475748D02*
X197556Y1475845D01*
X197468Y1475917D01*
X197341Y1475945D01*
G01X197588Y1478898D02*
X197556Y1478994D01*
X197468Y1479067D01*
X197341Y1479094D01*
G01X197588Y1482047D02*
X197556Y1482144D01*
X197468Y1482216D01*
X197341Y1482244D01*
G01X197588Y1485197D02*
X197556Y1485294D01*
X197468Y1485366D01*
X197341Y1485394D01*
G01X192255Y1474665D02*
X191983Y1475256D01*
G01X192255Y1479665D02*
X191983Y1480256D01*
G01X192255Y1484665D02*
X191983Y1485256D01*
G01X191565Y1479665D02*
X191139Y1480256D01*
G01X191565Y1484665D02*
X191139Y1485256D01*
G01X191497Y1474665D02*
X191074Y1475256D01*
G01X197725Y1480650D02*
X197588Y1480847D01*
X197450Y1481044D01*
X197311Y1481240D01*
G01X197816Y1475650D02*
X197681Y1475847D01*
X197546Y1476044D01*
X197410Y1476240D01*
G01X192743Y1465709D02*
X192705Y1465735D01*
X192677Y1465807D01*
X192667Y1465906D01*
G01X192743Y1468858D02*
X192705Y1468885D01*
X192677Y1468957D01*
X192667Y1469055D01*
G01X192743Y1472008D02*
X192705Y1472034D01*
X192677Y1472106D01*
X192667Y1472205D01*
G01X192743Y1475157D02*
X192705Y1475184D01*
X192677Y1475256D01*
X192667Y1475354D01*
G01X192743Y1478307D02*
X192705Y1478333D01*
X192677Y1478406D01*
X192667Y1478504D01*
G01X192743Y1481457D02*
X192705Y1481483D01*
X192677Y1481555D01*
X192667Y1481654D01*
G01X192743Y1484606D02*
X192705Y1484633D01*
X192677Y1484705D01*
X192667Y1484803D01*
G01X193407Y1466990D02*
X193400Y1466994D01*
X193394Y1467005D01*
X193389Y1467023D01*
X193383Y1467048D01*
X193380Y1467078D01*
X193376Y1467111D01*
X193375Y1467148D01*
X193374Y1467187D01*
G01X193407Y1470140D02*
X193400Y1470144D01*
X193394Y1470155D01*
X193389Y1470173D01*
X193383Y1470198D01*
X193380Y1470227D01*
X193376Y1470261D01*
X193375Y1470298D01*
X193374Y1470337D01*
G01X197341Y1465709D02*
X191256D01*
G01X197588Y1465906D02*
X190976D01*
G01X192370Y1466990D02*
X192341Y1466994D01*
X192313Y1467005D01*
X192288Y1467023D01*
X192265Y1467048D01*
X192247Y1467078D01*
X192233Y1467111D01*
X192225Y1467148D01*
X192222Y1467187D01*
G01X192370Y1470140D02*
X192341Y1470144D01*
X192313Y1470155D01*
X192288Y1470173D01*
X192265Y1470198D01*
X192247Y1470227D01*
X192233Y1470261D01*
X192225Y1470298D01*
X192222Y1470337D01*
G01X197341Y1465709D02*
X197468Y1465736D01*
X197557Y1465809D01*
X197588Y1465906D01*
G01X197341Y1468858D02*
X197468Y1468886D01*
X197557Y1468959D01*
X197588Y1469055D01*
G01X197341Y1472008D02*
X197468Y1472035D01*
X197557Y1472108D01*
X197588Y1472205D01*
G01X197341Y1475157D02*
X197468Y1475185D01*
X197557Y1475258D01*
X197588Y1475354D01*
G01X197341Y1478307D02*
X197468Y1478335D01*
X197557Y1478407D01*
X197588Y1478504D01*
G01X197341Y1481457D02*
X197468Y1481484D01*
X197557Y1481557D01*
X197588Y1481654D01*
G01X197341Y1484606D02*
X197468Y1484634D01*
X197557Y1484707D01*
X197588Y1484803D01*
G01X197350Y1466990D02*
X197477Y1467018D01*
X197567Y1467090D01*
X197598Y1467187D01*
G01X197350Y1470140D02*
X197477Y1470167D01*
X197567Y1470240D01*
X197598Y1470337D01*
G01X192292Y1466496D02*
X192265Y1466492D01*
X192239Y1466481D01*
X192215Y1466463D01*
X192194Y1466438D01*
X192177Y1466409D01*
X192164Y1466375D01*
X192156Y1466338D01*
X192154Y1466299D01*
G01X192292Y1469646D02*
X192265Y1469642D01*
X192239Y1469631D01*
X192215Y1469613D01*
X192194Y1469588D01*
X192177Y1469558D01*
X192164Y1469524D01*
X192156Y1469488D01*
X192154Y1469449D01*
G01X192292Y1472795D02*
X192265Y1472791D01*
X192239Y1472780D01*
X192215Y1472762D01*
X192194Y1472737D01*
X192177Y1472708D01*
X192164Y1472674D01*
X192156Y1472637D01*
X192154Y1472598D01*
G01X192292Y1475945D02*
X192265Y1475941D01*
X192239Y1475930D01*
X192215Y1475912D01*
X192194Y1475887D01*
X192177Y1475857D01*
X192164Y1475824D01*
X192156Y1475787D01*
X192154Y1475748D01*
G01X192292Y1479094D02*
X192265Y1479091D01*
X192239Y1479080D01*
X192215Y1479061D01*
X192194Y1479037D01*
X192177Y1479007D01*
X192164Y1478973D01*
X192156Y1478937D01*
X192154Y1478898D01*
G01X192292Y1482244D02*
X192265Y1482240D01*
X192239Y1482229D01*
X192215Y1482211D01*
X192194Y1482186D01*
X192177Y1482157D01*
X192164Y1482123D01*
X192156Y1482086D01*
X192154Y1482047D01*
G01X192292Y1485394D02*
X192265Y1485390D01*
X192239Y1485379D01*
X192215Y1485361D01*
X192194Y1485336D01*
X192177Y1485306D01*
X192164Y1485272D01*
X192156Y1485236D01*
X192154Y1485197D01*
G01X190976Y1466299D02*
X197588D01*
G01X197341Y1466496D02*
X191256D01*
G01X191542Y1466990D02*
X197350D01*
G01X191280Y1467187D02*
X197598D01*
G01Y1468171D02*
X191280D01*
G01X191542Y1468368D02*
X197350D01*
G01X197341Y1468858D02*
X191256D01*
G01X197588Y1469055D02*
X190976D01*
G01Y1469449D02*
X197588D01*
G01X197341Y1469646D02*
X191256D01*
G01X191542Y1470140D02*
X197350D01*
G01X191280Y1470337D02*
X197598D01*
G01Y1471321D02*
X191280D01*
G01X191542Y1471518D02*
X197350D01*
G01X197341Y1472008D02*
X191256D01*
G01X197588Y1472205D02*
X190976D01*
G01Y1472598D02*
X197588D01*
G01X197341Y1472795D02*
X191256D01*
G01X195106Y1473878D02*
X201575D01*
G01X197410Y1474665D02*
X191497D01*
G01X197341Y1475157D02*
X191256D01*
G01X191074Y1475256D02*
X197816D01*
G01X197588Y1475354D02*
X190976D01*
G01X191074Y1475650D02*
X197816D01*
G01X190976Y1475748D02*
X197588D01*
G01X197341Y1475945D02*
X191256D01*
G01X197410Y1476240D02*
X191497D01*
G01X197341Y1478307D02*
X191256D01*
G01X197588Y1478504D02*
X190976D01*
G01Y1478898D02*
X197588D01*
G01X197341Y1479094D02*
X191256D01*
G01X197311Y1479665D02*
X191565D01*
G01X191139Y1480256D02*
X197725D01*
G01X191139Y1480650D02*
X197725D01*
G01X197311Y1481240D02*
X191565D01*
G01X197341Y1481457D02*
X191256D01*
G01X197588Y1481654D02*
X190976D01*
G01Y1482047D02*
X197588D01*
G01X197341Y1482244D02*
X191256D01*
G01X197341Y1484606D02*
X191256D01*
G01X197311Y1484665D02*
X191565D01*
G01X197588Y1484803D02*
X190976D01*
G01Y1485197D02*
X197588D01*
G01X191139Y1485256D02*
X197725D01*
G01X199606Y1549272D02*
X201575Y1551240D01*
G01X204858Y1554193D02*
X208268Y1556161D01*
G01X191565Y1546240D02*
X191139Y1545650D01*
G01X191983D02*
X192255Y1546240D01*
G01X193107Y1545650D02*
X193185Y1546240D01*
G01X203601Y1561809D02*
X203547Y1561432D01*
G01X203543Y1554193D02*
Y1561358D01*
G01X208268Y1556161D02*
Y1557894D01*
G01X203601Y1561807D02*
X203637Y1562131D01*
X203631Y1562372D01*
X203575Y1562508D01*
G01D02*
X203632Y1562368D01*
X203637Y1562128D01*
G01X197725Y1545650D02*
X197588Y1545847D01*
X197450Y1546044D01*
X197311Y1546240D01*
G01X203547Y1561432D02*
X208268Y1556790D01*
G01Y1557894D02*
X203543Y1562539D01*
G01X199606Y1554193D02*
X201575Y1552224D01*
G01X191139Y1545650D02*
X197725D01*
G01X197311Y1546240D02*
X191565D01*
G01X204858Y1554193D02*
X201575D01*
G01X197311Y1544665D02*
X197450Y1544861D01*
X197588Y1545058D01*
X197725Y1545256D01*
G01X197311Y1539665D02*
X197450Y1539861D01*
X197588Y1540058D01*
X197725Y1540256D01*
G01X197311Y1534665D02*
X197450Y1534861D01*
X197588Y1535058D01*
X197725Y1535256D01*
G01X199279Y1529665D02*
X199419Y1529861D01*
X199556Y1530058D01*
X199693Y1530256D01*
G01X197311Y1524665D02*
X197450Y1524861D01*
X197588Y1525058D01*
X197725Y1525256D01*
G01X197311Y1519665D02*
X197450Y1519861D01*
X197588Y1520058D01*
X197725Y1520256D01*
G01X197311Y1514665D02*
X197450Y1514861D01*
X197588Y1515058D01*
X197725Y1515256D01*
G01X197311Y1509665D02*
X197450Y1509861D01*
X197588Y1510058D01*
X197725Y1510256D01*
G01X197311Y1504665D02*
X197450Y1504861D01*
X197588Y1505058D01*
X197725Y1505256D01*
G01X191565Y1541240D02*
X191139Y1540650D01*
G01X191565Y1536240D02*
X191139Y1535650D01*
G01X193534Y1531240D02*
X193107Y1530650D01*
G01X191565Y1526240D02*
X191139Y1525650D01*
G01X191565Y1521240D02*
X191139Y1520650D01*
G01X191565Y1516240D02*
X191139Y1515650D01*
G01X191565Y1511240D02*
X191139Y1510650D01*
G01X191565Y1506240D02*
X191139Y1505650D01*
G01X197588Y1532047D02*
X197555Y1531948D01*
X197467Y1531877D01*
X197341Y1531850D01*
G01X197588Y1503701D02*
X197555Y1503602D01*
X197467Y1503531D01*
X197341Y1503504D01*
G01X191983Y1540650D02*
X192255Y1541240D01*
G01X191983Y1535650D02*
X192255Y1536240D01*
G01X193951Y1530650D02*
X194224Y1531240D01*
G01X191983Y1525650D02*
X192255Y1526240D01*
G01X191983Y1520650D02*
X192255Y1521240D01*
G01X191983Y1515650D02*
X192255Y1516240D01*
G01X191983Y1510650D02*
X192255Y1511240D01*
G01X191983Y1505650D02*
X192255Y1506240D01*
G01X193185Y1541240D02*
X193107Y1540650D01*
G01Y1535650D02*
X193185Y1536240D01*
G01X193107Y1525650D02*
X193185Y1526240D01*
G01X193107Y1520650D02*
X193185Y1521240D01*
G01X195076Y1530650D02*
X195154Y1531240D01*
G01X193107Y1515650D02*
X193185Y1516240D01*
G01X193107Y1510650D02*
X193185Y1511240D01*
G01X193107Y1505650D02*
X193185Y1506240D01*
G01X190976Y1545039D02*
Y1544646D01*
G01Y1541890D02*
Y1541496D01*
G01Y1538740D02*
Y1538346D01*
G01Y1532441D02*
Y1532047D01*
G01Y1535591D02*
Y1535197D01*
G01Y1529291D02*
Y1528898D01*
G01Y1522992D02*
Y1522598D01*
G01Y1526142D02*
Y1525748D01*
G01Y1519843D02*
Y1519449D01*
G01Y1513543D02*
Y1513150D01*
G01Y1516693D02*
Y1516299D01*
G01Y1510394D02*
Y1510000D01*
G01Y1507244D02*
Y1506850D01*
G01Y1504094D02*
Y1503701D01*
G01X191139Y1505256D02*
Y1505650D01*
G01Y1510256D02*
Y1510650D01*
G01Y1515256D02*
Y1515650D01*
G01Y1520256D02*
Y1520650D01*
G01Y1525256D02*
Y1525650D01*
G01Y1535256D02*
Y1535650D01*
G01Y1540256D02*
Y1540650D01*
G01Y1545256D02*
Y1545650D01*
G01X191983Y1505256D02*
Y1505650D01*
G01Y1510256D02*
Y1510650D01*
G01Y1515256D02*
Y1515650D01*
G01Y1520256D02*
Y1520650D01*
G01Y1525256D02*
Y1525650D01*
G01Y1535256D02*
Y1535650D01*
G01Y1540256D02*
Y1540650D01*
G01Y1545256D02*
Y1545650D01*
G01X192154Y1545039D02*
Y1544646D01*
G01Y1541890D02*
Y1541496D01*
G01Y1538740D02*
Y1538346D01*
G01Y1532441D02*
Y1532047D01*
G01Y1535591D02*
Y1535197D01*
G01Y1529291D02*
Y1528898D01*
G01Y1522992D02*
Y1522598D01*
G01Y1526142D02*
Y1525748D01*
G01Y1519843D02*
Y1519449D01*
G01Y1513543D02*
Y1513150D01*
G01Y1516693D02*
Y1516299D01*
G01Y1510394D02*
Y1510000D01*
G01Y1507244D02*
Y1506850D01*
G01Y1504094D02*
Y1503701D01*
G01X192667Y1506850D02*
Y1507244D01*
G01Y1503701D02*
Y1504094D01*
G01Y1510000D02*
Y1510394D01*
G01Y1513150D02*
Y1513543D01*
G01Y1516299D02*
Y1516693D01*
G01Y1519449D02*
Y1519843D01*
G01Y1522598D02*
Y1522992D01*
G01Y1525748D02*
Y1526142D01*
G01Y1528898D02*
Y1529291D01*
G01Y1532047D02*
Y1532441D01*
G01Y1535197D02*
Y1535591D01*
G01Y1538346D02*
Y1538740D01*
G01Y1544646D02*
Y1545039D01*
G01Y1541496D02*
Y1541890D01*
G01X193107Y1545650D02*
Y1545256D01*
G01Y1535650D02*
Y1535256D01*
G01Y1525650D02*
Y1525256D01*
G01Y1520650D02*
Y1520256D01*
G01Y1515650D02*
Y1515256D01*
G01Y1510650D02*
Y1510256D01*
G01Y1505650D02*
Y1505256D01*
G01Y1540256D02*
Y1540650D01*
G01Y1530256D02*
Y1530650D01*
G01X193951Y1530256D02*
Y1530650D01*
G01X195076D02*
Y1530256D01*
G01X197588Y1506850D02*
Y1507244D01*
G01Y1503701D02*
Y1504094D01*
G01Y1510000D02*
Y1510394D01*
G01Y1513150D02*
Y1513543D01*
G01Y1516299D02*
Y1516693D01*
G01Y1519449D02*
Y1519843D01*
G01Y1522598D02*
Y1522992D01*
G01Y1525748D02*
Y1526142D01*
G01Y1528898D02*
Y1529291D01*
G01Y1532047D02*
Y1532441D01*
G01Y1535197D02*
Y1535591D01*
G01Y1538346D02*
Y1538740D01*
G01Y1544646D02*
Y1545039D01*
G01Y1541496D02*
Y1541890D01*
G01X197725Y1545650D02*
Y1545256D01*
G01Y1540650D02*
Y1540256D01*
G01Y1535650D02*
Y1535256D01*
G01Y1525650D02*
Y1525256D01*
G01Y1520650D02*
Y1520256D01*
G01Y1515650D02*
Y1515256D01*
G01Y1510650D02*
Y1510256D01*
G01Y1505650D02*
Y1505256D01*
G01X199693Y1530650D02*
Y1530256D01*
G01X192667Y1545039D02*
X192677Y1545138D01*
X192705Y1545210D01*
X192743Y1545236D01*
G01X192667Y1541890D02*
X192677Y1541988D01*
X192705Y1542060D01*
X192743Y1542087D01*
G01X192667Y1538740D02*
X192677Y1538839D01*
X192705Y1538911D01*
X192743Y1538937D01*
G01X192667Y1535591D02*
X192677Y1535689D01*
X192705Y1535761D01*
X192743Y1535787D01*
G01X192667Y1532441D02*
X192677Y1532539D01*
X192705Y1532611D01*
X192743Y1532638D01*
G01X192667Y1529291D02*
X192677Y1529390D01*
X192705Y1529462D01*
X192743Y1529488D01*
G01X192667Y1526142D02*
X192677Y1526240D01*
X192705Y1526312D01*
X192743Y1526339D01*
G01X192667Y1522992D02*
X192677Y1523091D01*
X192705Y1523163D01*
X192743Y1523189D01*
G01X192667Y1519843D02*
X192677Y1519941D01*
X192705Y1520013D01*
X192743Y1520039D01*
G01X192667Y1516693D02*
X192677Y1516791D01*
X192705Y1516863D01*
X192743Y1516890D01*
G01X192667Y1513543D02*
X192677Y1513642D01*
X192705Y1513714D01*
X192743Y1513740D01*
G01X192667Y1510394D02*
X192677Y1510492D01*
X192705Y1510564D01*
X192743Y1510591D01*
G01X192667Y1507244D02*
X192677Y1507343D01*
X192705Y1507415D01*
X192743Y1507441D01*
G01X192667Y1504094D02*
X192677Y1504193D01*
X192705Y1504265D01*
X192743Y1504291D01*
G01X192154Y1503701D02*
X192156Y1503663D01*
X192164Y1503626D01*
X192177Y1503592D01*
X192194Y1503561D01*
X192215Y1503537D01*
X192239Y1503519D01*
X192265Y1503508D01*
X192292Y1503504D01*
G01X192154Y1506850D02*
X192156Y1506812D01*
X192164Y1506775D01*
X192177Y1506741D01*
X192194Y1506711D01*
X192215Y1506687D01*
X192239Y1506669D01*
X192265Y1506657D01*
X192292Y1506654D01*
G01X192154Y1510000D02*
X192156Y1509962D01*
X192164Y1509925D01*
X192177Y1509891D01*
X192194Y1509861D01*
X192215Y1509836D01*
X192239Y1509818D01*
X192265Y1509807D01*
X192292Y1509803D01*
G01X192154Y1513150D02*
X192156Y1513111D01*
X192164Y1513074D01*
X192177Y1513041D01*
X192194Y1513010D01*
X192215Y1512986D01*
X192239Y1512968D01*
X192265Y1512957D01*
X192292Y1512953D01*
G01X192154Y1516299D02*
X192156Y1516261D01*
X192164Y1516224D01*
X192177Y1516190D01*
X192194Y1516160D01*
X192215Y1516135D01*
X192239Y1516117D01*
X192265Y1516106D01*
X192292Y1516102D01*
G01X192154Y1519449D02*
X192156Y1519411D01*
X192164Y1519374D01*
X192177Y1519340D01*
X192194Y1519309D01*
X192215Y1519285D01*
X192239Y1519267D01*
X192265Y1519256D01*
X192292Y1519252D01*
G01X192154Y1522598D02*
X192156Y1522560D01*
X192164Y1522523D01*
X192177Y1522489D01*
X192194Y1522459D01*
X192215Y1522435D01*
X192239Y1522417D01*
X192265Y1522406D01*
X192292Y1522402D01*
G01X192154Y1525748D02*
X192156Y1525710D01*
X192164Y1525673D01*
X192177Y1525639D01*
X192194Y1525609D01*
X192215Y1525584D01*
X192239Y1525566D01*
X192265Y1525555D01*
X192292Y1525551D01*
G01X192154Y1528898D02*
X192156Y1528859D01*
X192164Y1528822D01*
X192177Y1528789D01*
X192194Y1528758D01*
X192215Y1528734D01*
X192239Y1528716D01*
X192265Y1528705D01*
X192292Y1528701D01*
G01X192154Y1532047D02*
X192156Y1532009D01*
X192164Y1531972D01*
X192177Y1531938D01*
X192194Y1531908D01*
X192215Y1531883D01*
X192239Y1531865D01*
X192265Y1531854D01*
X192292Y1531850D01*
G01X192154Y1535197D02*
X192156Y1535159D01*
X192164Y1535122D01*
X192177Y1535088D01*
X192194Y1535057D01*
X192215Y1535033D01*
X192239Y1535015D01*
X192265Y1535004D01*
X192292Y1535000D01*
G01X192154Y1538346D02*
X192156Y1538308D01*
X192164Y1538271D01*
X192177Y1538237D01*
X192194Y1538207D01*
X192215Y1538183D01*
X192239Y1538165D01*
X192265Y1538154D01*
X192292Y1538150D01*
G01X192154Y1541496D02*
X192156Y1541458D01*
X192164Y1541421D01*
X192177Y1541387D01*
X192194Y1541357D01*
X192215Y1541332D01*
X192239Y1541314D01*
X192265Y1541303D01*
X192292Y1541299D01*
G01X192154Y1544646D02*
X192156Y1544607D01*
X192164Y1544570D01*
X192177Y1544537D01*
X192194Y1544506D01*
X192215Y1544482D01*
X192239Y1544464D01*
X192265Y1544453D01*
X192292Y1544449D01*
G01X193107Y1505256D02*
X193185Y1504665D01*
G01X193107Y1510256D02*
X193185Y1509665D01*
G01X193107Y1515256D02*
X193185Y1514665D01*
G01X193107Y1520256D02*
X193185Y1519665D01*
G01X193107Y1525256D02*
X193185Y1524665D01*
G01X193107Y1535256D02*
X193185Y1534665D01*
G01Y1539665D02*
X193107Y1540256D01*
G01X195076Y1530256D02*
X195154Y1529665D01*
G01X193107Y1545256D02*
X193185Y1544665D01*
G01X192255Y1504665D02*
X191983Y1505256D01*
G01X192255Y1509665D02*
X191983Y1510256D01*
G01X192255Y1514665D02*
X191983Y1515256D01*
G01X192255Y1519665D02*
X191983Y1520256D01*
G01X192255Y1524665D02*
X191983Y1525256D01*
G01X197588Y1507244D02*
X197556Y1507341D01*
X197468Y1507413D01*
X197341Y1507441D01*
G01X197588Y1510394D02*
X197556Y1510491D01*
X197468Y1510563D01*
X197341Y1510591D01*
G01X197588Y1513543D02*
X197556Y1513640D01*
X197468Y1513712D01*
X197341Y1513740D01*
G01X197588Y1516693D02*
X197556Y1516790D01*
X197468Y1516862D01*
X197341Y1516890D01*
G01X197588Y1519843D02*
X197556Y1519939D01*
X197468Y1520011D01*
X197341Y1520039D01*
G01X197588Y1522992D02*
X197556Y1523089D01*
X197468Y1523161D01*
X197341Y1523189D01*
G01X197588Y1526142D02*
X197556Y1526239D01*
X197468Y1526311D01*
X197341Y1526339D01*
G01X197588Y1529291D02*
X197556Y1529388D01*
X197468Y1529460D01*
X197341Y1529488D01*
G01X197588Y1535591D02*
X197556Y1535687D01*
X197468Y1535759D01*
X197341Y1535787D01*
G01X197588Y1538740D02*
X197556Y1538837D01*
X197468Y1538909D01*
X197341Y1538937D01*
G01X197588Y1541890D02*
X197556Y1541987D01*
X197468Y1542059D01*
X197341Y1542087D01*
G01X197588Y1545039D02*
X197556Y1545136D01*
X197468Y1545208D01*
X197341Y1545236D01*
G01X194224Y1529665D02*
X193951Y1530256D01*
G01X192255Y1534665D02*
X191983Y1535256D01*
G01X192255Y1539665D02*
X191983Y1540256D01*
G01X192255Y1544665D02*
X191983Y1545256D01*
G01X191565Y1504665D02*
X191139Y1505256D01*
G01X191565Y1509665D02*
X191139Y1510256D01*
G01X191565Y1514665D02*
X191139Y1515256D01*
G01X191565Y1519665D02*
X191139Y1520256D01*
G01X191565Y1524665D02*
X191139Y1525256D01*
G01X193534Y1529665D02*
X193107Y1530256D01*
G01X191565Y1534665D02*
X191139Y1535256D01*
G01X191565Y1539665D02*
X191139Y1540256D01*
G01X191565Y1544665D02*
X191139Y1545256D01*
G01X197725Y1505650D02*
X197588Y1505847D01*
X197450Y1506044D01*
X197311Y1506240D01*
G01X197725Y1510650D02*
X197588Y1510847D01*
X197450Y1511044D01*
X197311Y1511240D01*
G01X197725Y1515650D02*
X197588Y1515847D01*
X197450Y1516044D01*
X197311Y1516240D01*
G01X197725Y1520650D02*
X197588Y1520847D01*
X197450Y1521044D01*
X197311Y1521240D01*
G01X197725Y1525650D02*
X197588Y1525847D01*
X197450Y1526044D01*
X197311Y1526240D01*
G01X199693Y1530650D02*
X199556Y1530847D01*
X199419Y1531044D01*
X199279Y1531240D01*
G01X197725Y1535650D02*
X197588Y1535847D01*
X197450Y1536044D01*
X197311Y1536240D01*
G01X197725Y1540650D02*
X197588Y1540847D01*
X197450Y1541044D01*
X197311Y1541240D01*
G01X192743Y1503504D02*
X192705Y1503530D01*
X192677Y1503602D01*
X192667Y1503701D01*
G01X192743Y1506654D02*
X192705Y1506680D01*
X192677Y1506752D01*
X192667Y1506850D01*
G01X192743Y1509803D02*
X192705Y1509830D01*
X192677Y1509902D01*
X192667Y1510000D01*
G01X192743Y1512953D02*
X192705Y1512979D01*
X192677Y1513051D01*
X192667Y1513150D01*
G01X192743Y1516102D02*
X192705Y1516129D01*
X192677Y1516201D01*
X192667Y1516299D01*
G01X192743Y1519252D02*
X192705Y1519278D01*
X192677Y1519350D01*
X192667Y1519449D01*
G01X192743Y1522402D02*
X192705Y1522428D01*
X192677Y1522500D01*
X192667Y1522598D01*
G01X192743Y1525551D02*
X192705Y1525578D01*
X192677Y1525650D01*
X192667Y1525748D01*
G01X192743Y1528701D02*
X192705Y1528727D01*
X192677Y1528799D01*
X192667Y1528898D01*
G01X192743Y1531850D02*
X192705Y1531877D01*
X192677Y1531949D01*
X192667Y1532047D01*
G01X192743Y1535000D02*
X192705Y1535026D01*
X192677Y1535098D01*
X192667Y1535197D01*
G01X192743Y1538150D02*
X192705Y1538176D01*
X192677Y1538248D01*
X192667Y1538346D01*
G01X192743Y1541299D02*
X192705Y1541326D01*
X192677Y1541398D01*
X192667Y1541496D01*
G01X192743Y1544449D02*
X192705Y1544475D01*
X192677Y1544547D01*
X192667Y1544646D01*
G01X197341Y1504291D02*
X197467Y1504264D01*
X197557Y1504191D01*
X197588Y1504094D01*
G01X197341Y1532638D02*
X197467Y1532610D01*
X197557Y1532537D01*
X197588Y1532441D01*
G01X197341Y1503504D02*
X191256D01*
G01X197588Y1503701D02*
X190976D01*
G01Y1504094D02*
X197588D01*
G01X197341Y1504291D02*
X191256D01*
G01X197311Y1504665D02*
X191565D01*
G01X191139Y1505256D02*
X197725D01*
G01X191139Y1505650D02*
X197725D01*
G01X197311Y1506240D02*
X191565D01*
G01X197341Y1506654D02*
X191256D01*
G01X197588Y1506850D02*
X190976D01*
G01Y1507244D02*
X197588D01*
G01X197341Y1507441D02*
X191256D01*
G01X197311Y1509665D02*
X191565D01*
G01X197341Y1509803D02*
X191256D01*
G01X197588Y1510000D02*
X190976D01*
G01X191139Y1510256D02*
X197725D01*
G01X190976Y1510394D02*
X197588D01*
G01X197341Y1510591D02*
X191256D01*
G01X191139Y1510650D02*
X197725D01*
G01X197311Y1511240D02*
X191565D01*
G01X197341Y1512953D02*
X191256D01*
G01X197588Y1513150D02*
X190976D01*
G01Y1513543D02*
X197588D01*
G01X197341Y1513740D02*
X191256D01*
G01X197311Y1514665D02*
X191565D01*
G01X191139Y1515256D02*
X197725D01*
G01X191139Y1515650D02*
X197725D01*
G01X197341Y1516102D02*
X191256D01*
G01X197311Y1516240D02*
X191565D01*
G01X197588Y1516299D02*
X190976D01*
G01Y1516693D02*
X197588D01*
G01X197341Y1516890D02*
X191256D01*
G01X197341Y1519252D02*
X191256D01*
G01X197588Y1519449D02*
X190976D01*
G01X197311Y1519665D02*
X191565D01*
G01X190976Y1519843D02*
X197588D01*
G01X197341Y1520039D02*
X191256D01*
G01X191139Y1520256D02*
X197725D01*
G01X191139Y1520650D02*
X197725D01*
G01X197311Y1521240D02*
X191565D01*
G01X197341Y1522402D02*
X191256D01*
G01X197588Y1522598D02*
X190976D01*
G01Y1522992D02*
X197588D01*
G01X197341Y1523189D02*
X191256D01*
G01X197311Y1524665D02*
X191565D01*
G01X191139Y1525256D02*
X197725D01*
G01X197341Y1525551D02*
X191256D01*
G01X191139Y1525650D02*
X197725D01*
G01X197588Y1525748D02*
X190976D01*
G01Y1526142D02*
X197588D01*
G01X197311Y1526240D02*
X191565D01*
G01X197341Y1526339D02*
X191256D01*
G01X197341Y1528701D02*
X191256D01*
G01X197588Y1528898D02*
X190976D01*
G01Y1529291D02*
X197588D01*
G01X197341Y1529488D02*
X191256D01*
G01X199279Y1529665D02*
X193534D01*
G01X193107Y1530256D02*
X199693D01*
G01X193107Y1530650D02*
X199693D01*
G01X199279Y1531240D02*
X193534D01*
G01X197341Y1531850D02*
X191256D01*
G01X197588Y1532047D02*
X190976D01*
G01Y1532441D02*
X197588D01*
G01X197341Y1532638D02*
X191256D01*
G01X197311Y1534665D02*
X191565D01*
G01X197341Y1535000D02*
X191256D01*
G01X197588Y1535197D02*
X190976D01*
G01X191139Y1535256D02*
X197725D01*
G01X190976Y1535591D02*
X197588D01*
G01X191139Y1535650D02*
X197725D01*
G01X197341Y1535787D02*
X191256D01*
G01X197311Y1536240D02*
X191565D01*
G01X197341Y1538150D02*
X191256D01*
G01X197588Y1538346D02*
X190976D01*
G01Y1538740D02*
X197588D01*
G01X197341Y1538937D02*
X191256D01*
G01X197311Y1539665D02*
X191565D01*
G01X191139Y1540256D02*
X197725D01*
G01X191139Y1540650D02*
X197725D01*
G01X197311Y1541240D02*
X191565D01*
G01X197341Y1541299D02*
X191256D01*
G01X197588Y1541496D02*
X190976D01*
G01Y1541890D02*
X197588D01*
G01X197341Y1542087D02*
X191256D01*
G01X197341Y1506654D02*
X197468Y1506681D01*
X197557Y1506754D01*
X197588Y1506850D01*
G01X197341Y1509803D02*
X197468Y1509831D01*
X197557Y1509904D01*
X197588Y1510000D01*
G01X197341Y1512953D02*
X197468Y1512980D01*
X197557Y1513053D01*
X197588Y1513150D01*
G01X197341Y1516102D02*
X197468Y1516130D01*
X197557Y1516203D01*
X197588Y1516299D01*
G01X197341Y1519252D02*
X197468Y1519280D01*
X197557Y1519352D01*
X197588Y1519449D01*
G01X197341Y1522402D02*
X197468Y1522429D01*
X197557Y1522502D01*
X197588Y1522598D01*
G01X197341Y1525551D02*
X197468Y1525579D01*
X197557Y1525652D01*
X197588Y1525748D01*
G01X197341Y1528701D02*
X197468Y1528728D01*
X197557Y1528801D01*
X197588Y1528898D01*
G01X197341Y1535000D02*
X197468Y1535028D01*
X197557Y1535100D01*
X197588Y1535197D01*
G01X197341Y1538150D02*
X197468Y1538177D01*
X197557Y1538250D01*
X197588Y1538346D01*
G01X197341Y1541299D02*
X197468Y1541327D01*
X197557Y1541400D01*
X197588Y1541496D01*
G01X197341Y1544449D02*
X197468Y1544476D01*
X197557Y1544549D01*
X197588Y1544646D01*
G01X192292Y1504291D02*
X192265Y1504287D01*
X192239Y1504276D01*
X192215Y1504258D01*
X192194Y1504233D01*
X192177Y1504204D01*
X192164Y1504170D01*
X192156Y1504133D01*
X192154Y1504094D01*
G01X192292Y1507441D02*
X192265Y1507437D01*
X192239Y1507426D01*
X192215Y1507408D01*
X192194Y1507383D01*
X192177Y1507354D01*
X192164Y1507320D01*
X192156Y1507283D01*
X192154Y1507244D01*
G01X192292Y1510591D02*
X192265Y1510587D01*
X192239Y1510576D01*
X192215Y1510557D01*
X192194Y1510533D01*
X192177Y1510503D01*
X192164Y1510469D01*
X192156Y1510433D01*
X192154Y1510394D01*
G01X192292Y1513740D02*
X192265Y1513736D01*
X192239Y1513725D01*
X192215Y1513707D01*
X192194Y1513682D01*
X192177Y1513653D01*
X192164Y1513619D01*
X192156Y1513582D01*
X192154Y1513543D01*
G01X192292Y1516890D02*
X192265Y1516886D01*
X192239Y1516875D01*
X192215Y1516857D01*
X192194Y1516832D01*
X192177Y1516802D01*
X192164Y1516769D01*
X192156Y1516732D01*
X192154Y1516693D01*
G01X192292Y1520039D02*
X192265Y1520035D01*
X192239Y1520024D01*
X192215Y1520006D01*
X192194Y1519981D01*
X192177Y1519952D01*
X192164Y1519918D01*
X192156Y1519881D01*
X192154Y1519843D01*
G01X192292Y1523189D02*
X192265Y1523185D01*
X192239Y1523174D01*
X192215Y1523156D01*
X192194Y1523131D01*
X192177Y1523102D01*
X192164Y1523068D01*
X192156Y1523031D01*
X192154Y1522992D01*
G01X192292Y1526339D02*
X192265Y1526335D01*
X192239Y1526324D01*
X192215Y1526306D01*
X192194Y1526281D01*
X192177Y1526251D01*
X192164Y1526217D01*
X192156Y1526181D01*
X192154Y1526142D01*
G01X192292Y1529488D02*
X192265Y1529484D01*
X192239Y1529473D01*
X192215Y1529455D01*
X192194Y1529430D01*
X192177Y1529401D01*
X192164Y1529367D01*
X192156Y1529330D01*
X192154Y1529291D01*
G01X192292Y1532638D02*
X192265Y1532634D01*
X192239Y1532623D01*
X192215Y1532605D01*
X192194Y1532580D01*
X192177Y1532550D01*
X192164Y1532517D01*
X192156Y1532480D01*
X192154Y1532441D01*
G01X192292Y1535787D02*
X192265Y1535783D01*
X192239Y1535772D01*
X192215Y1535754D01*
X192194Y1535730D01*
X192177Y1535700D01*
X192164Y1535666D01*
X192156Y1535630D01*
X192154Y1535591D01*
G01X192292Y1538937D02*
X192265Y1538933D01*
X192239Y1538922D01*
X192215Y1538904D01*
X192194Y1538879D01*
X192177Y1538850D01*
X192164Y1538816D01*
X192156Y1538779D01*
X192154Y1538740D01*
G01X192292Y1542087D02*
X192265Y1542083D01*
X192239Y1542072D01*
X192215Y1542054D01*
X192194Y1542029D01*
X192177Y1541999D01*
X192164Y1541965D01*
X192156Y1541929D01*
X192154Y1541890D01*
G01X192292Y1545236D02*
X192265Y1545232D01*
X192239Y1545221D01*
X192215Y1545203D01*
X192194Y1545178D01*
X192177Y1545149D01*
X192164Y1545115D01*
X192156Y1545078D01*
X192154Y1545039D01*
G01X197341Y1544449D02*
X191256D01*
G01X197588Y1544646D02*
X190976D01*
G01X197311Y1544665D02*
X191565D01*
G01X190976Y1545039D02*
X197588D01*
G01X197341Y1545236D02*
X191256D01*
G01X191139Y1545256D02*
X197725D01*
G01X201575Y1819193D02*
X199606Y1817224D01*
G01X208268Y1814627D02*
X203547Y1809985D01*
G01X208268Y1813524D02*
X203543Y1808878D01*
G01X197311Y1825177D02*
X197450Y1825373D01*
X197588Y1825570D01*
X197725Y1825768D01*
G01X203575Y1808909D02*
X203632Y1809049D01*
X203637Y1809289D01*
G01X203575Y1808909D02*
X203631Y1809044D01*
X203638Y1809279D01*
X203601Y1809608D01*
G01X199606Y1822146D02*
Y1954783D01*
G01X200394Y1852362D02*
Y1821358D01*
G01X200453Y1955177D02*
Y1821752D01*
G01X201575Y1817224D02*
Y1959705D01*
G01X203543Y1810059D02*
Y1817224D01*
G01X208268Y1815256D02*
Y1813524D01*
G01X203602Y1809600D02*
X203547Y1809985D01*
G01X193107Y1825768D02*
X193185Y1825177D01*
G01X192255D02*
X191983Y1825768D01*
G01X191565Y1825177D02*
X191139Y1825768D01*
G01X201575Y1820177D02*
X199606Y1822146D01*
G01X204858Y1817224D02*
X208268Y1815256D01*
G01X204858Y1817224D02*
X201575D01*
G01X197311Y1825177D02*
X191565D01*
G01X192743Y1856260D02*
X192705Y1856233D01*
X192677Y1856161D01*
X192667Y1856063D01*
G01X192743Y1853110D02*
X192705Y1853084D01*
X192677Y1853011D01*
X192667Y1852913D01*
G01X191497Y1856752D02*
X191074Y1856161D01*
G01X191565Y1851752D02*
X191139Y1851161D01*
G01X191565Y1846752D02*
X191139Y1846161D01*
G01X197410Y1855177D02*
X197546Y1855373D01*
X197681Y1855570D01*
X197816Y1855768D01*
G01X197311Y1850177D02*
X197450Y1850373D01*
X197588Y1850570D01*
X197725Y1850768D01*
G01X191983Y1856161D02*
X192255Y1856752D01*
G01X191983Y1851161D02*
X192255Y1851752D01*
G01X191983Y1846161D02*
X192255Y1846752D01*
G01X192222Y1864234D02*
X192225Y1864272D01*
X192233Y1864309D01*
X192247Y1864343D01*
X192265Y1864374D01*
X192288Y1864398D01*
X192313Y1864416D01*
X192341Y1864427D01*
X192370Y1864431D01*
G01X192222Y1861085D02*
X192225Y1861123D01*
X192233Y1861160D01*
X192247Y1861194D01*
X192265Y1861224D01*
X192288Y1861248D01*
X192313Y1861267D01*
X192341Y1861278D01*
X192370Y1861281D01*
G01X192667Y1865512D02*
X192677Y1865610D01*
X192705Y1865682D01*
X192743Y1865709D01*
G01X192667Y1862362D02*
X192677Y1862461D01*
X192705Y1862533D01*
X192743Y1862559D01*
G01X192667Y1859213D02*
X192677Y1859311D01*
X192705Y1859383D01*
X192743Y1859409D01*
G01X192667Y1849764D02*
X192677Y1849862D01*
X192705Y1849934D01*
X192743Y1849961D01*
G01X192667Y1846614D02*
X192677Y1846713D01*
X192705Y1846785D01*
X192743Y1846811D01*
G01X193107Y1856161D02*
X193185Y1856752D01*
G01X193107Y1851161D02*
X193185Y1851752D01*
G01X193107Y1846161D02*
X193185Y1846752D01*
G01X190976Y1865512D02*
Y1865118D01*
G01Y1862362D02*
Y1861969D01*
G01Y1859213D02*
Y1858819D01*
G01Y1856063D02*
Y1855669D01*
G01Y1852913D02*
Y1852520D01*
G01Y1846614D02*
Y1846220D01*
G01Y1849764D02*
Y1849370D01*
G01X191074Y1855768D02*
Y1856161D01*
G01X191139Y1845768D02*
Y1846161D01*
G01Y1850768D02*
Y1851161D01*
G01X191280Y1860100D02*
Y1861085D01*
G01Y1863250D02*
Y1864234D01*
G01Y1866400D02*
Y1867384D01*
G01X191983Y1845768D02*
Y1846161D01*
G01Y1850768D02*
Y1851161D01*
G01Y1855768D02*
Y1856161D01*
G01X192154Y1865512D02*
Y1865118D01*
G01Y1862362D02*
Y1861969D01*
G01Y1859213D02*
Y1858819D01*
G01Y1856063D02*
Y1855669D01*
G01Y1852913D02*
Y1852520D01*
G01Y1846614D02*
Y1846220D01*
G01Y1849764D02*
Y1849370D01*
G01X192222Y1860100D02*
Y1861085D01*
G01Y1863250D02*
Y1864234D01*
G01Y1866400D02*
Y1867384D01*
G01X192667Y1846220D02*
Y1846614D01*
G01Y1849370D02*
Y1849764D01*
G01Y1852520D02*
Y1852913D01*
G01Y1858819D02*
Y1859213D01*
G01Y1855669D02*
Y1856063D01*
G01Y1861969D02*
Y1862362D01*
G01Y1865118D02*
Y1865512D01*
G01X193107Y1856161D02*
Y1855768D01*
G01Y1851161D02*
Y1850768D01*
G01Y1846161D02*
Y1845768D01*
G01X193374Y1860100D02*
Y1861085D01*
G01Y1863250D02*
Y1864234D01*
G01Y1866400D02*
Y1867384D01*
G01X195106Y1858720D02*
Y1857539D01*
G01X197588Y1846220D02*
Y1846614D01*
G01Y1849370D02*
Y1849764D01*
G01Y1852520D02*
Y1852913D01*
G01Y1858819D02*
Y1859213D01*
G01Y1855669D02*
Y1856063D01*
G01Y1861969D02*
Y1862362D01*
G01Y1865118D02*
Y1865512D01*
G01X197598Y1864234D02*
Y1863250D01*
G01Y1867384D02*
Y1866400D01*
G01Y1861085D02*
Y1860100D01*
G01X197725Y1851161D02*
Y1850768D01*
G01Y1846161D02*
Y1845768D01*
G01X197816Y1856161D02*
Y1855768D01*
G01X200394Y1857539D02*
Y1879390D01*
G01X200563Y1857743D02*
Y1852362D01*
G01X193374Y1864234D02*
X193375Y1864272D01*
X193376Y1864309D01*
X193380Y1864343D01*
X193383Y1864374D01*
X193389Y1864398D01*
X193394Y1864416D01*
X193400Y1864427D01*
X193407Y1864431D01*
G01X193374Y1861085D02*
X193375Y1861123D01*
X193376Y1861160D01*
X193380Y1861194D01*
X193383Y1861224D01*
X193389Y1861248D01*
X193394Y1861267D01*
X193400Y1861278D01*
X193407Y1861281D01*
G01X192154Y1846220D02*
X192156Y1846182D01*
X192164Y1846145D01*
X192177Y1846111D01*
X192194Y1846081D01*
X192215Y1846057D01*
X192239Y1846039D01*
X192265Y1846028D01*
X192292Y1846024D01*
G01X192154Y1849370D02*
X192156Y1849332D01*
X192164Y1849295D01*
X192177Y1849261D01*
X192194Y1849231D01*
X192215Y1849206D01*
X192239Y1849188D01*
X192265Y1849177D01*
X192292Y1849173D01*
G01X192154Y1852520D02*
X192156Y1852481D01*
X192164Y1852444D01*
X192177Y1852411D01*
X192194Y1852380D01*
X192215Y1852356D01*
X192239Y1852338D01*
X192265Y1852327D01*
X192292Y1852323D01*
G01X192154Y1855669D02*
X192156Y1855631D01*
X192164Y1855594D01*
X192177Y1855560D01*
X192194Y1855530D01*
X192215Y1855506D01*
X192239Y1855487D01*
X192265Y1855476D01*
X192292Y1855472D01*
G01X192154Y1858819D02*
X192156Y1858781D01*
X192164Y1858744D01*
X192177Y1858710D01*
X192194Y1858680D01*
X192215Y1858655D01*
X192239Y1858637D01*
X192265Y1858626D01*
X192292Y1858622D01*
G01X192154Y1861969D02*
X192156Y1861930D01*
X192164Y1861893D01*
X192177Y1861859D01*
X192194Y1861829D01*
X192215Y1861805D01*
X192239Y1861787D01*
X192265Y1861776D01*
X192292Y1861772D01*
G01X192154Y1865118D02*
X192156Y1865080D01*
X192164Y1865043D01*
X192177Y1865009D01*
X192194Y1864979D01*
X192215Y1864954D01*
X192239Y1864936D01*
X192265Y1864925D01*
X192292Y1864921D01*
G01X193107Y1850768D02*
X193185Y1850177D01*
G01X193107Y1855768D02*
X193185Y1855177D01*
G01X197598Y1861085D02*
X197565Y1861184D01*
X197476Y1861255D01*
X197350Y1861281D01*
G01X197598Y1864234D02*
X197565Y1864333D01*
X197476Y1864404D01*
X197350Y1864431D01*
G01X197588Y1846614D02*
X197556Y1846711D01*
X197468Y1846783D01*
X197341Y1846811D01*
G01X197588Y1849764D02*
X197556Y1849861D01*
X197468Y1849933D01*
X197341Y1849961D01*
G01X197588Y1852913D02*
X197556Y1853010D01*
X197468Y1853082D01*
X197341Y1853110D01*
G01X197588Y1856063D02*
X197556Y1856160D01*
X197468Y1856232D01*
X197341Y1856260D01*
G01X197588Y1859213D02*
X197556Y1859309D01*
X197468Y1859381D01*
X197341Y1859409D01*
G01X197588Y1862362D02*
X197556Y1862459D01*
X197468Y1862531D01*
X197341Y1862559D01*
G01X197588Y1865512D02*
X197556Y1865609D01*
X197468Y1865681D01*
X197341Y1865709D01*
G01X192255Y1850177D02*
X191983Y1850768D01*
G01X192255Y1855177D02*
X191983Y1855768D01*
G01X197725Y1846161D02*
X197588Y1846359D01*
X197450Y1846556D01*
X197311Y1846752D01*
G01X197725Y1851161D02*
X197588Y1851359D01*
X197450Y1851556D01*
X197311Y1851752D01*
G01X197816Y1856161D02*
X197681Y1856359D01*
X197546Y1856556D01*
X197410Y1856752D01*
G01X191565Y1850177D02*
X191139Y1850768D01*
G01X191497Y1855177D02*
X191074Y1855768D01*
G01X199606Y1858701D02*
X201575Y1856732D01*
G01X192743Y1846024D02*
X192705Y1846050D01*
X192677Y1846122D01*
X192667Y1846220D01*
G01X192743Y1849173D02*
X192705Y1849200D01*
X192677Y1849272D01*
X192667Y1849370D01*
G01X192743Y1852323D02*
X192705Y1852349D01*
X192677Y1852421D01*
X192667Y1852520D01*
G01X192743Y1855472D02*
X192705Y1855499D01*
X192677Y1855571D01*
X192667Y1855669D01*
G01X192743Y1858622D02*
X192705Y1858648D01*
X192677Y1858720D01*
X192667Y1858819D01*
G01X192743Y1861772D02*
X192705Y1861798D01*
X192677Y1861870D01*
X192667Y1861969D01*
G01X192743Y1864921D02*
X192705Y1864948D01*
X192677Y1865020D01*
X192667Y1865118D01*
G01X193407Y1859904D02*
X193400Y1859907D01*
X193394Y1859919D01*
X193389Y1859937D01*
X193383Y1859961D01*
X193380Y1859991D01*
X193376Y1860025D01*
X193375Y1860061D01*
X193374Y1860100D01*
G01X193407Y1863053D02*
X193400Y1863057D01*
X193394Y1863068D01*
X193389Y1863086D01*
X193383Y1863111D01*
X193380Y1863141D01*
X193376Y1863174D01*
X193375Y1863211D01*
X193374Y1863250D01*
G01X193407Y1866203D02*
X193400Y1866207D01*
X193394Y1866218D01*
X193389Y1866236D01*
X193383Y1866261D01*
X193380Y1866290D01*
X193376Y1866324D01*
X193375Y1866361D01*
X193374Y1866400D01*
G01X191139Y1845768D02*
X197725D01*
G01X197341Y1846024D02*
X191256D01*
G01X191139Y1846161D02*
X197725D01*
G01X197588Y1846220D02*
X190976D01*
G01Y1846614D02*
X197588D01*
G01X197311Y1846752D02*
X191565D01*
G01X197341Y1846811D02*
X191256D01*
G01X192370Y1859904D02*
X192341Y1859907D01*
X192313Y1859919D01*
X192288Y1859937D01*
X192265Y1859961D01*
X192247Y1859991D01*
X192233Y1860025D01*
X192225Y1860061D01*
X192222Y1860100D01*
G01X192370Y1863053D02*
X192341Y1863057D01*
X192313Y1863068D01*
X192288Y1863086D01*
X192265Y1863111D01*
X192247Y1863141D01*
X192233Y1863174D01*
X192225Y1863211D01*
X192222Y1863250D01*
G01X192370Y1866203D02*
X192341Y1866207D01*
X192313Y1866218D01*
X192288Y1866236D01*
X192265Y1866261D01*
X192247Y1866290D01*
X192233Y1866324D01*
X192225Y1866361D01*
X192222Y1866400D01*
G01X197341Y1846024D02*
X197468Y1846051D01*
X197557Y1846124D01*
X197588Y1846220D01*
G01X197341Y1849173D02*
X197468Y1849201D01*
X197557Y1849274D01*
X197588Y1849370D01*
G01X197341Y1852323D02*
X197468Y1852350D01*
X197557Y1852423D01*
X197588Y1852520D01*
G01X197341Y1855472D02*
X197468Y1855500D01*
X197557Y1855573D01*
X197588Y1855669D01*
G01X197341Y1858622D02*
X197468Y1858650D01*
X197557Y1858722D01*
X197588Y1858819D01*
G01X197341Y1861772D02*
X197468Y1861799D01*
X197557Y1861872D01*
X197588Y1861969D01*
G01X197341Y1864921D02*
X197468Y1864949D01*
X197557Y1865022D01*
X197588Y1865118D01*
G01X197350Y1859904D02*
X197477Y1859931D01*
X197567Y1860004D01*
X197598Y1860100D01*
G01X197350Y1863053D02*
X197477Y1863081D01*
X197567Y1863153D01*
X197598Y1863250D01*
G01X197350Y1866203D02*
X197477Y1866230D01*
X197567Y1866303D01*
X197598Y1866400D01*
G01X192292Y1846811D02*
X192265Y1846807D01*
X192239Y1846796D01*
X192215Y1846778D01*
X192194Y1846753D01*
X192177Y1846724D01*
X192164Y1846690D01*
X192156Y1846653D01*
X192154Y1846614D01*
G01X192292Y1849961D02*
X192265Y1849957D01*
X192239Y1849946D01*
X192215Y1849928D01*
X192194Y1849903D01*
X192177Y1849873D01*
X192164Y1849839D01*
X192156Y1849803D01*
X192154Y1849764D01*
G01X192292Y1853110D02*
X192265Y1853106D01*
X192239Y1853095D01*
X192215Y1853077D01*
X192194Y1853052D01*
X192177Y1853023D01*
X192164Y1852989D01*
X192156Y1852952D01*
X192154Y1852913D01*
G01X192292Y1856260D02*
X192265Y1856256D01*
X192239Y1856245D01*
X192215Y1856227D01*
X192194Y1856202D01*
X192177Y1856172D01*
X192164Y1856139D01*
X192156Y1856102D01*
X192154Y1856063D01*
G01X192292Y1859409D02*
X192265Y1859406D01*
X192239Y1859394D01*
X192215Y1859376D01*
X192194Y1859352D01*
X192177Y1859322D01*
X192164Y1859288D01*
X192156Y1859252D01*
X192154Y1859213D01*
G01X192292Y1862559D02*
X192265Y1862555D01*
X192239Y1862544D01*
X192215Y1862526D01*
X192194Y1862501D01*
X192177Y1862472D01*
X192164Y1862438D01*
X192156Y1862401D01*
X192154Y1862362D01*
G01X192292Y1865709D02*
X192265Y1865705D01*
X192239Y1865694D01*
X192215Y1865676D01*
X192194Y1865651D01*
X192177Y1865621D01*
X192164Y1865587D01*
X192156Y1865551D01*
X192154Y1865512D01*
G01X197341Y1849173D02*
X191256D01*
G01X197588Y1849370D02*
X190976D01*
G01Y1849764D02*
X197588D01*
G01X197341Y1849961D02*
X191256D01*
G01X197311Y1850177D02*
X191565D01*
G01X191139Y1850768D02*
X197725D01*
G01X191139Y1851161D02*
X197725D01*
G01X197311Y1851752D02*
X191565D01*
G01X197341Y1852323D02*
X191256D01*
G01X197588Y1852520D02*
X190976D01*
G01Y1852913D02*
X197588D01*
G01X197341Y1853110D02*
X191256D01*
G01X197410Y1855177D02*
X191497D01*
G01X197341Y1855472D02*
X191256D01*
G01X197588Y1855669D02*
X190976D01*
G01X191074Y1855768D02*
X197816D01*
G01X190976Y1856063D02*
X197588D01*
G01X191074Y1856161D02*
X197816D01*
G01X197341Y1856260D02*
X191256D01*
G01X197410Y1856752D02*
X191497D01*
G01X201575Y1857539D02*
X195106D01*
G01X197341Y1858622D02*
X191256D01*
G01X197588Y1858819D02*
X190976D01*
G01Y1859213D02*
X197588D01*
G01X197341Y1859409D02*
X191256D01*
G01X191542Y1859904D02*
X197350D01*
G01X191280Y1860100D02*
X197598D01*
G01Y1861085D02*
X191280D01*
G01X191542Y1861281D02*
X197350D01*
G01X197341Y1861772D02*
X191256D01*
G01X197588Y1861969D02*
X190976D01*
G01Y1862362D02*
X197588D01*
G01X197341Y1862559D02*
X191256D01*
G01X191542Y1863053D02*
X197350D01*
G01X191280Y1863250D02*
X197598D01*
G01Y1864234D02*
X191280D01*
G01X191542Y1864431D02*
X197350D01*
G01X197341Y1864921D02*
X191256D01*
G01X197588Y1865118D02*
X190976D01*
G01Y1865512D02*
X197588D01*
G01X197341Y1865709D02*
X191256D01*
G01X191542Y1866203D02*
X197350D01*
G01X191280Y1866400D02*
X197598D01*
G01X192743Y1843661D02*
X192705Y1843635D01*
X192677Y1843563D01*
X192667Y1843465D01*
G01X192743Y1840512D02*
X192705Y1840485D01*
X192677Y1840413D01*
X192667Y1840315D01*
G01X192743Y1837362D02*
X192705Y1837336D01*
X192677Y1837263D01*
X192667Y1837165D01*
G01X192743Y1827913D02*
X192705Y1827887D01*
X192677Y1827815D01*
X192667Y1827717D01*
G01X197311Y1845177D02*
X197450Y1845373D01*
X197588Y1845570D01*
X197725Y1845768D01*
G01X197311Y1840177D02*
X197450Y1840373D01*
X197588Y1840570D01*
X197725Y1840768D01*
G01X197311Y1835177D02*
X197450Y1835373D01*
X197588Y1835570D01*
X197725Y1835768D01*
G01X197311Y1830177D02*
X197450Y1830373D01*
X197588Y1830570D01*
X197725Y1830768D01*
G01X191565Y1841752D02*
X191139Y1841161D01*
G01X191565Y1836752D02*
X191139Y1836161D01*
G01X191565Y1831752D02*
X191139Y1831161D01*
G01X191565Y1826752D02*
X191139Y1826161D01*
G01X191983Y1841161D02*
X192255Y1841752D01*
G01X191983Y1836161D02*
X192255Y1836752D01*
G01X191983Y1831161D02*
X192255Y1831752D01*
G01X191983Y1826161D02*
X192255Y1826752D01*
G01X192667Y1834016D02*
X192677Y1834114D01*
X192705Y1834186D01*
X192743Y1834213D01*
G01X192667Y1830866D02*
X192677Y1830965D01*
X192705Y1831037D01*
X192743Y1831063D01*
G01X193107Y1841161D02*
X193185Y1841752D01*
G01X193107Y1836161D02*
X193185Y1836752D01*
G01X193107Y1831161D02*
X193185Y1831752D01*
G01X193107Y1826161D02*
X193185Y1826752D01*
G01X190976Y1843465D02*
Y1843071D01*
G01Y1837165D02*
Y1836772D01*
G01Y1840315D02*
Y1839921D01*
G01Y1834016D02*
Y1833622D01*
G01Y1830866D02*
Y1830472D01*
G01Y1827717D02*
Y1827323D01*
G01X191139Y1825768D02*
Y1826161D01*
G01Y1830768D02*
Y1831161D01*
G01Y1835768D02*
Y1836161D01*
G01Y1840768D02*
Y1841161D01*
G01X191983Y1825768D02*
Y1826161D01*
G01Y1830768D02*
Y1831161D01*
G01Y1835768D02*
Y1836161D01*
G01Y1840768D02*
Y1841161D01*
G01X192154Y1843465D02*
Y1843071D01*
G01Y1837165D02*
Y1836772D01*
G01Y1840315D02*
Y1839921D01*
G01Y1834016D02*
Y1833622D01*
G01Y1830866D02*
Y1830472D01*
G01Y1827717D02*
Y1827323D01*
G01X192667Y1830472D02*
Y1830866D01*
G01Y1827323D02*
Y1827717D01*
G01Y1833622D02*
Y1834016D01*
G01Y1836772D02*
Y1837165D01*
G01Y1839921D02*
Y1840315D01*
G01Y1843071D02*
Y1843465D01*
G01X193107Y1841161D02*
Y1840768D01*
G01Y1836161D02*
Y1835768D01*
G01Y1831161D02*
Y1830768D01*
G01Y1826161D02*
Y1825768D01*
G01X197588Y1830472D02*
Y1830866D01*
G01Y1827323D02*
Y1827717D01*
G01Y1833622D02*
Y1834016D01*
G01Y1836772D02*
Y1837165D01*
G01Y1839921D02*
Y1840315D01*
G01Y1843071D02*
Y1843465D01*
G01X197725Y1841161D02*
Y1840768D01*
G01Y1836161D02*
Y1835768D01*
G01Y1831161D02*
Y1830768D01*
G01Y1826161D02*
Y1825768D01*
G01X192154Y1827323D02*
X192156Y1827285D01*
X192164Y1827248D01*
X192177Y1827214D01*
X192194Y1827183D01*
X192215Y1827159D01*
X192239Y1827141D01*
X192265Y1827130D01*
X192292Y1827126D01*
G01X192154Y1830472D02*
X192156Y1830434D01*
X192164Y1830397D01*
X192177Y1830363D01*
X192194Y1830333D01*
X192215Y1830309D01*
X192239Y1830291D01*
X192265Y1830280D01*
X192292Y1830276D01*
G01X192154Y1833622D02*
X192156Y1833584D01*
X192164Y1833547D01*
X192177Y1833513D01*
X192194Y1833483D01*
X192215Y1833458D01*
X192239Y1833440D01*
X192265Y1833429D01*
X192292Y1833425D01*
G01X192154Y1836772D02*
X192156Y1836733D01*
X192164Y1836696D01*
X192177Y1836663D01*
X192194Y1836632D01*
X192215Y1836608D01*
X192239Y1836590D01*
X192265Y1836579D01*
X192292Y1836575D01*
G01X192154Y1839921D02*
X192156Y1839883D01*
X192164Y1839846D01*
X192177Y1839812D01*
X192194Y1839782D01*
X192215Y1839757D01*
X192239Y1839739D01*
X192265Y1839728D01*
X192292Y1839724D01*
G01X192154Y1843071D02*
X192156Y1843033D01*
X192164Y1842996D01*
X192177Y1842962D01*
X192194Y1842931D01*
X192215Y1842907D01*
X192239Y1842889D01*
X192265Y1842878D01*
X192292Y1842874D01*
G01X193107Y1830768D02*
X193185Y1830177D01*
G01X193107Y1835768D02*
X193185Y1835177D01*
G01X193107Y1840768D02*
X193185Y1840177D01*
G01X193107Y1845768D02*
X193185Y1845177D01*
G01X197588Y1827717D02*
X197556Y1827813D01*
X197468Y1827885D01*
X197341Y1827913D01*
G01X197588Y1830866D02*
X197556Y1830963D01*
X197468Y1831035D01*
X197341Y1831063D01*
G01X197588Y1834016D02*
X197556Y1834113D01*
X197468Y1834185D01*
X197341Y1834213D01*
G01X197588Y1837165D02*
X197556Y1837262D01*
X197468Y1837334D01*
X197341Y1837362D01*
G01X197588Y1840315D02*
X197556Y1840412D01*
X197468Y1840484D01*
X197341Y1840512D01*
G01X197588Y1843465D02*
X197556Y1843561D01*
X197468Y1843633D01*
X197341Y1843661D01*
G01X192255Y1830177D02*
X191983Y1830768D01*
G01X192255Y1835177D02*
X191983Y1835768D01*
G01X192255Y1840177D02*
X191983Y1840768D01*
G01X192255Y1845177D02*
X191983Y1845768D01*
G01X191565Y1830177D02*
X191139Y1830768D01*
G01X191565Y1835177D02*
X191139Y1835768D01*
G01X191565Y1840177D02*
X191139Y1840768D01*
G01X191565Y1845177D02*
X191139Y1845768D01*
G01X197725Y1826161D02*
X197588Y1826359D01*
X197450Y1826556D01*
X197311Y1826752D01*
G01X197725Y1831161D02*
X197588Y1831359D01*
X197450Y1831556D01*
X197311Y1831752D01*
G01X197725Y1836161D02*
X197588Y1836359D01*
X197450Y1836556D01*
X197311Y1836752D01*
G01X197725Y1841161D02*
X197588Y1841359D01*
X197450Y1841556D01*
X197311Y1841752D01*
G01X192743Y1827126D02*
X192705Y1827152D01*
X192677Y1827224D01*
X192667Y1827323D01*
G01X192743Y1830276D02*
X192705Y1830302D01*
X192677Y1830374D01*
X192667Y1830472D01*
G01X192743Y1833425D02*
X192705Y1833452D01*
X192677Y1833524D01*
X192667Y1833622D01*
G01X192743Y1836575D02*
X192705Y1836601D01*
X192677Y1836673D01*
X192667Y1836772D01*
G01X192743Y1839724D02*
X192705Y1839751D01*
X192677Y1839823D01*
X192667Y1839921D01*
G01X192743Y1842874D02*
X192705Y1842900D01*
X192677Y1842972D01*
X192667Y1843071D01*
G01X191139Y1825768D02*
X197725D01*
G01X191139Y1826161D02*
X197725D01*
G01X197311Y1826752D02*
X191565D01*
G01X197341Y1827126D02*
X191256D01*
G01X197588Y1827323D02*
X190976D01*
G01Y1827717D02*
X197588D01*
G01X197341Y1827913D02*
X191256D01*
G01X197311Y1830177D02*
X191565D01*
G01X197341Y1830276D02*
X191256D01*
G01X197588Y1830472D02*
X190976D01*
G01X191139Y1830768D02*
X197725D01*
G01X190976Y1830866D02*
X197588D01*
G01X197341Y1831063D02*
X191256D01*
G01X191139Y1831161D02*
X197725D01*
G01X197311Y1831752D02*
X191565D01*
G01X197341Y1833425D02*
X191256D01*
G01X197588Y1833622D02*
X190976D01*
G01Y1834016D02*
X197588D01*
G01X197341Y1834213D02*
X191256D01*
G01X197311Y1835177D02*
X191565D01*
G01X191139Y1835768D02*
X197725D01*
G01X191139Y1836161D02*
X197725D01*
G01X197341Y1836575D02*
X191256D01*
G01X197311Y1836752D02*
X191565D01*
G01X197588Y1836772D02*
X190976D01*
G01Y1837165D02*
X197588D01*
G01X197341Y1837362D02*
X191256D01*
G01X197341Y1839724D02*
X191256D01*
G01X197588Y1839921D02*
X190976D01*
G01X197311Y1840177D02*
X191565D01*
G01X190976Y1840315D02*
X197588D01*
G01X197341Y1840512D02*
X191256D01*
G01X191139Y1840768D02*
X197725D01*
G01X191139Y1841161D02*
X197725D01*
G01X197311Y1841752D02*
X191565D01*
G01X197341Y1842874D02*
X191256D01*
G01X197588Y1843071D02*
X190976D01*
G01Y1843465D02*
X197588D01*
G01X197341Y1843661D02*
X191256D01*
G01X197311Y1845177D02*
X191565D01*
G01X197341Y1827126D02*
X197468Y1827154D01*
X197557Y1827226D01*
X197588Y1827323D01*
G01X197341Y1830276D02*
X197468Y1830303D01*
X197557Y1830376D01*
X197588Y1830472D01*
G01X197341Y1833425D02*
X197468Y1833453D01*
X197557Y1833526D01*
X197588Y1833622D01*
G01X197341Y1836575D02*
X197468Y1836602D01*
X197557Y1836675D01*
X197588Y1836772D01*
G01X197341Y1839724D02*
X197468Y1839752D01*
X197557Y1839825D01*
X197588Y1839921D01*
G01X197341Y1842874D02*
X197468Y1842902D01*
X197557Y1842974D01*
X197588Y1843071D01*
G01X192292Y1827913D02*
X192265Y1827909D01*
X192239Y1827898D01*
X192215Y1827880D01*
X192194Y1827856D01*
X192177Y1827826D01*
X192164Y1827792D01*
X192156Y1827756D01*
X192154Y1827717D01*
G01X192292Y1831063D02*
X192265Y1831059D01*
X192239Y1831048D01*
X192215Y1831030D01*
X192194Y1831005D01*
X192177Y1830976D01*
X192164Y1830942D01*
X192156Y1830905D01*
X192154Y1830866D01*
G01X192292Y1834213D02*
X192265Y1834209D01*
X192239Y1834198D01*
X192215Y1834180D01*
X192194Y1834155D01*
X192177Y1834125D01*
X192164Y1834091D01*
X192156Y1834055D01*
X192154Y1834016D01*
G01X192292Y1837362D02*
X192265Y1837358D01*
X192239Y1837347D01*
X192215Y1837329D01*
X192194Y1837304D01*
X192177Y1837275D01*
X192164Y1837241D01*
X192156Y1837204D01*
X192154Y1837165D01*
G01X192292Y1840512D02*
X192265Y1840508D01*
X192239Y1840497D01*
X192215Y1840479D01*
X192194Y1840454D01*
X192177Y1840424D01*
X192164Y1840391D01*
X192156Y1840354D01*
X192154Y1840315D01*
G01X192292Y1843661D02*
X192265Y1843657D01*
X192239Y1843646D01*
X192215Y1843628D01*
X192194Y1843604D01*
X192177Y1843574D01*
X192164Y1843540D01*
X192156Y1843504D01*
X192154Y1843465D01*
G01X199279Y1935177D02*
X199419Y1935373D01*
X199556Y1935570D01*
X199693Y1935768D01*
G01X197311Y1930177D02*
X197450Y1930373D01*
X197588Y1930570D01*
X197725Y1930768D01*
G01X197311Y1925177D02*
X197450Y1925373D01*
X197588Y1925570D01*
X197725Y1925768D01*
G01X197311Y1920177D02*
X197450Y1920373D01*
X197588Y1920570D01*
X197725Y1920768D01*
G01X197311Y1915177D02*
X197450Y1915373D01*
X197588Y1915570D01*
X197725Y1915768D01*
G01X197311Y1910177D02*
X197450Y1910373D01*
X197588Y1910570D01*
X197725Y1910768D01*
G01X193534Y1936752D02*
X193107Y1936161D01*
G01X191565Y1931752D02*
X191139Y1931161D01*
G01X191565Y1926752D02*
X191139Y1926161D01*
G01X191565Y1921752D02*
X191139Y1921161D01*
G01X191565Y1916752D02*
X191139Y1916161D01*
G01X191565Y1911752D02*
X191139Y1911161D01*
G01X191565Y1906752D02*
X191139Y1906161D01*
G01X193951Y1936161D02*
X194224Y1936752D01*
G01X191983Y1931161D02*
X192255Y1931752D01*
G01X191983Y1926161D02*
X192255Y1926752D01*
G01X191983Y1921161D02*
X192255Y1921752D01*
G01X191983Y1916161D02*
X192255Y1916752D01*
G01X191983Y1911161D02*
X192255Y1911752D01*
G01X191983Y1906161D02*
X192255Y1906752D01*
G01X197588Y1937559D02*
X197555Y1937460D01*
X197467Y1937389D01*
X197341Y1937362D01*
G01X197588Y1909213D02*
X197555Y1909113D01*
X197467Y1909043D01*
X197341Y1909016D01*
G01X192667Y1937953D02*
X192677Y1938051D01*
X192705Y1938123D01*
X192743Y1938150D01*
G01X192667Y1934803D02*
X192677Y1934902D01*
X192705Y1934974D01*
X192743Y1935000D01*
G01X192667Y1931654D02*
X192677Y1931752D01*
X192705Y1931824D01*
X192743Y1931850D01*
G01X192667Y1928504D02*
X192677Y1928602D01*
X192705Y1928674D01*
X192743Y1928701D01*
G01X192667Y1925354D02*
X192677Y1925453D01*
X192705Y1925525D01*
X192743Y1925551D01*
G01X192667Y1922205D02*
X192677Y1922303D01*
X192705Y1922375D01*
X192743Y1922402D01*
G01X192667Y1919055D02*
X192677Y1919154D01*
X192705Y1919226D01*
X192743Y1919252D01*
G01X192667Y1915906D02*
X192677Y1916004D01*
X192705Y1916076D01*
X192743Y1916102D01*
G01X192667Y1912756D02*
X192677Y1912854D01*
X192705Y1912926D01*
X192743Y1912953D01*
G01X192667Y1909606D02*
X192677Y1909705D01*
X192705Y1909777D01*
X192743Y1909803D01*
G01X192667Y1906457D02*
X192677Y1906555D01*
X192705Y1906627D01*
X192743Y1906654D01*
G01X193107Y1931161D02*
X193185Y1931752D01*
G01X193107Y1926161D02*
X193185Y1926752D01*
G01X195076Y1936161D02*
X195154Y1936752D01*
G01X193107Y1921161D02*
X193185Y1921752D01*
G01X193107Y1916161D02*
X193185Y1916752D01*
G01X193107Y1911161D02*
X193185Y1911752D01*
G01X193107Y1906161D02*
X193185Y1906752D01*
G01X190976Y1937953D02*
Y1937559D01*
G01Y1934803D02*
Y1934409D01*
G01Y1931654D02*
Y1931260D01*
G01Y1925354D02*
Y1924961D01*
G01Y1928504D02*
Y1928110D01*
G01Y1922205D02*
Y1921811D01*
G01Y1915906D02*
Y1915512D01*
G01Y1919055D02*
Y1918661D01*
G01Y1912756D02*
Y1912362D01*
G01Y1906457D02*
Y1906063D01*
G01Y1909606D02*
Y1909213D01*
G01X191139Y1905768D02*
Y1906161D01*
G01Y1910768D02*
Y1911161D01*
G01Y1915768D02*
Y1916161D01*
G01Y1920768D02*
Y1921161D01*
G01Y1925768D02*
Y1926161D01*
G01Y1930768D02*
Y1931161D01*
G01X191983Y1905768D02*
Y1906161D01*
G01Y1910768D02*
Y1911161D01*
G01Y1915768D02*
Y1916161D01*
G01Y1920768D02*
Y1921161D01*
G01Y1925768D02*
Y1926161D01*
G01Y1930768D02*
Y1931161D01*
G01X192154Y1937953D02*
Y1937559D01*
G01Y1934803D02*
Y1934409D01*
G01Y1931654D02*
Y1931260D01*
G01Y1925354D02*
Y1924961D01*
G01Y1928504D02*
Y1928110D01*
G01Y1922205D02*
Y1921811D01*
G01Y1915906D02*
Y1915512D01*
G01Y1919055D02*
Y1918661D01*
G01Y1912756D02*
Y1912362D01*
G01Y1906457D02*
Y1906063D01*
G01Y1909606D02*
Y1909213D01*
G01X192667Y1906063D02*
Y1906457D01*
G01Y1909213D02*
Y1909606D01*
G01Y1912362D02*
Y1912756D01*
G01Y1915512D02*
Y1915906D01*
G01Y1918661D02*
Y1919055D01*
G01Y1921811D02*
Y1922205D01*
G01Y1924961D02*
Y1925354D01*
G01Y1928110D02*
Y1928504D01*
G01Y1931260D02*
Y1931654D01*
G01Y1937559D02*
Y1937953D01*
G01Y1934409D02*
Y1934803D01*
G01X193107Y1931161D02*
Y1930768D01*
G01Y1926161D02*
Y1925768D01*
G01Y1921161D02*
Y1920768D01*
G01Y1916161D02*
Y1915768D01*
G01Y1911161D02*
Y1910768D01*
G01Y1906161D02*
Y1905768D01*
G01Y1935768D02*
Y1936161D01*
G01X193951Y1935768D02*
Y1936161D01*
G01X195076D02*
Y1935768D01*
G01X197588Y1906063D02*
Y1906457D01*
G01Y1909213D02*
Y1909606D01*
G01Y1912362D02*
Y1912756D01*
G01Y1915512D02*
Y1915906D01*
G01Y1918661D02*
Y1919055D01*
G01Y1921811D02*
Y1922205D01*
G01Y1924961D02*
Y1925354D01*
G01Y1928110D02*
Y1928504D01*
G01Y1931260D02*
Y1931654D01*
G01Y1937559D02*
Y1937953D01*
G01Y1934409D02*
Y1934803D01*
G01X197725Y1931161D02*
Y1930768D01*
G01Y1926161D02*
Y1925768D01*
G01Y1921161D02*
Y1920768D01*
G01Y1916161D02*
Y1915768D01*
G01Y1911161D02*
Y1910768D01*
G01Y1906161D02*
Y1905768D01*
G01X199693Y1936161D02*
Y1935768D01*
G01X192154Y1906063D02*
X192156Y1906025D01*
X192164Y1905988D01*
X192177Y1905954D01*
X192194Y1905924D01*
X192215Y1905899D01*
X192239Y1905881D01*
X192265Y1905870D01*
X192292Y1905866D01*
G01X192154Y1909213D02*
X192156Y1909174D01*
X192164Y1909137D01*
X192177Y1909104D01*
X192194Y1909073D01*
X192215Y1909049D01*
X192239Y1909031D01*
X192265Y1909020D01*
X192292Y1909016D01*
G01X192154Y1912362D02*
X192156Y1912324D01*
X192164Y1912287D01*
X192177Y1912253D01*
X192194Y1912223D01*
X192215Y1912198D01*
X192239Y1912180D01*
X192265Y1912169D01*
X192292Y1912165D01*
G01X192154Y1915512D02*
X192156Y1915474D01*
X192164Y1915437D01*
X192177Y1915403D01*
X192194Y1915372D01*
X192215Y1915348D01*
X192239Y1915330D01*
X192265Y1915319D01*
X192292Y1915315D01*
G01X192154Y1918661D02*
X192156Y1918623D01*
X192164Y1918586D01*
X192177Y1918552D01*
X192194Y1918522D01*
X192215Y1918498D01*
X192239Y1918480D01*
X192265Y1918469D01*
X192292Y1918465D01*
G01X192154Y1921811D02*
X192156Y1921773D01*
X192164Y1921736D01*
X192177Y1921702D01*
X192194Y1921672D01*
X192215Y1921647D01*
X192239Y1921629D01*
X192265Y1921618D01*
X192292Y1921614D01*
G01X192154Y1924961D02*
X192156Y1924922D01*
X192164Y1924885D01*
X192177Y1924852D01*
X192194Y1924821D01*
X192215Y1924797D01*
X192239Y1924779D01*
X192265Y1924768D01*
X192292Y1924764D01*
G01X192154Y1928110D02*
X192156Y1928072D01*
X192164Y1928035D01*
X192177Y1928001D01*
X192194Y1927971D01*
X192215Y1927946D01*
X192239Y1927928D01*
X192265Y1927917D01*
X192292Y1927913D01*
G01X192154Y1931260D02*
X192156Y1931222D01*
X192164Y1931185D01*
X192177Y1931151D01*
X192194Y1931120D01*
X192215Y1931096D01*
X192239Y1931078D01*
X192265Y1931067D01*
X192292Y1931063D01*
G01X192154Y1934409D02*
X192156Y1934371D01*
X192164Y1934334D01*
X192177Y1934300D01*
X192194Y1934270D01*
X192215Y1934246D01*
X192239Y1934228D01*
X192265Y1934217D01*
X192292Y1934213D01*
G01X192154Y1937559D02*
X192156Y1937521D01*
X192164Y1937484D01*
X192177Y1937450D01*
X192194Y1937420D01*
X192215Y1937395D01*
X192239Y1937377D01*
X192265Y1937366D01*
X192292Y1937362D01*
G01X193107Y1910768D02*
X193185Y1910177D01*
G01X193107Y1915768D02*
X193185Y1915177D01*
G01X193107Y1920768D02*
X193185Y1920177D01*
G01X193107Y1925768D02*
X193185Y1925177D01*
G01X193107Y1930768D02*
X193185Y1930177D01*
G01X195076Y1935768D02*
X195154Y1935177D01*
G01X197588Y1906457D02*
X197556Y1906554D01*
X197468Y1906626D01*
X197341Y1906654D01*
G01X197588Y1912756D02*
X197556Y1912853D01*
X197468Y1912925D01*
X197341Y1912953D01*
G01X197588Y1915906D02*
X197556Y1916002D01*
X197468Y1916074D01*
X197341Y1916102D01*
G01X197588Y1919055D02*
X197556Y1919152D01*
X197468Y1919224D01*
X197341Y1919252D01*
G01X197588Y1922205D02*
X197556Y1922302D01*
X197468Y1922374D01*
X197341Y1922402D01*
G01X197588Y1925354D02*
X197556Y1925451D01*
X197468Y1925523D01*
X197341Y1925551D01*
G01X197588Y1928504D02*
X197556Y1928601D01*
X197468Y1928673D01*
X197341Y1928701D01*
G01X197588Y1931654D02*
X197556Y1931750D01*
X197468Y1931822D01*
X197341Y1931850D01*
G01X197588Y1934803D02*
X197556Y1934900D01*
X197468Y1934972D01*
X197341Y1935000D01*
G01X192255Y1910177D02*
X191983Y1910768D01*
G01X192255Y1915177D02*
X191983Y1915768D01*
G01X192255Y1920177D02*
X191983Y1920768D01*
G01X192255Y1925177D02*
X191983Y1925768D01*
G01X192255Y1930177D02*
X191983Y1930768D01*
G01X194224Y1935177D02*
X193951Y1935768D01*
G01X191565Y1910177D02*
X191139Y1910768D01*
G01X191565Y1915177D02*
X191139Y1915768D01*
G01X191565Y1920177D02*
X191139Y1920768D01*
G01X191565Y1925177D02*
X191139Y1925768D01*
G01X191565Y1930177D02*
X191139Y1930768D01*
G01X193534Y1935177D02*
X193107Y1935768D01*
G01X197725Y1906161D02*
X197588Y1906359D01*
X197450Y1906556D01*
X197311Y1906752D01*
G01X197725Y1911161D02*
X197588Y1911359D01*
X197450Y1911556D01*
X197311Y1911752D01*
G01X197725Y1916161D02*
X197588Y1916359D01*
X197450Y1916556D01*
X197311Y1916752D01*
G01X197725Y1921161D02*
X197588Y1921359D01*
X197450Y1921556D01*
X197311Y1921752D01*
G01X197725Y1926161D02*
X197588Y1926359D01*
X197450Y1926556D01*
X197311Y1926752D01*
G01X197725Y1931161D02*
X197588Y1931359D01*
X197450Y1931556D01*
X197311Y1931752D01*
G01X199693Y1936161D02*
X199556Y1936359D01*
X199419Y1936556D01*
X199279Y1936752D01*
G01X192743Y1905866D02*
X192705Y1905893D01*
X192677Y1905965D01*
X192667Y1906063D01*
G01X192743Y1909016D02*
X192705Y1909042D01*
X192677Y1909114D01*
X192667Y1909213D01*
G01X192743Y1912165D02*
X192705Y1912192D01*
X192677Y1912264D01*
X192667Y1912362D01*
G01X192743Y1915315D02*
X192705Y1915341D01*
X192677Y1915413D01*
X192667Y1915512D01*
G01X192743Y1918465D02*
X192705Y1918491D01*
X192677Y1918563D01*
X192667Y1918661D01*
G01X192743Y1921614D02*
X192705Y1921641D01*
X192677Y1921713D01*
X192667Y1921811D01*
G01X192743Y1924764D02*
X192705Y1924790D01*
X192677Y1924862D01*
X192667Y1924961D01*
G01X192743Y1927913D02*
X192705Y1927940D01*
X192677Y1928012D01*
X192667Y1928110D01*
G01X192743Y1931063D02*
X192705Y1931089D01*
X192677Y1931161D01*
X192667Y1931260D01*
G01X192743Y1934213D02*
X192705Y1934239D01*
X192677Y1934311D01*
X192667Y1934409D01*
G01X192743Y1937362D02*
X192705Y1937389D01*
X192677Y1937461D01*
X192667Y1937559D01*
G01X197341Y1909803D02*
X197467Y1909776D01*
X197557Y1909703D01*
X197588Y1909606D01*
G01X191139Y1905768D02*
X197725D01*
G01X197341Y1905866D02*
X191256D01*
G01X197588Y1906063D02*
X190976D01*
G01X191139Y1906161D02*
X197725D01*
G01X190976Y1906457D02*
X197588D01*
G01X197341Y1906654D02*
X191256D01*
G01X197311Y1906752D02*
X191565D01*
G01X197341Y1909016D02*
X191256D01*
G01X197588Y1909213D02*
X190976D01*
G01Y1909606D02*
X197588D01*
G01X197341Y1909803D02*
X191256D01*
G01X197311Y1910177D02*
X191565D01*
G01X191139Y1910768D02*
X197725D01*
G01X191139Y1911161D02*
X197725D01*
G01X197311Y1911752D02*
X191565D01*
G01X197341Y1912165D02*
X191256D01*
G01X197588Y1912362D02*
X190976D01*
G01Y1912756D02*
X197588D01*
G01X197341Y1912953D02*
X191256D01*
G01X197311Y1915177D02*
X191565D01*
G01X197341Y1915315D02*
X191256D01*
G01X197588Y1915512D02*
X190976D01*
G01X191139Y1915768D02*
X197725D01*
G01X190976Y1915906D02*
X197588D01*
G01X197341Y1916102D02*
X191256D01*
G01X191139Y1916161D02*
X197725D01*
G01X197311Y1916752D02*
X191565D01*
G01X197341Y1918465D02*
X191256D01*
G01X197588Y1918661D02*
X190976D01*
G01Y1919055D02*
X197588D01*
G01X197341Y1919252D02*
X191256D01*
G01X197311Y1920177D02*
X191565D01*
G01X191139Y1920768D02*
X197725D01*
G01X191139Y1921161D02*
X197725D01*
G01X197341Y1921614D02*
X191256D01*
G01X197311Y1921752D02*
X191565D01*
G01X197588Y1921811D02*
X190976D01*
G01Y1922205D02*
X197588D01*
G01X197341Y1922402D02*
X191256D01*
G01X197341Y1924764D02*
X191256D01*
G01X197588Y1924961D02*
X190976D01*
G01X197311Y1925177D02*
X191565D01*
G01X190976Y1925354D02*
X197588D01*
G01X197341Y1938150D02*
X197467Y1938122D01*
X197557Y1938049D01*
X197588Y1937953D01*
G01X197341Y1905866D02*
X197468Y1905894D01*
X197557Y1905967D01*
X197588Y1906063D01*
G01X197341Y1912165D02*
X197468Y1912193D01*
X197557Y1912266D01*
X197588Y1912362D01*
G01X197341Y1915315D02*
X197468Y1915343D01*
X197557Y1915415D01*
X197588Y1915512D01*
G01X197341Y1918465D02*
X197468Y1918492D01*
X197557Y1918565D01*
X197588Y1918661D01*
G01X197341Y1921614D02*
X197468Y1921642D01*
X197557Y1921715D01*
X197588Y1921811D01*
G01X197341Y1924764D02*
X197468Y1924791D01*
X197557Y1924864D01*
X197588Y1924961D01*
G01X197341Y1927913D02*
X197468Y1927941D01*
X197557Y1928014D01*
X197588Y1928110D01*
G01X197341Y1931063D02*
X197468Y1931091D01*
X197557Y1931163D01*
X197588Y1931260D01*
G01X197341Y1934213D02*
X197468Y1934240D01*
X197557Y1934313D01*
X197588Y1934409D01*
G01X192292Y1906654D02*
X192265Y1906650D01*
X192239Y1906639D01*
X192215Y1906620D01*
X192194Y1906596D01*
X192177Y1906566D01*
X192164Y1906532D01*
X192156Y1906496D01*
X192154Y1906457D01*
G01X192292Y1909803D02*
X192265Y1909799D01*
X192239Y1909788D01*
X192215Y1909770D01*
X192194Y1909745D01*
X192177Y1909716D01*
X192164Y1909682D01*
X192156Y1909645D01*
X192154Y1909606D01*
G01X192292Y1912953D02*
X192265Y1912949D01*
X192239Y1912938D01*
X192215Y1912920D01*
X192194Y1912895D01*
X192177Y1912865D01*
X192164Y1912831D01*
X192156Y1912795D01*
X192154Y1912756D01*
G01X192292Y1916102D02*
X192265Y1916098D01*
X192239Y1916087D01*
X192215Y1916069D01*
X192194Y1916044D01*
X192177Y1916015D01*
X192164Y1915981D01*
X192156Y1915944D01*
X192154Y1915906D01*
G01X192292Y1919252D02*
X192265Y1919248D01*
X192239Y1919237D01*
X192215Y1919219D01*
X192194Y1919194D01*
X192177Y1919165D01*
X192164Y1919131D01*
X192156Y1919094D01*
X192154Y1919055D01*
G01X192292Y1922402D02*
X192265Y1922398D01*
X192239Y1922387D01*
X192215Y1922369D01*
X192194Y1922344D01*
X192177Y1922314D01*
X192164Y1922280D01*
X192156Y1922244D01*
X192154Y1922205D01*
G01X192292Y1925551D02*
X192265Y1925547D01*
X192239Y1925536D01*
X192215Y1925518D01*
X192194Y1925493D01*
X192177Y1925464D01*
X192164Y1925430D01*
X192156Y1925393D01*
X192154Y1925354D01*
G01X192292Y1928701D02*
X192265Y1928697D01*
X192239Y1928686D01*
X192215Y1928668D01*
X192194Y1928643D01*
X192177Y1928613D01*
X192164Y1928580D01*
X192156Y1928543D01*
X192154Y1928504D01*
G01X192292Y1931850D02*
X192265Y1931846D01*
X192239Y1931835D01*
X192215Y1931817D01*
X192194Y1931793D01*
X192177Y1931763D01*
X192164Y1931729D01*
X192156Y1931693D01*
X192154Y1931654D01*
G01X192292Y1935000D02*
X192265Y1934996D01*
X192239Y1934985D01*
X192215Y1934967D01*
X192194Y1934942D01*
X192177Y1934913D01*
X192164Y1934879D01*
X192156Y1934842D01*
X192154Y1934803D01*
G01X192292Y1938150D02*
X192265Y1938146D01*
X192239Y1938135D01*
X192215Y1938117D01*
X192194Y1938092D01*
X192177Y1938062D01*
X192164Y1938028D01*
X192156Y1937992D01*
X192154Y1937953D01*
G01X197341Y1925551D02*
X191256D01*
G01X191139Y1925768D02*
X197725D01*
G01X191139Y1926161D02*
X197725D01*
G01X197311Y1926752D02*
X191565D01*
G01X197341Y1927913D02*
X191256D01*
G01X197588Y1928110D02*
X190976D01*
G01Y1928504D02*
X197588D01*
G01X197341Y1928701D02*
X191256D01*
G01X197311Y1930177D02*
X191565D01*
G01X191139Y1930768D02*
X197725D01*
G01X197341Y1931063D02*
X191256D01*
G01X191139Y1931161D02*
X197725D01*
G01X197588Y1931260D02*
X190976D01*
G01Y1931654D02*
X197588D01*
G01X197311Y1931752D02*
X191565D01*
G01X197341Y1931850D02*
X191256D01*
G01X197341Y1934213D02*
X191256D01*
G01X197588Y1934409D02*
X190976D01*
G01Y1934803D02*
X197588D01*
G01X197341Y1935000D02*
X191256D01*
G01X199279Y1935177D02*
X193534D01*
G01X193107Y1935768D02*
X199693D01*
G01X193107Y1936161D02*
X199693D01*
G01X199279Y1936752D02*
X193534D01*
G01X197341Y1937362D02*
X191256D01*
G01X197588Y1937559D02*
X190976D01*
G01Y1937953D02*
X197588D01*
G01X197341Y1938150D02*
X191256D01*
G01X201575Y1880197D02*
X199606Y1878228D01*
G01X192743Y1872008D02*
X192705Y1871981D01*
X192677Y1871909D01*
X192667Y1871811D01*
G01X197410Y1880177D02*
X197546Y1880373D01*
X197681Y1880570D01*
X197816Y1880768D01*
G01X197311Y1905177D02*
X197450Y1905373D01*
X197588Y1905570D01*
X197725Y1905768D01*
G01X197311Y1900177D02*
X197450Y1900373D01*
X197588Y1900570D01*
X197725Y1900768D01*
G01X199279Y1895177D02*
X199419Y1895373D01*
X199556Y1895570D01*
X199693Y1895768D01*
G01X197311Y1890177D02*
X197450Y1890373D01*
X197588Y1890570D01*
X197725Y1890768D01*
G01X197311Y1885177D02*
X197450Y1885373D01*
X197588Y1885570D01*
X197725Y1885768D01*
G01X191497Y1881752D02*
X191074Y1881161D01*
G01X191565Y1901752D02*
X191139Y1901161D01*
G01X193534Y1896752D02*
X193107Y1896161D01*
G01X191565Y1891752D02*
X191139Y1891161D01*
G01X191565Y1886752D02*
X191139Y1886161D01*
G01X191983Y1901161D02*
X192255Y1901752D01*
G01X193951Y1896161D02*
X194224Y1896752D01*
G01X191983Y1891161D02*
X192255Y1891752D01*
G01X191983Y1886161D02*
X192255Y1886752D01*
G01X191983Y1881161D02*
X192255Y1881752D01*
G01X192222Y1876833D02*
X192225Y1876871D01*
X192233Y1876908D01*
X192247Y1876942D01*
X192265Y1876972D01*
X192288Y1876996D01*
X192313Y1877015D01*
X192341Y1877026D01*
X192370Y1877030D01*
G01X192222Y1873683D02*
X192225Y1873721D01*
X192233Y1873758D01*
X192247Y1873792D01*
X192265Y1873822D01*
X192288Y1873847D01*
X192313Y1873865D01*
X192341Y1873876D01*
X192370Y1873880D01*
G01X192222Y1870533D02*
X192225Y1870572D01*
X192233Y1870609D01*
X192247Y1870643D01*
X192265Y1870673D01*
X192288Y1870697D01*
X192313Y1870715D01*
X192341Y1870726D01*
X192370Y1870730D01*
G01X192222Y1867384D02*
X192225Y1867422D01*
X192233Y1867459D01*
X192247Y1867493D01*
X192265Y1867523D01*
X192288Y1867548D01*
X192313Y1867566D01*
X192341Y1867577D01*
X192370Y1867581D01*
G01X192667Y1903307D02*
X192677Y1903406D01*
X192705Y1903478D01*
X192743Y1903504D01*
G01X192667Y1900157D02*
X192677Y1900256D01*
X192705Y1900328D01*
X192743Y1900354D01*
G01X192667Y1897008D02*
X192677Y1897106D01*
X192705Y1897178D01*
X192743Y1897205D01*
G01X192667Y1893858D02*
X192677Y1893957D01*
X192705Y1894029D01*
X192743Y1894055D01*
G01X192667Y1890709D02*
X192677Y1890807D01*
X192705Y1890879D01*
X192743Y1890906D01*
G01X192667Y1887559D02*
X192677Y1887657D01*
X192705Y1887730D01*
X192743Y1887756D01*
G01X192667Y1884409D02*
X192677Y1884508D01*
X192705Y1884580D01*
X192743Y1884606D01*
G01X192667Y1881260D02*
X192677Y1881358D01*
X192705Y1881430D01*
X192743Y1881457D01*
G01X192667Y1878110D02*
X192677Y1878209D01*
X192705Y1878281D01*
X192743Y1878307D01*
G01X192667Y1874961D02*
X192677Y1875059D01*
X192705Y1875131D01*
X192743Y1875157D01*
G01X192667Y1868661D02*
X192677Y1868760D01*
X192705Y1868832D01*
X192743Y1868858D01*
G01X193107Y1901161D02*
X193185Y1901752D01*
G01X193107Y1891161D02*
X193185Y1891752D01*
G01X193107Y1886161D02*
X193185Y1886752D01*
G01X195076Y1896161D02*
X195154Y1896752D01*
G01X193107Y1881161D02*
X193185Y1881752D01*
G01X190976Y1903307D02*
Y1902913D01*
G01Y1897008D02*
Y1896614D01*
G01Y1900157D02*
Y1899764D01*
G01Y1893858D02*
Y1893465D01*
G01Y1890709D02*
Y1890315D01*
G01Y1887559D02*
Y1887165D01*
G01Y1884409D02*
Y1884016D01*
G01Y1881260D02*
Y1880866D01*
G01Y1874961D02*
Y1874567D01*
G01Y1878110D02*
Y1877717D01*
G01Y1871811D02*
Y1871417D01*
G01Y1868661D02*
Y1868268D01*
G01X191074Y1880768D02*
Y1881161D01*
G01X191139Y1885768D02*
Y1886161D01*
G01Y1890768D02*
Y1891161D01*
G01Y1900768D02*
Y1901161D01*
G01X191280Y1869549D02*
Y1870533D01*
G01Y1875848D02*
Y1876833D01*
G01Y1872699D02*
Y1873683D01*
G01X191983Y1880768D02*
Y1881161D01*
G01Y1885768D02*
Y1886161D01*
G01Y1890768D02*
Y1891161D01*
G01Y1900768D02*
Y1901161D01*
G01X192154Y1903307D02*
Y1902913D01*
G01Y1897008D02*
Y1896614D01*
G01Y1900157D02*
Y1899764D01*
G01Y1893858D02*
Y1893465D01*
G01Y1890709D02*
Y1890315D01*
G01Y1887559D02*
Y1887165D01*
G01Y1884409D02*
Y1884016D01*
G01Y1881260D02*
Y1880866D01*
G01Y1874961D02*
Y1874567D01*
G01Y1878110D02*
Y1877717D01*
G01Y1871811D02*
Y1871417D01*
G01Y1868661D02*
Y1868268D01*
G01X192222Y1869549D02*
Y1870533D01*
G01Y1875848D02*
Y1876833D01*
G01Y1872699D02*
Y1873683D01*
G01X192667Y1868268D02*
Y1868661D01*
G01Y1871417D02*
Y1871811D01*
G01Y1874567D02*
Y1874961D01*
G01Y1877717D02*
Y1878110D01*
G01Y1880866D02*
Y1881260D01*
G01Y1884016D02*
Y1884409D01*
G01Y1890315D02*
Y1890709D01*
G01Y1887165D02*
Y1887559D01*
G01Y1893465D02*
Y1893858D01*
G01Y1896614D02*
Y1897008D01*
G01Y1899764D02*
Y1900157D01*
G01Y1902913D02*
Y1903307D01*
G01X193107Y1901161D02*
Y1900768D01*
G01Y1891161D02*
Y1890768D01*
G01Y1886161D02*
Y1885768D01*
G01Y1881161D02*
Y1880768D01*
G01Y1895768D02*
Y1896161D01*
G01X193374Y1869549D02*
Y1870533D01*
G01Y1875848D02*
Y1876833D01*
G01Y1872699D02*
Y1873683D01*
G01X193951Y1895768D02*
Y1896161D01*
G01X195076D02*
Y1895768D01*
G01X195106Y1879390D02*
Y1878209D01*
G01X197588Y1868268D02*
Y1868661D01*
G01Y1871417D02*
Y1871811D01*
G01Y1874567D02*
Y1874961D01*
G01Y1877717D02*
Y1878110D01*
G01Y1880866D02*
Y1881260D01*
G01Y1884016D02*
Y1884409D01*
G01Y1890315D02*
Y1890709D01*
G01Y1887165D02*
Y1887559D01*
G01Y1893465D02*
Y1893858D01*
G01Y1896614D02*
Y1897008D01*
G01Y1899764D02*
Y1900157D01*
G01Y1902913D02*
Y1903307D01*
G01X197598Y1876833D02*
Y1875848D01*
G01Y1873683D02*
Y1872699D01*
G01Y1870533D02*
Y1869549D01*
G01X197725Y1901161D02*
Y1900768D01*
G01Y1891161D02*
Y1890768D01*
G01Y1886161D02*
Y1885768D01*
G01X197816Y1881161D02*
Y1880768D01*
G01X199693Y1896161D02*
Y1895768D01*
G01X200394Y1955571D02*
Y1884665D01*
G01X200563D02*
Y1879185D01*
G01X193374Y1876833D02*
X193375Y1876871D01*
X193376Y1876908D01*
X193380Y1876942D01*
X193383Y1876972D01*
X193389Y1876996D01*
X193394Y1877015D01*
X193400Y1877026D01*
X193407Y1877030D01*
G01X193374Y1873683D02*
X193375Y1873721D01*
X193376Y1873758D01*
X193380Y1873792D01*
X193383Y1873822D01*
X193389Y1873847D01*
X193394Y1873865D01*
X193400Y1873876D01*
X193407Y1873880D01*
G01X193374Y1870533D02*
X193375Y1870572D01*
X193376Y1870609D01*
X193380Y1870643D01*
X193383Y1870673D01*
X193389Y1870697D01*
X193394Y1870715D01*
X193400Y1870726D01*
X193407Y1870730D01*
G01X193374Y1867384D02*
X193375Y1867422D01*
X193376Y1867459D01*
X193380Y1867493D01*
X193383Y1867523D01*
X193389Y1867548D01*
X193394Y1867566D01*
X193400Y1867577D01*
X193407Y1867581D01*
G01X192154Y1868268D02*
X192156Y1868230D01*
X192164Y1868193D01*
X192177Y1868159D01*
X192194Y1868128D01*
X192215Y1868104D01*
X192239Y1868086D01*
X192265Y1868075D01*
X192292Y1868071D01*
G01X192154Y1871417D02*
X192156Y1871379D01*
X192164Y1871342D01*
X192177Y1871308D01*
X192194Y1871278D01*
X192215Y1871254D01*
X192239Y1871235D01*
X192265Y1871224D01*
X192292Y1871220D01*
G01X192154Y1874567D02*
X192156Y1874529D01*
X192164Y1874492D01*
X192177Y1874458D01*
X192194Y1874428D01*
X192215Y1874403D01*
X192239Y1874385D01*
X192265Y1874374D01*
X192292Y1874370D01*
G01X192154Y1877717D02*
X192156Y1877678D01*
X192164Y1877641D01*
X192177Y1877607D01*
X192194Y1877577D01*
X192215Y1877553D01*
X192239Y1877535D01*
X192265Y1877524D01*
X192292Y1877520D01*
G01X192154Y1880866D02*
X192156Y1880828D01*
X192164Y1880791D01*
X192177Y1880757D01*
X192194Y1880727D01*
X192215Y1880702D01*
X192239Y1880684D01*
X192265Y1880673D01*
X192292Y1880669D01*
G01X192154Y1884016D02*
X192156Y1883978D01*
X192164Y1883941D01*
X192177Y1883907D01*
X192194Y1883876D01*
X192215Y1883852D01*
X192239Y1883834D01*
X192265Y1883823D01*
X192292Y1883819D01*
G01X192154Y1887165D02*
X192156Y1887127D01*
X192164Y1887090D01*
X192177Y1887056D01*
X192194Y1887026D01*
X192215Y1887002D01*
X192239Y1886983D01*
X192265Y1886972D01*
X192292Y1886969D01*
G01X192154Y1890315D02*
X192156Y1890277D01*
X192164Y1890240D01*
X192177Y1890206D01*
X192194Y1890176D01*
X192215Y1890151D01*
X192239Y1890133D01*
X192265Y1890122D01*
X192292Y1890118D01*
G01X192154Y1893465D02*
X192156Y1893426D01*
X192164Y1893389D01*
X192177Y1893356D01*
X192194Y1893325D01*
X192215Y1893301D01*
X192239Y1893283D01*
X192265Y1893272D01*
X192292Y1893268D01*
G01X192154Y1896614D02*
X192156Y1896576D01*
X192164Y1896539D01*
X192177Y1896505D01*
X192194Y1896475D01*
X192215Y1896450D01*
X192239Y1896432D01*
X192265Y1896421D01*
X192292Y1896417D01*
G01X192154Y1899764D02*
X192156Y1899726D01*
X192164Y1899689D01*
X192177Y1899655D01*
X192194Y1899624D01*
X192215Y1899600D01*
X192239Y1899582D01*
X192265Y1899571D01*
X192292Y1899567D01*
G01X192154Y1902913D02*
X192156Y1902875D01*
X192164Y1902838D01*
X192177Y1902804D01*
X192194Y1902774D01*
X192215Y1902750D01*
X192239Y1902731D01*
X192265Y1902720D01*
X192292Y1902717D01*
G01X193107Y1880768D02*
X193185Y1880177D01*
G01X193107Y1885768D02*
X193185Y1885177D01*
G01X193107Y1890768D02*
X193185Y1890177D01*
G01X193107Y1900768D02*
X193185Y1900177D01*
G01X193107Y1905768D02*
X193185Y1905177D01*
G01X195076Y1895768D02*
X195154Y1895177D01*
G01X197598Y1867384D02*
X197565Y1867483D01*
X197476Y1867554D01*
X197350Y1867581D01*
G01X197598Y1870533D02*
X197565Y1870633D01*
X197476Y1870704D01*
X197350Y1870730D01*
G01X197598Y1873683D02*
X197565Y1873782D01*
X197476Y1873853D01*
X197350Y1873880D01*
G01X197598Y1876833D02*
X197565Y1876932D01*
X197476Y1877003D01*
X197350Y1877030D01*
G01X197588Y1868661D02*
X197556Y1868758D01*
X197468Y1868830D01*
X197341Y1868858D01*
G01X197588Y1871811D02*
X197556Y1871908D01*
X197468Y1871980D01*
X197341Y1872008D01*
G01X197588Y1874961D02*
X197556Y1875057D01*
X197468Y1875130D01*
X197341Y1875157D01*
G01X197588Y1878110D02*
X197556Y1878207D01*
X197468Y1878279D01*
X197341Y1878307D01*
G01X197588Y1881260D02*
X197556Y1881357D01*
X197468Y1881429D01*
X197341Y1881457D01*
G01X197588Y1884409D02*
X197556Y1884506D01*
X197468Y1884578D01*
X197341Y1884606D01*
G01X197588Y1887559D02*
X197556Y1887656D01*
X197468Y1887728D01*
X197341Y1887756D01*
G01X197588Y1890709D02*
X197556Y1890806D01*
X197468Y1890878D01*
X197341Y1890906D01*
G01X197588Y1893858D02*
X197556Y1893955D01*
X197468Y1894027D01*
X197341Y1894055D01*
G01X197588Y1897008D02*
X197556Y1897105D01*
X197468Y1897177D01*
X197341Y1897205D01*
G01X197588Y1900157D02*
X197556Y1900254D01*
X197468Y1900326D01*
X197341Y1900354D01*
G01X197588Y1903307D02*
X197556Y1903404D01*
X197468Y1903476D01*
X197341Y1903504D01*
G01X192255Y1880177D02*
X191983Y1880768D01*
G01X192255Y1885177D02*
X191983Y1885768D01*
G01X192255Y1890177D02*
X191983Y1890768D01*
G01X194224Y1895177D02*
X193951Y1895768D01*
G01X192255Y1900177D02*
X191983Y1900768D01*
G01X192255Y1905177D02*
X191983Y1905768D01*
G01X197816Y1881161D02*
X197681Y1881359D01*
X197546Y1881556D01*
X197410Y1881752D01*
G01X191565Y1885177D02*
X191139Y1885768D01*
G01X191565Y1890177D02*
X191139Y1890768D01*
G01X193534Y1895177D02*
X193107Y1895768D01*
G01X191565Y1900177D02*
X191139Y1900768D01*
G01X191565Y1905177D02*
X191139Y1905768D01*
G01X191497Y1880177D02*
X191074Y1880768D01*
G01X197725Y1886161D02*
X197588Y1886359D01*
X197450Y1886556D01*
X197311Y1886752D01*
G01X197725Y1891161D02*
X197588Y1891359D01*
X197450Y1891556D01*
X197311Y1891752D01*
G01X199693Y1896161D02*
X199556Y1896359D01*
X199419Y1896556D01*
X199279Y1896752D01*
G01X197725Y1901161D02*
X197588Y1901359D01*
X197450Y1901556D01*
X197311Y1901752D01*
G01X192743Y1868071D02*
X192705Y1868097D01*
X192677Y1868169D01*
X192667Y1868268D01*
G01X192743Y1871220D02*
X192705Y1871247D01*
X192677Y1871319D01*
X192667Y1871417D01*
G01X192743Y1874370D02*
X192705Y1874396D01*
X192677Y1874469D01*
X192667Y1874567D01*
G01X192743Y1877520D02*
X192705Y1877546D01*
X192677Y1877618D01*
X192667Y1877717D01*
G01X193407Y1869352D02*
X193400Y1869356D01*
X193394Y1869367D01*
X193389Y1869385D01*
X193383Y1869410D01*
X193380Y1869440D01*
X193376Y1869474D01*
X193375Y1869510D01*
X193374Y1869549D01*
G01X193407Y1872502D02*
X193400Y1872506D01*
X193394Y1872517D01*
X193389Y1872535D01*
X193383Y1872560D01*
X193380Y1872589D01*
X193376Y1872623D01*
X193375Y1872660D01*
X193374Y1872699D01*
G01X193407Y1875652D02*
X193400Y1875656D01*
X193394Y1875667D01*
X193389Y1875685D01*
X193383Y1875709D01*
X193380Y1875739D01*
X193376Y1875773D01*
X193375Y1875809D01*
X193374Y1875848D01*
G01X192743Y1880669D02*
X192705Y1880696D01*
X192677Y1880768D01*
X192667Y1880866D01*
G01X192743Y1883819D02*
X192705Y1883845D01*
X192677Y1883917D01*
X192667Y1884016D01*
G01X192743Y1886969D02*
X192705Y1886995D01*
X192677Y1887067D01*
X192667Y1887165D01*
G01X192743Y1890118D02*
X192705Y1890144D01*
X192677Y1890217D01*
X192667Y1890315D01*
G01X192743Y1893268D02*
X192705Y1893294D01*
X192677Y1893366D01*
X192667Y1893465D01*
G01X192743Y1896417D02*
X192705Y1896444D01*
X192677Y1896516D01*
X192667Y1896614D01*
G01X192743Y1899567D02*
X192705Y1899593D01*
X192677Y1899665D01*
X192667Y1899764D01*
G01X192743Y1902717D02*
X192705Y1902743D01*
X192677Y1902815D01*
X192667Y1902913D01*
G01X192370Y1869352D02*
X192341Y1869356D01*
X192313Y1869367D01*
X192288Y1869385D01*
X192265Y1869410D01*
X192247Y1869440D01*
X192233Y1869474D01*
X192225Y1869510D01*
X192222Y1869549D01*
G01X192370Y1872502D02*
X192341Y1872506D01*
X192313Y1872517D01*
X192288Y1872535D01*
X192265Y1872560D01*
X192247Y1872589D01*
X192233Y1872623D01*
X192225Y1872660D01*
X192222Y1872699D01*
G01X192370Y1875652D02*
X192341Y1875656D01*
X192313Y1875667D01*
X192288Y1875685D01*
X192265Y1875709D01*
X192247Y1875739D01*
X192233Y1875773D01*
X192225Y1875809D01*
X192222Y1875848D01*
G01X197341Y1868071D02*
X197468Y1868098D01*
X197557Y1868171D01*
X197588Y1868268D01*
G01X197341Y1871220D02*
X197468Y1871248D01*
X197557Y1871321D01*
X197588Y1871417D01*
G01X197341Y1874370D02*
X197468Y1874398D01*
X197557Y1874470D01*
X197588Y1874567D01*
G01X197341Y1877520D02*
X197468Y1877547D01*
X197557Y1877620D01*
X197588Y1877717D01*
G01X197350Y1869352D02*
X197477Y1869380D01*
X197567Y1869452D01*
X197598Y1869549D01*
G01X197350Y1872502D02*
X197477Y1872530D01*
X197567Y1872602D01*
X197598Y1872699D01*
G01X197350Y1875652D02*
X197477Y1875679D01*
X197567Y1875752D01*
X197598Y1875848D01*
G01X192292Y1868858D02*
X192265Y1868854D01*
X192239Y1868843D01*
X192215Y1868825D01*
X192194Y1868800D01*
X192177Y1868771D01*
X192164Y1868737D01*
X192156Y1868700D01*
X192154Y1868661D01*
G01X192292Y1872008D02*
X192265Y1872004D01*
X192239Y1871993D01*
X192215Y1871975D01*
X192194Y1871950D01*
X192177Y1871920D01*
X192164Y1871887D01*
X192156Y1871850D01*
X192154Y1871811D01*
G01X192292Y1875157D02*
X192265Y1875154D01*
X192239Y1875143D01*
X192215Y1875124D01*
X192194Y1875100D01*
X192177Y1875070D01*
X192164Y1875036D01*
X192156Y1875000D01*
X192154Y1874961D01*
G01X192292Y1878307D02*
X192265Y1878303D01*
X192239Y1878292D01*
X192215Y1878274D01*
X192194Y1878249D01*
X192177Y1878220D01*
X192164Y1878186D01*
X192156Y1878149D01*
X192154Y1878110D01*
G01X192292Y1881457D02*
X192265Y1881453D01*
X192239Y1881442D01*
X192215Y1881424D01*
X192194Y1881399D01*
X192177Y1881369D01*
X192164Y1881335D01*
X192156Y1881299D01*
X192154Y1881260D01*
G01X192292Y1884606D02*
X192265Y1884602D01*
X192239Y1884591D01*
X192215Y1884573D01*
X192194Y1884548D01*
X192177Y1884519D01*
X192164Y1884485D01*
X192156Y1884448D01*
X192154Y1884409D01*
G01X192292Y1887756D02*
X192265Y1887752D01*
X192239Y1887741D01*
X192215Y1887723D01*
X192194Y1887698D01*
X192177Y1887669D01*
X192164Y1887635D01*
X192156Y1887598D01*
X192154Y1887559D01*
G01X197598Y1867384D02*
X191280D01*
G01X191542Y1867581D02*
X197350D01*
G01X197341Y1868071D02*
X191256D01*
G01X197588Y1868268D02*
X190976D01*
G01Y1868661D02*
X197588D01*
G01X197341Y1868858D02*
X191256D01*
G01X191542Y1869352D02*
X197350D01*
G01X191280Y1869549D02*
X197598D01*
G01Y1870533D02*
X191280D01*
G01X191542Y1870730D02*
X197350D01*
G01X197341Y1871220D02*
X191256D01*
G01X197588Y1871417D02*
X190976D01*
G01Y1871811D02*
X197588D01*
G01X197341Y1872008D02*
X191256D01*
G01X191542Y1872502D02*
X197350D01*
G01X191280Y1872699D02*
X197598D01*
G01Y1873683D02*
X191280D01*
G01X191542Y1873880D02*
X197350D01*
G01X197341Y1874370D02*
X191256D01*
G01X197588Y1874567D02*
X190976D01*
G01Y1874961D02*
X197588D01*
G01X197341Y1875157D02*
X191256D01*
G01X191542Y1875652D02*
X197350D01*
G01X191280Y1875848D02*
X197598D01*
G01Y1876833D02*
X191280D01*
G01X191542Y1877030D02*
X197350D01*
G01X197341Y1877520D02*
X191256D01*
G01X197588Y1877717D02*
X190976D01*
G01Y1878110D02*
X197588D01*
G01X197341Y1878307D02*
X191256D01*
G01X195106Y1879390D02*
X201575D01*
G01X197410Y1880177D02*
X191497D01*
G01X197341Y1880669D02*
X191256D01*
G01X191074Y1880768D02*
X197816D01*
G01X197588Y1880866D02*
X190976D01*
G01X191074Y1881161D02*
X197816D01*
G01X190976Y1881260D02*
X197588D01*
G01X197341Y1881457D02*
X191256D01*
G01X197410Y1881752D02*
X191497D01*
G01X197341Y1883819D02*
X191256D01*
G01X197588Y1884016D02*
X190976D01*
G01Y1884409D02*
X197588D01*
G01X197341Y1884606D02*
X191256D01*
G01X197311Y1885177D02*
X191565D01*
G01X191139Y1885768D02*
X197725D01*
G01X191139Y1886161D02*
X197725D01*
G01X197311Y1886752D02*
X191565D01*
G01X197341Y1886969D02*
X191256D01*
G01X197588Y1887165D02*
X190976D01*
G01Y1887559D02*
X197588D01*
G01X197341Y1887756D02*
X191256D01*
G01X197341Y1890118D02*
X191256D01*
G01X197311Y1890177D02*
X191565D01*
G01X197588Y1890315D02*
X190976D01*
G01Y1890709D02*
X197588D01*
G01X191139Y1890768D02*
X197725D01*
G01X197341Y1890906D02*
X191256D01*
G01X191139Y1891161D02*
X197725D01*
G01X197311Y1891752D02*
X191565D01*
G01X197341Y1893268D02*
X191256D01*
G01X197588Y1893465D02*
X190976D01*
G01Y1893858D02*
X197588D01*
G01X197341Y1894055D02*
X191256D01*
G01X199279Y1895177D02*
X193534D01*
G01X193107Y1895768D02*
X199693D01*
G01X193107Y1896161D02*
X199693D01*
G01X197341Y1896417D02*
X191256D01*
G01X197588Y1896614D02*
X190976D01*
G01X199279Y1896752D02*
X193534D01*
G01X190976Y1897008D02*
X197588D01*
G01X197341Y1897205D02*
X191256D01*
G01X197341Y1899567D02*
X191256D01*
G01X197588Y1899764D02*
X190976D01*
G01Y1900157D02*
X197588D01*
G01X197311Y1900177D02*
X191565D01*
G01X197341Y1900354D02*
X191256D01*
G01X191139Y1900768D02*
X197725D01*
G01X191139Y1901161D02*
X197725D01*
G01X197311Y1901752D02*
X191565D01*
G01X197341Y1902717D02*
X191256D01*
G01X197588Y1902913D02*
X190976D01*
G01Y1903307D02*
X197588D01*
G01X197341Y1903504D02*
X191256D01*
G01X197311Y1905177D02*
X191565D01*
G01X197341Y1880669D02*
X197468Y1880697D01*
X197557Y1880770D01*
X197588Y1880866D01*
G01X197341Y1883819D02*
X197468Y1883846D01*
X197557Y1883919D01*
X197588Y1884016D01*
G01X197341Y1886969D02*
X197468Y1886996D01*
X197557Y1887069D01*
X197588Y1887165D01*
G01X197341Y1890118D02*
X197468Y1890146D01*
X197557Y1890219D01*
X197588Y1890315D01*
G01X197341Y1893268D02*
X197468Y1893295D01*
X197557Y1893368D01*
X197588Y1893465D01*
G01X197341Y1896417D02*
X197468Y1896445D01*
X197557Y1896518D01*
X197588Y1896614D01*
G01X197341Y1899567D02*
X197468Y1899594D01*
X197557Y1899667D01*
X197588Y1899764D01*
G01X197341Y1902717D02*
X197468Y1902744D01*
X197557Y1902817D01*
X197588Y1902913D01*
G01X192292Y1890906D02*
X192265Y1890902D01*
X192239Y1890891D01*
X192215Y1890872D01*
X192194Y1890848D01*
X192177Y1890818D01*
X192164Y1890784D01*
X192156Y1890748D01*
X192154Y1890709D01*
G01X192292Y1894055D02*
X192265Y1894051D01*
X192239Y1894040D01*
X192215Y1894022D01*
X192194Y1893997D01*
X192177Y1893968D01*
X192164Y1893934D01*
X192156Y1893897D01*
X192154Y1893858D01*
G01X192292Y1897205D02*
X192265Y1897201D01*
X192239Y1897190D01*
X192215Y1897172D01*
X192194Y1897147D01*
X192177Y1897117D01*
X192164Y1897083D01*
X192156Y1897047D01*
X192154Y1897008D01*
G01X192292Y1900354D02*
X192265Y1900350D01*
X192239Y1900339D01*
X192215Y1900321D01*
X192194Y1900296D01*
X192177Y1900267D01*
X192164Y1900233D01*
X192156Y1900196D01*
X192154Y1900157D01*
G01X192292Y1903504D02*
X192265Y1903500D01*
X192239Y1903489D01*
X192215Y1903471D01*
X192194Y1903446D01*
X192177Y1903417D01*
X192164Y1903383D01*
X192156Y1903346D01*
X192154Y1903307D01*
G01X197311Y1945177D02*
X197450Y1945373D01*
X197588Y1945570D01*
X197725Y1945768D01*
G01X197311Y1940177D02*
X197450Y1940373D01*
X197588Y1940570D01*
X197725Y1940768D01*
G01X191565Y1941752D02*
X191139Y1941161D01*
G01X191983D02*
X192255Y1941752D01*
G01X192667Y1944252D02*
X192677Y1944350D01*
X192705Y1944422D01*
X192743Y1944449D01*
G01X192667Y1941102D02*
X192677Y1941201D01*
X192705Y1941273D01*
X192743Y1941299D01*
G01X193107Y1941161D02*
X193185Y1941752D01*
G01X190976Y1944252D02*
Y1943858D01*
G01Y1941102D02*
Y1940709D01*
G01X191139Y1940768D02*
Y1941161D01*
G01X191983Y1940768D02*
Y1941161D01*
G01X192154Y1944252D02*
Y1943858D01*
G01Y1941102D02*
Y1940709D01*
G01X192667D02*
Y1941102D01*
G01Y1943858D02*
Y1944252D01*
G01X193107Y1941161D02*
Y1940768D01*
G01X197588Y1940709D02*
Y1941102D01*
G01Y1943858D02*
Y1944252D01*
G01X197725Y1941161D02*
Y1940768D01*
G01X192154Y1940709D02*
X192156Y1940670D01*
X192164Y1940633D01*
X192177Y1940600D01*
X192194Y1940569D01*
X192215Y1940545D01*
X192239Y1940527D01*
X192265Y1940516D01*
X192292Y1940512D01*
G01X192154Y1943858D02*
X192156Y1943820D01*
X192164Y1943783D01*
X192177Y1943749D01*
X192194Y1943719D01*
X192215Y1943694D01*
X192239Y1943676D01*
X192265Y1943665D01*
X192292Y1943661D01*
G01X193107Y1940768D02*
X193185Y1940177D01*
G01Y1945177D02*
X193107Y1945768D01*
G01X197588Y1941102D02*
X197556Y1941199D01*
X197468Y1941271D01*
X197341Y1941299D01*
G01X197588Y1944252D02*
X197556Y1944349D01*
X197468Y1944421D01*
X197341Y1944449D01*
G01X192255Y1940177D02*
X191983Y1940768D01*
G01X192255Y1945177D02*
X191983Y1945768D01*
G01X191565Y1940177D02*
X191139Y1940768D01*
G01X191565Y1945177D02*
X191139Y1945768D01*
G01X197725Y1941161D02*
X197588Y1941359D01*
X197450Y1941556D01*
X197311Y1941752D01*
G01X192743Y1940512D02*
X192705Y1940538D01*
X192677Y1940610D01*
X192667Y1940709D01*
G01X192743Y1943661D02*
X192705Y1943688D01*
X192677Y1943760D01*
X192667Y1943858D01*
G01X197341Y1940512D02*
X197468Y1940539D01*
X197557Y1940612D01*
X197588Y1940709D01*
G01X197341Y1943661D02*
X197468Y1943689D01*
X197557Y1943762D01*
X197588Y1943858D01*
G01X192292Y1941299D02*
X192265Y1941295D01*
X192239Y1941284D01*
X192215Y1941266D01*
X192194Y1941241D01*
X192177Y1941212D01*
X192164Y1941178D01*
X192156Y1941141D01*
X192154Y1941102D01*
G01X192292Y1944449D02*
X192265Y1944445D01*
X192239Y1944434D01*
X192215Y1944416D01*
X192194Y1944391D01*
X192177Y1944361D01*
X192164Y1944328D01*
X192156Y1944291D01*
X192154Y1944252D01*
G01X197311Y1940177D02*
X191565D01*
G01X197341Y1940512D02*
X191256D01*
G01X197588Y1940709D02*
X190976D01*
G01X191139Y1940768D02*
X197725D01*
G01X190976Y1941102D02*
X197588D01*
G01X191139Y1941161D02*
X197725D01*
G01X197341Y1941299D02*
X191256D01*
G01X197311Y1941752D02*
X191565D01*
G01X197341Y1943661D02*
X191256D01*
G01X197588Y1943858D02*
X190976D01*
G01Y1944252D02*
X197588D01*
G01X197341Y1944449D02*
X191256D01*
G01X197311Y1945177D02*
X191565D01*
G01X203601Y1967319D02*
X203637Y1967643D01*
X203631Y1967884D01*
X203575Y1968020D01*
G01X203601Y1967321D02*
X203547Y1966944D01*
G01X203575Y1968020D02*
X203632Y1967880D01*
X203637Y1967640D01*
G01X204858Y1959705D02*
X208268Y1961673D01*
G01X199606Y1954783D02*
X201575Y1956752D01*
G01X197311Y1950177D02*
X197450Y1950373D01*
X197588Y1950570D01*
X197725Y1950768D01*
G01X191565Y1951752D02*
X191139Y1951161D01*
G01X191565Y1946752D02*
X191139Y1946161D01*
G01X191983Y1951161D02*
X192255Y1951752D01*
G01X191983Y1946161D02*
X192255Y1946752D01*
G01X192667Y1950551D02*
X192677Y1950650D01*
X192705Y1950722D01*
X192743Y1950748D01*
G01X192667Y1947402D02*
X192677Y1947500D01*
X192705Y1947572D01*
X192743Y1947598D01*
G01X193107Y1951161D02*
X193185Y1951752D01*
G01Y1946752D02*
X193107Y1946161D01*
G01X190976Y1950551D02*
Y1950157D01*
G01Y1947402D02*
Y1947008D01*
G01X191139Y1945768D02*
Y1946161D01*
G01Y1950768D02*
Y1951161D01*
G01X191983Y1945768D02*
Y1946161D01*
G01Y1950768D02*
Y1951161D01*
G01X192154Y1950551D02*
Y1950157D01*
G01Y1947402D02*
Y1947008D01*
G01X192667D02*
Y1947402D01*
G01Y1950157D02*
Y1950551D01*
G01X193107Y1951161D02*
Y1950768D01*
G01Y1945768D02*
Y1946161D01*
G01X197588Y1947008D02*
Y1947402D01*
G01Y1950157D02*
Y1950551D01*
G01X197725Y1951161D02*
Y1950768D01*
G01Y1946161D02*
Y1945768D01*
G01X203543Y1959705D02*
Y1966870D01*
G01X208268Y1961673D02*
Y1963406D01*
G01X192154Y1947008D02*
X192156Y1946970D01*
X192164Y1946933D01*
X192177Y1946899D01*
X192194Y1946869D01*
X192215Y1946844D01*
X192239Y1946826D01*
X192265Y1946815D01*
X192292Y1946811D01*
G01X192154Y1950157D02*
X192156Y1950119D01*
X192164Y1950082D01*
X192177Y1950048D01*
X192194Y1950018D01*
X192215Y1949994D01*
X192239Y1949976D01*
X192265Y1949965D01*
X192292Y1949961D01*
G01X193107Y1950768D02*
X193185Y1950177D01*
G01X197588Y1947402D02*
X197556Y1947498D01*
X197468Y1947570D01*
X197341Y1947598D01*
G01X197588Y1950551D02*
X197556Y1950648D01*
X197468Y1950720D01*
X197341Y1950748D01*
G01X192255Y1950177D02*
X191983Y1950768D01*
G01X191565Y1950177D02*
X191139Y1950768D01*
G01X197725Y1946161D02*
X197588Y1946359D01*
X197450Y1946556D01*
X197311Y1946752D01*
G01X197725Y1951161D02*
X197588Y1951359D01*
X197450Y1951556D01*
X197311Y1951752D01*
G01X199606Y1959705D02*
X201575Y1957736D01*
G01X203547Y1966944D02*
X208268Y1962302D01*
G01Y1963406D02*
X203543Y1968051D01*
G01X192743Y1946811D02*
X192705Y1946837D01*
X192677Y1946909D01*
X192667Y1947008D01*
G01X192743Y1949961D02*
X192705Y1949987D01*
X192677Y1950059D01*
X192667Y1950157D01*
G01X197341Y1946811D02*
X197468Y1946839D01*
X197557Y1946911D01*
X197588Y1947008D01*
G01X197341Y1949961D02*
X197468Y1949988D01*
X197557Y1950061D01*
X197588Y1950157D01*
G01X192292Y1947598D02*
X192265Y1947594D01*
X192239Y1947583D01*
X192215Y1947565D01*
X192194Y1947541D01*
X192177Y1947511D01*
X192164Y1947477D01*
X192156Y1947441D01*
X192154Y1947402D01*
G01X192292Y1950748D02*
X192265Y1950744D01*
X192239Y1950733D01*
X192215Y1950715D01*
X192194Y1950690D01*
X192177Y1950661D01*
X192164Y1950627D01*
X192156Y1950590D01*
X192154Y1950551D01*
G01X191139Y1945768D02*
X197725D01*
G01X191139Y1946161D02*
X197725D01*
G01X197311Y1946752D02*
X191565D01*
G01X197341Y1946811D02*
X191256D01*
G01X197588Y1947008D02*
X190976D01*
G01Y1947402D02*
X197588D01*
G01X197341Y1947598D02*
X191256D01*
G01X197341Y1949961D02*
X191256D01*
G01X197588Y1950157D02*
X190976D01*
G01X197311Y1950177D02*
X191565D01*
G01X190976Y1950551D02*
X197588D01*
G01X197341Y1950748D02*
X191256D01*
G01X191139Y1950768D02*
X197725D01*
G01X191139Y1951161D02*
X197725D01*
G01X197311Y1951752D02*
X191565D01*
G01X204858Y1959705D02*
X201575D01*
G01X268566Y272631D02*
G03X282626I7030J-6888D01*
G01X259848Y265743D02*
G03X291344I15748J0D01*
G01X259848D02*
G03X291344I15748J0D01*
G01X259848D02*
Y279523D01*
G01Y265743D02*
Y279523D01*
G01X291344Y265743D02*
Y279523D01*
G01Y265743D02*
Y279523D01*
G01X281501D02*
G03X269690I-5906J0D01*
G01X281501D02*
G03X269690I-5906J0D01*
G01X283470D02*
G03X267722I-7874J0D01*
G01X289375D02*
G03X261816I-13780J0D01*
G01X291344D02*
G03X259848I-15748J0D01*
G01X291344D02*
G03X259848I-15748J0D01*
G01X266541D02*
G03I-984J0D01*
G01X267886Y284542D02*
G03I-984J0D01*
G01X268566Y272631D02*
G03X269690Y275387I-2813J2754D01*
G01Y277160D02*
Y279523D01*
G01D02*
Y275387D01*
G01X267722Y279523D02*
Y277160D01*
G01X261816Y279523D02*
Y277160D01*
G01D02*
X269690D01*
G01X271560Y288217D02*
G03I-984J0D01*
G01X285275Y284542D02*
G03I-985J0D01*
G01X286620Y279523D02*
G03I-985J0D01*
G01X281501Y275387D02*
G03X282626Y272631I3937J0D01*
G01X289375Y277160D02*
Y279523D01*
G01X283470Y277160D02*
Y279523D01*
G01X281501Y275387D02*
Y279523D01*
G01D02*
Y277160D01*
G01D02*
X289375D01*
G01X281600Y288217D02*
G03I-984J0D01*
G01X281499Y685025D02*
G03X269693I-5903J0D01*
G01X281501D02*
G03X269690I-5906J0D01*
G01X283470D02*
G03X267722I-7874J0D01*
G01X289375D02*
G03X261816I-13780J0D01*
G01X291344D02*
G03X259848I-15748J0D01*
G01X291344D02*
G03X259848I-15748J0D01*
G01X291344D02*
G03X259848I-15748J0D01*
G01X268567Y678135D02*
G03X282625I7029J-6890D01*
G01X259848Y671245D02*
G03X291344I15748J0D01*
G01X259848D02*
G03X291344I15748J0D01*
G01X259848D02*
G03X291344I15748J0D01*
G01X266541Y685025D02*
G03I-984J0D01*
G01X271560Y693719D02*
G03I-984J0D01*
G01X267886Y690044D02*
G03I-984J0D01*
G01X268567Y678135D02*
G03X269693Y680891I-2811J2757D01*
G01Y685025D02*
Y680891D01*
G01X269690Y682663D02*
Y685025D01*
G01X267722D02*
Y682663D01*
G01X261816Y685025D02*
Y682663D01*
G01X259848Y671245D02*
Y685025D01*
G01Y671245D02*
Y685025D01*
G01Y671245D02*
Y685025D01*
G01X261816Y682663D02*
X269690D01*
G01X285275Y690044D02*
G03I-985J0D01*
G01X281600Y693719D02*
G03I-984J0D01*
G01X286620Y685025D02*
G03I-985J0D01*
G01X281499Y680891D02*
G03X282625Y678135I3937J1D01*
G01X291344Y671245D02*
Y685025D01*
G01Y671245D02*
Y685025D01*
G01Y671245D02*
Y685025D01*
G01X289375Y682663D02*
Y685025D01*
G01X283470Y682663D02*
Y685025D01*
G01X281501D02*
Y682663D01*
G01X281499Y680891D02*
Y685025D01*
G01X281501Y682663D02*
X289375D01*
G01X268567Y1081678D02*
G03X282625I7029J-6890D01*
G01X259848Y1074789D02*
G03X291344I15748J0D01*
G01X259848D02*
G03X291344I15748J0D01*
G01X259848D02*
G03X291344I15748J0D01*
G01X268567Y1081678D02*
G03X269693Y1084434I-2811J2757D01*
G01Y1088568D02*
Y1084434D01*
G01X259848Y1074789D02*
Y1088568D01*
G01Y1074789D02*
Y1088568D01*
G01Y1074789D02*
Y1088568D01*
G01X281499D02*
G03X269693I-5903J0D01*
G01X281501D02*
G03X269690I-5906J0D01*
G01X283470D02*
G03X267722I-7874J0D01*
G01X289375D02*
G03X261816I-13780J0D01*
G01X291344D02*
G03X259848I-15748J0D01*
G01X291344D02*
G03X259848I-15748J0D01*
G01X291344D02*
G03X259848I-15748J0D01*
G01X266541D02*
G03I-984J0D01*
G01X271560Y1097262D02*
G03I-984J0D01*
G01X267886Y1093588D02*
G03I-984J0D01*
G01X261816Y1086206D02*
X269690D01*
G01D02*
Y1088568D01*
G01X267722D02*
Y1086206D01*
G01X261816Y1088568D02*
Y1086206D01*
G01X281499Y1084434D02*
G03X282625Y1081678I3937J1D01*
G01X291344Y1074789D02*
Y1088568D01*
G01Y1074789D02*
Y1088568D01*
G01Y1074789D02*
Y1088568D01*
G01X281499Y1084434D02*
Y1088568D01*
G01X285275Y1093588D02*
G03I-985J0D01*
G01X281600Y1097262D02*
G03I-984J0D01*
G01X286620Y1088568D02*
G03I-985J0D01*
G01X281501Y1086206D02*
X289375D01*
G01D02*
Y1088568D01*
G01X283470Y1086206D02*
Y1088568D01*
G01X281501D02*
Y1086206D01*
G01X276679Y1490153D02*
G03I-6989J0D01*
G01X268567Y1896639D02*
G03X282625I7029J-6890D01*
G01X259848Y1889749D02*
G03X291344I15748J0D01*
G01X259848D02*
G03X291344I15748J0D01*
G01X259848D02*
G03X291344I15748J0D01*
G01X281499Y1903529D02*
G03X269693I-5903J0D01*
G01X281501D02*
G03X269690I-5906J0D01*
G01X283470D02*
G03X267722I-7874J0D01*
G01X289375D02*
G03X261816I-13780J0D01*
G01X291344D02*
G03X259848I-15748J0D01*
G01X291344D02*
G03X259848I-15748J0D01*
G01X291344D02*
G03X259848I-15748J0D01*
G01X266541D02*
G03I-984J0D01*
G01X271560Y1912223D02*
G03I-984J0D01*
G01X267886Y1908548D02*
G03I-984J0D01*
G01X268567Y1896639D02*
G03X269693Y1899395I-2811J2757D01*
G01X261816Y1901166D02*
X269690D01*
G01X269693Y1903529D02*
Y1899395D01*
G01X269690Y1901166D02*
Y1903529D01*
G01X267722D02*
Y1901166D01*
G01X261816Y1903529D02*
Y1901166D01*
G01X259848Y1889749D02*
Y1903529D01*
G01Y1889749D02*
Y1903529D01*
G01Y1889749D02*
Y1903529D01*
G01X285275Y1908548D02*
G03I-985J0D01*
G01X281600Y1912223D02*
G03I-984J0D01*
G01X286620Y1903529D02*
G03I-985J0D01*
G01X281499Y1899395D02*
G03X282625Y1896639I3937J1D01*
G01X281501Y1901166D02*
X289375D01*
G01X291344Y1889749D02*
Y1903529D01*
G01Y1889749D02*
Y1903529D01*
G01Y1889749D02*
Y1903529D01*
G01X289375Y1901166D02*
Y1903529D01*
G01X283470Y1901166D02*
Y1903529D01*
G01X281501D02*
Y1901166D01*
G01X281499Y1899395D02*
Y1903529D01*
G01X395983Y-172119D02*
Y-191056D01*
G01Y2437400D02*
Y2418463D01*
G01X596235Y-172119D02*
X1777830D01*
G01X615652D02*
Y-191056D01*
G01Y2437400D02*
Y2418463D01*
G01X835322Y-172119D02*
Y-191056D01*
G01X815453Y182874D02*
X842028D01*
G01X823031Y186811D02*
X834449D01*
G01X838091Y188583D02*
X834449D01*
G01X823031D02*
X819390D01*
G01X838091Y189567D02*
X834449D01*
G01X823031D02*
X819390D01*
G01X838091Y191142D02*
X834449D01*
G01X823031D02*
X819390D01*
G01X838091Y192126D02*
X834449D01*
G01X823031D02*
X819390D01*
G01X815453Y202953D02*
Y182874D01*
G01X819390Y192126D02*
Y191142D01*
G01Y189567D02*
Y188583D01*
G01X821277Y192126D02*
Y191142D01*
G01Y189567D02*
Y188583D01*
G01X821358Y192126D02*
Y191142D01*
G01Y189567D02*
Y188583D01*
G01X822753Y192126D02*
Y191142D01*
G01Y189567D02*
Y188583D01*
G01X822835Y192126D02*
Y191142D01*
G01Y189567D02*
Y188583D01*
G01X823031Y199016D02*
Y186811D01*
G01X834449D02*
Y199016D01*
G01X834646Y192126D02*
Y191142D01*
G01Y189567D02*
Y188583D01*
G01X834727Y192126D02*
Y191142D01*
G01Y189567D02*
Y188583D01*
G01X836122Y192126D02*
Y191142D01*
G01Y189567D02*
Y188583D01*
G01X836204Y192126D02*
Y191142D01*
G01Y189567D02*
Y188583D01*
G01X838091Y192126D02*
Y191142D01*
G01Y189567D02*
Y188583D01*
G01Y193701D02*
X834449D01*
G01X823031D02*
X819390D01*
G01X838091Y194685D02*
X834449D01*
G01X823031D02*
X819390D01*
G01X838091Y196260D02*
X834449D01*
G01X823031D02*
X819390D01*
G01X818691Y196417D02*
X818597D01*
G01Y197165D02*
X818691D01*
G01X838091Y197244D02*
X834449D01*
G01X823031D02*
X819390D01*
G01X834449Y199016D02*
X823031D01*
G01X842028Y202953D02*
X815453D01*
G01X818504Y196926D02*
Y197054D01*
G01X818597Y196417D02*
Y197038D01*
G01X818691Y197165D02*
Y196417D01*
G01X819390Y197244D02*
Y196260D01*
G01Y194685D02*
Y193701D01*
G01X821277Y197244D02*
Y196260D01*
G01Y194685D02*
Y193701D01*
G01X821358Y197244D02*
Y196260D01*
G01Y194685D02*
Y193701D01*
G01X822753Y197244D02*
Y196260D01*
G01Y194685D02*
Y193701D01*
G01X822835Y197244D02*
Y196260D01*
G01Y194685D02*
Y193701D01*
G01X834646Y197244D02*
Y196260D01*
G01Y194685D02*
Y193701D01*
G01X834727Y197244D02*
Y196260D01*
G01Y194685D02*
Y193701D01*
G01X836122Y197244D02*
Y196260D01*
G01Y194685D02*
Y193701D01*
G01X836204Y197244D02*
Y196260D01*
G01Y194685D02*
Y193701D01*
G01X838091Y197244D02*
Y196260D01*
G01Y194685D02*
Y193701D01*
G01X818504Y197054D02*
X818597Y197165D01*
G01Y197038D02*
X818504Y196926D01*
G01X825394Y196850D02*
G03I-591J0D01*
G01X818504Y1811227D02*
X818597Y1811339D01*
G01Y1811211D02*
X818504Y1811100D01*
G01X815453Y1817126D02*
Y1797047D01*
G01X818504Y1811100D02*
Y1811227D01*
G01X818597Y1810591D02*
Y1811211D01*
G01X818691Y1811339D02*
Y1810591D01*
G01X819390Y1811417D02*
Y1810433D01*
G01Y1808858D02*
Y1807874D01*
G01Y1806299D02*
Y1805315D01*
G01Y1803740D02*
Y1802756D01*
G01X821277Y1811417D02*
Y1810433D01*
G01Y1808858D02*
Y1807874D01*
G01Y1806299D02*
Y1805315D01*
G01Y1803740D02*
Y1802756D01*
G01X821358Y1811417D02*
Y1810433D01*
G01Y1808858D02*
Y1807874D01*
G01Y1806299D02*
Y1805315D01*
G01Y1803740D02*
Y1802756D01*
G01X822753Y1811417D02*
Y1810433D01*
G01Y1808858D02*
Y1807874D01*
G01Y1806299D02*
Y1805315D01*
G01Y1803740D02*
Y1802756D01*
G01X822835Y1811417D02*
Y1810433D01*
G01Y1808858D02*
Y1807874D01*
G01Y1806299D02*
Y1805315D01*
G01Y1803740D02*
Y1802756D01*
G01X823031Y1813189D02*
Y1800984D01*
G01X834449D02*
Y1813189D01*
G01X834646Y1811417D02*
Y1810433D01*
G01Y1808858D02*
Y1807874D01*
G01Y1806299D02*
Y1805315D01*
G01Y1803740D02*
Y1802756D01*
G01X834727Y1811417D02*
Y1810433D01*
G01Y1808858D02*
Y1807874D01*
G01Y1806299D02*
Y1805315D01*
G01Y1803740D02*
Y1802756D01*
G01X836122Y1811417D02*
Y1810433D01*
G01Y1808858D02*
Y1807874D01*
G01Y1806299D02*
Y1805315D01*
G01Y1803740D02*
Y1802756D01*
G01X836204Y1811417D02*
Y1810433D01*
G01Y1808858D02*
Y1807874D01*
G01Y1806299D02*
Y1805315D01*
G01Y1803740D02*
Y1802756D01*
G01X838091Y1811417D02*
Y1810433D01*
G01Y1808858D02*
Y1807874D01*
G01Y1806299D02*
Y1805315D01*
G01Y1803740D02*
Y1802756D01*
G01X815453Y1797047D02*
X842028D01*
G01X823031Y1800984D02*
X834449D01*
G01X838091Y1802756D02*
X834449D01*
G01X823031D02*
X819390D01*
G01X838091Y1803740D02*
X834449D01*
G01X823031D02*
X819390D01*
G01X838091Y1805315D02*
X834449D01*
G01X823031D02*
X819390D01*
G01X838091Y1806299D02*
X834449D01*
G01X823031D02*
X819390D01*
G01X838091Y1807874D02*
X834449D01*
G01X823031D02*
X819390D01*
G01X838091Y1808858D02*
X834449D01*
G01X823031D02*
X819390D01*
G01X838091Y1810433D02*
X834449D01*
G01X823031D02*
X819390D01*
G01X818691Y1810591D02*
X818597D01*
G01Y1811339D02*
X818691D01*
G01X838091Y1811417D02*
X834449D01*
G01X823031D02*
X819390D01*
G01X834449Y1813189D02*
X823031D01*
G01X842028Y1817126D02*
X815453D01*
G01X825394Y1811023D02*
G03I-591J0D01*
G01X835322Y2437400D02*
Y2418463D01*
G01X907795Y173898D02*
X891417D01*
G01X901772Y178228D02*
X897441D01*
G01X902397Y179016D02*
X896815D01*
G01Y180591D02*
X902397D01*
G01X897441Y181378D02*
X901772D01*
G01X907795Y184075D02*
X891417D01*
G01X905512Y188012D02*
X931890D01*
G01X894943Y188051D02*
X898856D01*
G01X900775D02*
X901661D01*
G01X898856Y188789D02*
X895977D01*
G01X895239Y192259D02*
X896050D01*
G01X892118Y193154D02*
X892400Y192976D01*
X892588Y192711D01*
X892655Y192409D01*
X892590Y192108D01*
X892405Y191841D01*
X892119Y191660D01*
X891769Y191594D01*
G01X897296Y193149D02*
X897576Y192968D01*
G01X892192Y190852D02*
X892552Y190616D01*
X892791Y190266D01*
X892876Y189862D01*
X892794Y189460D01*
X892557Y189108D01*
X892194Y188868D01*
X891769Y188783D01*
G01X897575Y192969D02*
X897758Y192704D01*
X897822Y192405D01*
X897757Y192108D01*
G01X891417Y186831D02*
Y173898D01*
G01X894943Y188494D02*
Y188051D01*
G01X895239Y192406D02*
Y192259D01*
G01X896050D02*
Y192406D01*
G01X896815Y180591D02*
Y179016D01*
G01X896850D02*
Y180591D01*
G01X896874Y179016D02*
Y180591D01*
G01X898198D02*
Y179016D01*
G01X898567D02*
Y180591D01*
G01X898856Y188051D02*
Y188789D01*
G01X900645Y180591D02*
Y179016D01*
G01X901015D02*
Y180591D01*
G01X901575Y192579D02*
Y188799D01*
G01X902338Y180591D02*
Y179016D01*
G01X902362Y180591D02*
Y179016D01*
G01X902397D02*
Y180591D01*
G01X905512Y186831D02*
Y195177D01*
G01X907795Y173898D02*
Y200295D01*
G01X895239Y192406D02*
X895325Y192883D01*
X895573Y193326D01*
X895961Y193677D01*
X896468Y193897D01*
X897045Y193954D01*
X897609Y193831D01*
X898085Y193549D01*
X898424Y193144D01*
X898604Y192687D01*
X898619Y192207D01*
X898462Y191737D01*
X898147Y191320D01*
G01X896118Y192711D02*
X896050Y192406D01*
G01X897576Y191844D02*
X897759Y192110D01*
X897822Y192407D01*
X897757Y192705D01*
G01X896307Y192978D02*
X896118Y192710D01*
G01X898147Y191320D02*
X898484Y191781D01*
X898630Y192300D01*
X898570Y192818D01*
X898319Y193301D01*
X897882Y193696D01*
X897309Y193919D01*
X896674Y193938D01*
X896090Y193752D01*
X895635Y193399D01*
X895342Y192927D01*
X895239Y192406D01*
G01X897576Y191844D02*
X896013Y190317D01*
G01X898147Y191320D02*
X896519Y189773D01*
G01X892192Y188867D02*
X892552Y189103D01*
X892791Y189453D01*
X892876Y189857D01*
X892794Y190259D01*
X892557Y190611D01*
X892194Y190851D01*
X891769Y190936D01*
G01X892118Y191659D02*
X892400Y191837D01*
X892588Y192102D01*
X892655Y192404D01*
X892590Y192704D01*
X892405Y192971D01*
X892119Y193153D01*
X891769Y193219D01*
G01X896307Y192978D02*
X896594Y193156D01*
X896948Y193218D01*
G01X896013Y190317D02*
G03X894943Y188494I2809J-2874D01*
G01X896519Y189773D02*
G03X895977Y188789I1276J-1344D01*
G01X897441Y181378D02*
G03Y178228I0J-1575D01*
G01X903875Y193292D02*
G03X901661Y188051I7142J-6105D01*
G01X902989Y193219D02*
G03X900775Y188051I6938J-6031D01*
G01X901772Y178228D02*
G03Y181378I0J1575D01*
G01X896457Y159252D02*
X902756D01*
G01X898031Y159547D02*
X894882D01*
G01X901181D02*
X904331D01*
G01X896561Y160024D02*
X896467D01*
G01Y160772D02*
X896561D01*
G01X904331Y161516D02*
X901181D01*
G01X894882D02*
X898031D01*
G01X904331Y162106D02*
X901181D01*
G01X894882D02*
X898031D01*
G01Y164075D02*
X894882D01*
G01X901181D02*
X904331D01*
G01X902756Y164370D02*
X896457D01*
G01X894882Y164075D02*
Y162106D01*
G01Y159547D02*
Y161516D01*
G01X896374Y160533D02*
Y160660D01*
G01X896457Y164370D02*
Y163780D01*
G01Y162598D02*
Y161024D01*
G01Y159843D02*
Y159252D01*
G01X896467Y160024D02*
Y160644D01*
G01X896561Y160772D02*
Y160024D01*
G01X897441Y159252D02*
Y164370D01*
G01X897638D02*
Y159252D01*
G01X898031Y161516D02*
Y159547D01*
G01Y162106D02*
Y164075D01*
G01X901181Y161516D02*
Y159547D01*
G01Y162106D02*
Y164075D01*
G01X901575Y164370D02*
Y159252D01*
G01X901772D02*
Y164370D01*
G01X902756Y159252D02*
Y159843D01*
G01Y163780D02*
Y164370D01*
G01Y161024D02*
Y162598D01*
G01X904331Y164075D02*
Y162106D01*
G01Y159547D02*
Y161516D01*
G01X896374Y160660D02*
X896467Y160772D01*
G01Y160644D02*
X896374Y160533D01*
G01X896457Y162598D02*
G03Y163780I0J591D01*
G01Y159843D02*
G03Y161024I0J591D01*
G01X902756Y163780D02*
G03Y162598I0J-591D01*
G01Y161024D02*
G03Y159843I0J-591D01*
G01X931890Y186831D02*
X877953D01*
G01X880327Y188051D02*
X881213D01*
G01X901575Y188799D02*
X877953D01*
G01X901575Y192579D02*
X877953D01*
G01X886253Y191659D02*
X885970Y191837D01*
X885783Y192102D01*
X885716Y192404D01*
X885780Y192704D01*
X885966Y192971D01*
X886251Y193153D01*
X886602Y193219D01*
G01X886951Y193154D02*
X887233Y192976D01*
X887420Y192711D01*
X887487Y192409D01*
X887423Y192108D01*
X887237Y191841D01*
X886952Y191660D01*
X886602Y191594D01*
G01X891420Y191659D02*
X891137Y191837D01*
X890950Y192102D01*
X890883Y192404D01*
X890948Y192704D01*
X891133Y192971D01*
X891419Y193153D01*
X891769Y193219D01*
G01X886179Y188867D02*
X885819Y189103D01*
X885580Y189453D01*
X885494Y189857D01*
X885577Y190259D01*
X885813Y190611D01*
X886177Y190851D01*
X886602Y190936D01*
G01X887025Y190852D02*
X887385Y190616D01*
X887624Y190266D01*
X887709Y189862D01*
X887626Y189460D01*
X887390Y189108D01*
X887026Y188868D01*
X886602Y188783D01*
G01X891346Y188867D02*
X890986Y189103D01*
X890747Y189453D01*
X890662Y189857D01*
X890744Y190259D01*
X890981Y190611D01*
X891344Y190851D01*
X891769Y190936D01*
G01X887800Y191307D02*
X888251Y190867D01*
X888521Y190331D01*
X888592Y189761D01*
X888450Y189197D01*
X888103Y188672D01*
X887576Y188279D01*
X886933Y188076D01*
X886254Y188078D01*
X885614Y188286D01*
X885091Y188683D01*
X884750Y189206D01*
X884611Y189767D01*
X884683Y190335D01*
X884954Y190869D01*
G01X892967Y191307D02*
X893419Y190867D01*
X893689Y190331D01*
X893759Y189761D01*
X893617Y189197D01*
X893270Y188672D01*
X892743Y188279D01*
X892100Y188076D01*
X891421Y188078D01*
X890781Y188286D01*
X890258Y188683D01*
X889917Y189206D01*
X889779Y189767D01*
X889850Y190335D01*
X890121Y190869D01*
G01X885404Y191307D02*
X885081Y191727D01*
X884919Y192210D01*
X884941Y192715D01*
X885143Y193192D01*
X885510Y193595D01*
X886017Y193863D01*
X886607Y193957D01*
X887197Y193859D01*
X887699Y193591D01*
X888063Y193187D01*
X888265Y192709D01*
X888284Y192204D01*
X888120Y191723D01*
X887800Y191307D01*
G01X890571D02*
X890249Y191727D01*
X890086Y192210D01*
X890108Y192715D01*
X890311Y193192D01*
X890678Y193595D01*
X891184Y193863D01*
X891775Y193957D01*
X892364Y193859D01*
X892867Y193591D01*
X893231Y193187D01*
X893432Y192709D01*
X893451Y192204D01*
X893287Y191723D01*
X892967Y191307D01*
G01X877953Y200512D02*
Y186831D01*
G01X887800Y191307D02*
X888122Y191727D01*
X888285Y192210D01*
X888263Y192715D01*
X888060Y193192D01*
X887693Y193595D01*
X887187Y193863D01*
X886596Y193957D01*
X886007Y193859D01*
X885504Y193591D01*
X885140Y193187D01*
X884939Y192709D01*
X884920Y192204D01*
X885083Y191723D01*
X885404Y191307D01*
G01X892967D02*
X893289Y191727D01*
X893452Y192210D01*
X893430Y192715D01*
X893227Y193192D01*
X892861Y193595D01*
X892354Y193863D01*
X891763Y193957D01*
X891174Y193859D01*
X890672Y193591D01*
X890307Y193187D01*
X890106Y192709D01*
X890087Y192204D01*
X890251Y191723D01*
X890571Y191307D01*
G01X885404D02*
X884952Y190867D01*
X884682Y190331D01*
X884612Y189761D01*
X884754Y189197D01*
X885100Y188672D01*
X885628Y188279D01*
X886270Y188076D01*
X886950Y188078D01*
X887590Y188286D01*
X888112Y188683D01*
X888454Y189206D01*
X888592Y189767D01*
X888520Y190335D01*
X888250Y190869D01*
G01X890571Y191307D02*
X890120Y190867D01*
X889850Y190331D01*
X889779Y189761D01*
X889921Y189197D01*
X890268Y188672D01*
X890795Y188279D01*
X891437Y188076D01*
X892117Y188078D01*
X892757Y188286D01*
X893280Y188683D01*
X893621Y189206D01*
X893759Y189767D01*
X893687Y190335D01*
X893417Y190869D01*
G01X886179Y190852D02*
X885819Y190616D01*
X885580Y190266D01*
X885494Y189862D01*
X885577Y189460D01*
X885813Y189108D01*
X886177Y188868D01*
X886602Y188783D01*
G01X887025Y188867D02*
X887385Y189103D01*
X887624Y189453D01*
X887709Y189857D01*
X887626Y190259D01*
X887390Y190611D01*
X887026Y190851D01*
X886602Y190936D01*
G01X891346Y190852D02*
X890986Y190616D01*
X890747Y190266D01*
X890662Y189862D01*
X890744Y189460D01*
X890981Y189108D01*
X891344Y188868D01*
X891769Y188783D01*
G01X886253Y193154D02*
X885970Y192976D01*
X885783Y192711D01*
X885716Y192409D01*
X885780Y192108D01*
X885966Y191841D01*
X886251Y191660D01*
X886602Y191594D01*
G01X886951Y191659D02*
X887233Y191837D01*
X887420Y192102D01*
X887487Y192404D01*
X887423Y192704D01*
X887237Y192971D01*
X886952Y193153D01*
X886602Y193219D01*
G01X891420Y193154D02*
X891137Y192976D01*
X890950Y192711D01*
X890883Y192409D01*
X890948Y192108D01*
X891133Y191841D01*
X891419Y191660D01*
X891769Y191594D01*
G01X883428Y193292D02*
G03X881213Y188051I7141J-6107D01*
G01X882542Y193219D02*
G03X880327Y188051I6937J-6032D01*
G01X894882Y191614D02*
G03I-4528J0D01*
G01X893858D02*
G03I-3504J0D01*
G01X893701D02*
G03I-3347J0D01*
G01X892520D02*
G03I-2166J0D01*
G01X842028Y202953D02*
Y182874D01*
G01X895669Y225295D02*
X894685D01*
G01X895669Y225492D02*
X894685D01*
G01X895669Y227343D02*
X894685D01*
G01X895669Y227539D02*
X894685D01*
G01X895669Y227933D02*
X894685D01*
G01X895669Y229902D02*
X894685D01*
G01X895669Y230295D02*
X894685D01*
G01X928910Y230315D02*
X909449D01*
G01X895669Y230492D02*
X894685D01*
G01X895669Y232343D02*
X894685D01*
G01X895669Y232539D02*
X894685D01*
G01X895669Y232933D02*
X894685D01*
G01X927953Y234311D02*
X901260D01*
G01X895669Y234902D02*
X894685D01*
G01X895669Y235295D02*
X894685D01*
G01X895669Y235492D02*
X894685D01*
G01X927953Y236654D02*
X909449D01*
G01X899213D02*
X898110D01*
G01X923452Y236673D02*
X901260D01*
G01X891678Y236772D02*
X899213D01*
G01X896219Y237264D02*
X894094D01*
G01X897203Y237559D02*
X896219D01*
G01X897203Y237756D02*
X896219D01*
G01X898110Y237953D02*
X892085D01*
G01X898110Y239134D02*
X892085D01*
G01X897203Y239331D02*
X896219D01*
G01X897203Y239528D02*
X896219D01*
G01X897203Y240709D02*
X896219D01*
G01X897203Y240906D02*
X896219D01*
G01X898110Y241102D02*
X892085D01*
G01X898110Y242283D02*
X892085D01*
G01X897203Y242480D02*
X896219D01*
G01X897203Y242677D02*
X896219D01*
G01X897203Y243858D02*
X896219D01*
G01X897203Y244055D02*
X896219D01*
G01X898110Y244252D02*
X892085D01*
G01X898110Y245433D02*
X892085D01*
G01X897203Y245630D02*
X896219D01*
G01X897203Y245827D02*
X896219D01*
G01X897203Y247008D02*
X896219D01*
G01X897203Y247205D02*
X896219D01*
G01X898110Y247402D02*
X892085D01*
G01X898110Y248583D02*
X892085D01*
G01X897203Y248780D02*
X896219D01*
G01X897203Y248976D02*
X896219D01*
G01X897203Y250157D02*
X896219D01*
G01X897203Y250354D02*
X896219D01*
G01X898110Y250551D02*
X892085D01*
G01X898110Y251732D02*
X892085D01*
G01X897203Y251929D02*
X896219D01*
G01X897203Y252126D02*
X896219D01*
G01X897203Y253307D02*
X896219D01*
G01X897203Y253504D02*
X896219D01*
G01X898110Y253701D02*
X892085D01*
G01X898110Y254882D02*
X892085D01*
G01X897203Y255079D02*
X896219D01*
G01X897203Y255276D02*
X896219D01*
G01Y255571D02*
X894094D01*
G01X899213Y256063D02*
X891678D01*
G01X923452Y256161D02*
X901260D01*
G01X899213Y256181D02*
X898110D01*
G01X909449D02*
X927953D01*
G01X895669Y257343D02*
X894685D01*
G01X895669Y257539D02*
X894685D01*
G01X895669Y257933D02*
X894685D01*
G01X927953Y258524D02*
X901260D01*
G01X895669Y259902D02*
X894685D01*
G01X895669Y260295D02*
X894685D01*
G01X895669Y260492D02*
X894685D01*
G01X895669Y262343D02*
X894685D01*
G01X895669Y262539D02*
X894685D01*
G01X928910Y262618D02*
X909449D01*
G01X895669Y262933D02*
X894685D01*
G01X895669Y264902D02*
X894685D01*
G01X891522Y265709D02*
Y264921D01*
G01Y262559D02*
Y261772D01*
G01Y259409D02*
Y258622D01*
G01Y256260D02*
Y255472D01*
G01Y253110D02*
Y252323D01*
G01Y249961D02*
Y249173D01*
G01Y246811D02*
Y246024D01*
G01Y243661D02*
Y242874D01*
G01Y240512D02*
Y239724D01*
G01Y237362D02*
Y236575D01*
G01Y234213D02*
Y233425D01*
G01Y231063D02*
Y230276D01*
G01Y227913D02*
Y227126D01*
G01X891678Y236772D02*
Y240591D01*
G01Y242795D02*
Y250039D01*
G01Y252244D02*
Y256063D01*
G01X892085Y254882D02*
Y253701D01*
G01Y251732D02*
Y250551D01*
G01Y248583D02*
Y247402D01*
G01Y245433D02*
Y244252D01*
G01Y242283D02*
Y241102D01*
G01Y239134D02*
Y237953D01*
G01X892104Y252244D02*
Y250039D01*
G01Y242795D02*
Y240591D01*
G01X892156Y236772D02*
Y256063D01*
G01X893506Y265709D02*
Y264921D01*
G01Y262559D02*
Y261772D01*
G01Y259409D02*
Y258622D01*
G01Y256260D02*
Y255472D01*
G01Y253110D02*
Y252323D01*
G01Y249961D02*
Y249173D01*
G01Y246811D02*
Y246024D01*
G01Y243661D02*
Y242874D01*
G01Y240512D02*
Y239724D01*
G01Y237362D02*
Y236575D01*
G01Y234213D02*
Y233425D01*
G01Y231063D02*
Y230276D01*
G01Y227913D02*
Y227126D01*
G01X893701Y264705D02*
Y263130D01*
G01Y259705D02*
Y258130D01*
G01Y234705D02*
Y233130D01*
G01Y229705D02*
Y228130D01*
G01X894685Y265492D02*
Y262343D01*
G01Y260492D02*
Y257343D01*
G01Y235492D02*
Y232343D01*
G01Y230492D02*
Y227343D01*
G01X895235Y254882D02*
Y253701D01*
G01Y251732D02*
Y250551D01*
G01Y248583D02*
Y247402D01*
G01Y245433D02*
Y244252D01*
G01Y242283D02*
Y241102D01*
G01Y239134D02*
Y237953D01*
G01X895512Y236772D02*
Y256063D01*
G01X895669Y265492D02*
Y262343D01*
G01Y260492D02*
Y257343D01*
G01Y235492D02*
Y232343D01*
G01Y230492D02*
Y227343D01*
G01X896219Y237264D02*
Y255571D01*
G01X896429Y256063D02*
Y236772D01*
G01X896654Y264705D02*
Y263130D01*
G01Y259705D02*
Y258130D01*
G01Y234705D02*
Y233130D01*
G01Y229705D02*
Y228130D01*
G01X896868Y227126D02*
Y227913D01*
G01Y233425D02*
Y234213D01*
G01Y230276D02*
Y231063D01*
G01Y236575D02*
Y237362D01*
G01Y242874D02*
Y243661D01*
G01Y239724D02*
Y240512D01*
G01Y246024D02*
Y246811D01*
G01Y252323D02*
Y253110D01*
G01Y249173D02*
Y249961D01*
G01Y255472D02*
Y256260D01*
G01Y261772D02*
Y262559D01*
G01Y258622D02*
Y259409D01*
G01Y264921D02*
Y265709D01*
G01X896929Y256063D02*
Y236772D01*
G01X897203Y255472D02*
Y253110D01*
G01Y252323D02*
Y249961D01*
G01Y249173D02*
Y246811D01*
G01Y246024D02*
Y243661D01*
G01Y242874D02*
Y240512D01*
G01Y239724D02*
Y237362D01*
G01X897244Y227126D02*
Y227913D01*
G01Y233425D02*
Y234213D01*
G01Y230276D02*
Y231063D01*
G01Y236575D02*
Y237362D01*
G01Y242874D02*
Y243661D01*
G01Y239724D02*
Y240512D01*
G01Y246024D02*
Y246811D01*
G01Y252323D02*
Y253110D01*
G01Y249173D02*
Y249961D01*
G01Y255472D02*
Y256260D01*
G01Y261772D02*
Y262559D01*
G01Y258622D02*
Y259409D01*
G01Y264921D02*
Y265709D01*
G01X897270Y227126D02*
Y227913D01*
G01Y233425D02*
Y234213D01*
G01Y230276D02*
Y231063D01*
G01Y236575D02*
Y237362D01*
G01Y242874D02*
Y243661D01*
G01Y239724D02*
Y240512D01*
G01Y246024D02*
Y246811D01*
G01Y252323D02*
Y253110D01*
G01Y249173D02*
Y249961D01*
G01Y255472D02*
Y256260D01*
G01Y261772D02*
Y262559D01*
G01Y258622D02*
Y259409D01*
G01Y264921D02*
Y265709D01*
G01X897717Y236772D02*
Y256063D01*
G01X898031D02*
Y236772D01*
G01X903228Y256161D02*
Y236673D01*
G01Y258524D02*
Y274862D01*
G01X898110Y227736D02*
G03X897717Y228130I-394J0D01*
G01Y229705D02*
G03X898110Y230098I-1J394D01*
G01Y232736D02*
G03X897717Y233130I-394J0D01*
G01Y234705D02*
G03X898110Y235098I-1J394D01*
G01Y257736D02*
G03X897717Y258130I-394J0D01*
G01Y259705D02*
G03X898110Y260098I-1J394D01*
G01Y262736D02*
G03X897717Y263130I-394J0D01*
G01Y264705D02*
G03X898110Y265098I-1J394D01*
G01X879724Y227126D02*
X887057D01*
G01X887204D02*
X899213D01*
G01Y227913D02*
X887204D01*
G01X887057D02*
X879724D01*
G01X890551Y228130D02*
X897717D01*
G01X890551Y229705D02*
X897717D01*
G01X879724Y230276D02*
X887057D01*
G01X887204D02*
X899213D01*
G01Y231063D02*
X887204D01*
G01X887057D02*
X879724D01*
G01X890551Y233130D02*
X897717D01*
G01X879724Y233425D02*
X887057D01*
G01X887204D02*
X899213D01*
G01Y234213D02*
X887204D01*
G01X887057D02*
X879724D01*
G01X890551Y234705D02*
X897717D01*
G01X879724Y236575D02*
X887057D01*
G01X887204D02*
X899213D01*
G01Y237362D02*
X887204D01*
G01X887057D02*
X879724D01*
G01Y239724D02*
X887057D01*
G01X887204D02*
X899213D01*
G01Y240512D02*
X887204D01*
G01X887057D02*
X879724D01*
G01X890221Y240591D02*
X892104D01*
G01Y242795D02*
X890221D01*
G01X879724Y242874D02*
X887057D01*
G01X887204D02*
X899213D01*
G01Y243661D02*
X887204D01*
G01X887057D02*
X879724D01*
G01Y246024D02*
X887057D01*
G01X887204D02*
X899213D01*
G01Y246811D02*
X887204D01*
G01X887057D02*
X879724D01*
G01Y249173D02*
X887057D01*
G01X887204D02*
X899213D01*
G01Y249961D02*
X887204D01*
G01X887057D02*
X879724D01*
G01X890221Y250039D02*
X892104D01*
G01Y252244D02*
X890221D01*
G01X879724Y252323D02*
X887057D01*
G01X887204D02*
X899213D01*
G01Y253110D02*
X887204D01*
G01X887057D02*
X879724D01*
G01Y255472D02*
X887057D01*
G01X887204D02*
X899213D01*
G01Y256260D02*
X887204D01*
G01X887057D02*
X879724D01*
G01X890551Y258130D02*
X897717D01*
G01X879724Y258622D02*
X887057D01*
G01X887204D02*
X899213D01*
G01Y259409D02*
X887204D01*
G01X887057D02*
X879724D01*
G01X890551Y259705D02*
X897717D01*
G01X879724Y261772D02*
X887057D01*
G01X887204D02*
X899213D01*
G01Y262559D02*
X887204D01*
G01X887057D02*
X879724D01*
G01X890551Y263130D02*
X897717D01*
G01X890551Y264705D02*
X897717D01*
G01X879724Y264921D02*
X887057D01*
G01X887204D02*
X899213D01*
G01X879724Y227126D02*
Y227913D01*
G01Y233425D02*
Y234213D01*
G01Y230276D02*
Y231063D01*
G01Y236575D02*
Y237362D01*
G01Y242874D02*
Y243661D01*
G01Y239724D02*
Y240512D01*
G01Y246024D02*
Y246811D01*
G01Y252323D02*
Y253110D01*
G01Y249173D02*
Y249961D01*
G01Y255472D02*
Y256260D01*
G01Y261772D02*
Y262559D01*
G01Y258622D02*
Y259409D01*
G01Y264921D02*
Y265709D01*
G01X881498Y227126D02*
Y227913D01*
G01Y233425D02*
Y234213D01*
G01Y230276D02*
Y231063D01*
G01Y236575D02*
Y237362D01*
G01Y242874D02*
Y243661D01*
G01Y239724D02*
Y240512D01*
G01Y246024D02*
Y246811D01*
G01Y252323D02*
Y253110D01*
G01Y249173D02*
Y249961D01*
G01Y255472D02*
Y256260D01*
G01Y261772D02*
Y262559D01*
G01Y258622D02*
Y259409D01*
G01Y264921D02*
Y265709D01*
G01X881686D02*
Y264921D01*
G01Y262559D02*
Y261772D01*
G01Y259409D02*
Y258622D01*
G01Y256260D02*
Y255472D01*
G01Y253110D02*
Y252323D01*
G01Y249961D02*
Y249173D01*
G01Y246811D02*
Y246024D01*
G01Y243661D02*
Y242874D01*
G01Y240512D02*
Y239724D01*
G01Y237362D02*
Y236575D01*
G01Y234213D02*
Y233425D01*
G01Y231063D02*
Y230276D01*
G01Y227913D02*
Y227126D01*
G01X884523Y265709D02*
Y264921D01*
G01Y262559D02*
Y261772D01*
G01Y259409D02*
Y258622D01*
G01Y256260D02*
Y255472D01*
G01Y253110D02*
Y252323D01*
G01Y249961D02*
Y249173D01*
G01Y246811D02*
Y246024D01*
G01Y243661D02*
Y242874D01*
G01Y240512D02*
Y239724D01*
G01Y237362D02*
Y236575D01*
G01Y234213D02*
Y233425D01*
G01Y231063D02*
Y230276D01*
G01Y227913D02*
Y227126D01*
G01X885464D02*
Y227913D01*
G01Y233425D02*
Y234213D01*
G01Y230276D02*
Y231063D01*
G01Y236575D02*
Y237362D01*
G01Y242874D02*
Y243661D01*
G01Y239724D02*
Y240512D01*
G01Y246024D02*
Y246811D01*
G01Y252323D02*
Y253110D01*
G01Y249173D02*
Y249961D01*
G01Y255472D02*
Y256260D01*
G01Y261772D02*
Y262559D01*
G01Y258622D02*
Y259409D01*
G01Y264921D02*
Y265709D01*
G01X887057Y227126D02*
Y227913D01*
G01Y233425D02*
Y234213D01*
G01Y230276D02*
Y231063D01*
G01Y236575D02*
Y237362D01*
G01Y242874D02*
Y243661D01*
G01Y239724D02*
Y240512D01*
G01Y246024D02*
Y246811D01*
G01Y252323D02*
Y253110D01*
G01Y249173D02*
Y249961D01*
G01Y255472D02*
Y256260D01*
G01Y261772D02*
Y262559D01*
G01Y258622D02*
Y259409D01*
G01Y264921D02*
Y265709D01*
G01X887204Y227126D02*
Y227913D01*
G01Y233425D02*
Y234213D01*
G01Y230276D02*
Y231063D01*
G01Y236575D02*
Y237362D01*
G01Y242874D02*
Y243661D01*
G01Y239724D02*
Y240512D01*
G01Y246024D02*
Y246811D01*
G01Y252323D02*
Y253110D01*
G01Y249173D02*
Y249961D01*
G01Y255472D02*
Y256260D01*
G01Y261772D02*
Y262559D01*
G01Y258622D02*
Y259409D01*
G01Y264921D02*
Y265709D01*
G01X888142Y264921D02*
Y262559D01*
G01Y261772D02*
Y259409D01*
G01Y258622D02*
Y256260D01*
G01Y255472D02*
Y253110D01*
G01Y252323D02*
Y249961D01*
G01Y249173D02*
Y246811D01*
G01Y246024D02*
Y243661D01*
G01Y242874D02*
Y240512D01*
G01Y239724D02*
Y237362D01*
G01Y236575D02*
Y234213D01*
G01Y233425D02*
Y231063D01*
G01Y230276D02*
Y227913D01*
G01X889870Y227126D02*
Y227913D01*
G01Y233425D02*
Y234213D01*
G01Y230276D02*
Y231063D01*
G01Y236575D02*
Y237362D01*
G01Y242874D02*
Y243661D01*
G01Y239724D02*
Y240512D01*
G01Y246024D02*
Y246811D01*
G01Y252323D02*
Y253110D01*
G01Y249173D02*
Y249961D01*
G01Y255472D02*
Y256260D01*
G01Y261772D02*
Y262559D01*
G01Y258622D02*
Y259409D01*
G01Y264921D02*
Y265709D01*
G01X890221Y240591D02*
Y242795D01*
G01Y250039D02*
Y252244D01*
G01X890551Y264705D02*
Y263130D01*
G01Y259705D02*
Y258130D01*
G01Y234705D02*
Y233130D01*
G01Y229705D02*
Y228130D01*
G01X895669Y265295D02*
X894685D01*
G01X895669Y265492D02*
X894685D01*
G01X899213Y265709D02*
X887204D01*
G01X887057D02*
X879724D01*
G01X888142Y268071D02*
Y265709D01*
G01X903139Y201417D02*
X903487Y201502D01*
G01X901484Y201673D02*
X901832Y201758D01*
G01X900037Y193219D02*
X902989D01*
G01X903875Y193957D02*
X900037D01*
G01X899213Y197480D02*
X893113D01*
G01Y197539D02*
X899213D01*
G01X898110Y199114D02*
X907480D01*
G01X899213Y199705D02*
X929921D01*
G01X927953Y200098D02*
X909449D01*
G01X907795Y200295D02*
X901260D01*
G01X898110Y200886D02*
X907480D01*
G01X901135Y201673D02*
X901484D01*
G01X901397Y202185D02*
X901222D01*
G01X895669Y202343D02*
X894685D01*
G01X895669Y202539D02*
X894685D01*
G01X895669Y202933D02*
X894685D01*
G01X902965Y204061D02*
X903226D01*
G01X903313Y204573D02*
X902878D01*
G01X895669Y204902D02*
X894685D01*
G01X901484Y205256D02*
X900787D01*
G01X895669Y205295D02*
X894685D01*
G01X895669Y205492D02*
X894685D01*
G01X904272Y205768D02*
X900874D01*
G01X900177Y206280D02*
X904272D01*
G01X895669Y207343D02*
X894685D01*
G01X895669Y207539D02*
X894685D01*
G01X895669Y207933D02*
X894685D01*
G01X895669Y209902D02*
X894685D01*
G01X895669Y210295D02*
X894685D01*
G01X895669Y210492D02*
X894685D01*
G01X895669Y212343D02*
X894685D01*
G01X895669Y212539D02*
X894685D01*
G01X895669Y212933D02*
X894685D01*
G01X895669Y214902D02*
X894685D01*
G01X895669Y215295D02*
X894685D01*
G01X895669Y215492D02*
X894685D01*
G01X927953Y216713D02*
X901260D01*
G01X895669Y217343D02*
X894685D01*
G01X895669Y217539D02*
X894685D01*
G01X895669Y217933D02*
X894685D01*
G01X927953Y219075D02*
X901260D01*
G01X895669Y219902D02*
X894685D01*
G01X895669Y220295D02*
X894685D01*
G01X895669Y220492D02*
X894685D01*
G01X895669Y222343D02*
X894685D01*
G01X895669Y222539D02*
X894685D01*
G01X895669Y222933D02*
X894685D01*
G01X895669Y224902D02*
X894685D01*
G01X896949Y193218D02*
X897296Y193149D01*
G01X900787Y201758D02*
X901135Y201673D01*
G01X901222Y202185D02*
X900961Y202270D01*
G01X903662Y204403D02*
X903313Y204573D01*
G01X903226Y204061D02*
X903487Y203891D01*
G01X900787Y205256D02*
X900177Y205768D01*
G01X900874D02*
X901484Y205256D01*
G01X900438Y202100D02*
X900787Y201758D01*
G01X904010Y204061D02*
X903662Y204403D01*
G01X900961Y202270D02*
X900787Y202526D01*
G01X903487Y203891D02*
X903662Y203635D01*
G01X892857Y197933D02*
X893113Y197539D01*
G01X900264Y202441D02*
X900438Y202100D01*
G01X904184Y203720D02*
X904010Y204061D01*
G01X900787Y202526D02*
X900700Y202782D01*
G01X900177D02*
X900264Y202441D01*
G01X903662Y203635D02*
X903749Y203294D01*
G01X904272D02*
X904184Y203720D01*
G01X891522Y224764D02*
Y223976D01*
G01Y221614D02*
Y220827D01*
G01Y218465D02*
Y217677D01*
G01Y215315D02*
Y214528D01*
G01Y212165D02*
Y211378D01*
G01Y209016D02*
Y208228D01*
G01Y205866D02*
Y205079D01*
G01X892474Y195177D02*
Y197933D01*
G01X893113Y197539D02*
Y197480D01*
G01X893506Y224764D02*
Y223976D01*
G01Y221614D02*
Y220827D01*
G01Y218465D02*
Y217677D01*
G01Y215315D02*
Y214528D01*
G01Y212165D02*
Y211378D01*
G01Y209016D02*
Y208228D01*
G01Y205866D02*
Y205079D01*
G01X893640Y200512D02*
Y332126D01*
G01X893701Y224705D02*
Y223130D01*
G01Y219705D02*
Y218130D01*
G01Y214705D02*
Y213130D01*
G01Y209705D02*
Y208130D01*
G01Y204705D02*
Y203130D01*
G01X894094Y197933D02*
Y334902D01*
G01X894685Y225492D02*
Y222343D01*
G01Y220492D02*
Y217343D01*
G01Y215492D02*
Y212343D01*
G01Y210492D02*
Y207343D01*
G01Y205492D02*
Y202343D01*
G01X895669Y225492D02*
Y222343D01*
G01Y220492D02*
Y217343D01*
G01Y215492D02*
Y212343D01*
G01Y210492D02*
Y207343D01*
G01Y205492D02*
Y202343D01*
G01Y197480D02*
Y195177D01*
G01X896654Y224705D02*
Y223130D01*
G01Y219705D02*
Y218130D01*
G01Y214705D02*
Y213130D01*
G01Y209705D02*
Y208130D01*
G01Y204705D02*
Y203130D01*
G01X896868Y205079D02*
Y205866D01*
G01Y208228D02*
Y209016D01*
G01Y214528D02*
Y215315D01*
G01Y211378D02*
Y212165D01*
G01Y217677D02*
Y218465D01*
G01Y223976D02*
Y224764D01*
G01Y220827D02*
Y221614D01*
G01X897244Y205079D02*
Y205866D01*
G01Y208228D02*
Y209016D01*
G01Y214528D02*
Y215315D01*
G01Y211378D02*
Y212165D01*
G01Y217677D02*
Y218465D01*
G01Y223976D02*
Y224764D01*
G01Y220827D02*
Y221614D01*
G01X897270Y205079D02*
Y205866D01*
G01Y208228D02*
Y209016D01*
G01Y214528D02*
Y215315D01*
G01Y211378D02*
Y212165D01*
G01Y217677D02*
Y218465D01*
G01Y223976D02*
Y224764D01*
G01Y220827D02*
Y221614D01*
G01X897657Y202953D02*
Y204921D01*
G01X898110Y197933D02*
Y334902D01*
G01X899213Y335354D02*
Y197480D01*
G01X900037Y193957D02*
Y193219D01*
G01X900177Y203209D02*
Y202782D01*
G01Y205768D02*
Y206280D01*
G01X900700Y202782D02*
Y203294D01*
G01X901135Y203806D02*
Y204317D01*
G01X901260Y200295D02*
Y332539D01*
G01X901575Y196988D02*
Y194547D01*
G01X901919Y203294D02*
Y202782D01*
G01X902442D02*
Y203294D01*
G01X903139Y201929D02*
Y201417D01*
G01X903228Y234311D02*
Y219075D01*
G01Y216713D02*
Y200295D01*
G01X903749Y203294D02*
Y202611D01*
G01X903875Y193292D02*
Y193957D01*
G01X904272Y206280D02*
Y205768D01*
G01Y202611D02*
Y203294D01*
G01X907480Y200886D02*
Y199114D01*
G01X909449Y332736D02*
Y200098D01*
G01X900264Y203635D02*
X900177Y203209D01*
G01X902006Y203720D02*
X901919Y203294D01*
G01X904184Y202185D02*
X904272Y202611D01*
G01X902442Y203294D02*
X902529Y203635D01*
G01X902355Y202441D02*
X902442Y202782D01*
G01X903749Y202611D02*
X903662Y202270D01*
G01X900700Y203294D02*
X900787Y203550D01*
G01X901919Y202782D02*
X901832Y202526D01*
G01X902181Y204061D02*
X902006Y203720D01*
G01X902181Y202100D02*
X902355Y202441D01*
G01X903923Y201758D02*
X904184Y202185D01*
G01X902529Y203635D02*
X902704Y203891D01*
G01X901832Y202526D02*
X901658Y202270D01*
G01X900526Y203976D02*
X900264Y203635D01*
G01X900787Y203550D02*
X900961Y203720D01*
G01X902529Y204403D02*
X902181Y204061D01*
G01X901832Y201758D02*
X902181Y202100D01*
G01X903662Y202270D02*
X903400Y202014D01*
G01X900874Y204232D02*
X900526Y203976D01*
G01X902704Y203891D02*
X902965Y204061D01*
G01X903487Y201502D02*
X903923Y201758D01*
G01X900961Y203720D02*
X901135Y203806D01*
G01X902878Y204573D02*
X902529Y204403D01*
G01X901135Y204317D02*
X900874Y204232D01*
G01X901658Y202270D02*
X901397Y202185D01*
G01X903400Y202014D02*
X903139Y201929D01*
G01X898110Y207736D02*
G03X897717Y208130I-394J0D01*
G01Y209705D02*
G03X898110Y210098I-1J394D01*
G01Y217736D02*
G03X897717Y218130I-394J0D01*
G01Y219705D02*
G03X898110Y220098I-1J394D01*
G01Y212736D02*
G03X897717Y213130I-394J0D01*
G01Y214705D02*
G03X898110Y215098I-1J394D01*
G01Y222736D02*
G03X897717Y223130I-394J0D01*
G01Y224705D02*
G03X898110Y225098I-1J394D01*
G01Y202736D02*
G03X897717Y203130I-394J0D01*
G01Y204705D02*
G03X898110Y205098I-1J394D01*
G01X879589Y193219D02*
X882542D01*
G01X883428Y193957D02*
X879589D01*
G01X877953Y194547D02*
X901575D01*
G01X927953Y195177D02*
X877953D01*
G01X901575Y196988D02*
X877953D01*
G01X878745Y197933D02*
X899213D01*
G01X898110Y200512D02*
X877953D01*
G01X894094Y202500D02*
X885110D01*
G01X889587Y202953D02*
X897657D01*
G01X890551Y203130D02*
X897717D01*
G01X890551Y204705D02*
X897717D01*
G01X897657Y204921D02*
X889587D01*
G01X879724Y205079D02*
X887057D01*
G01X887204D02*
X899213D01*
G01Y205866D02*
X887204D01*
G01X887057D02*
X879724D01*
G01X890551Y208130D02*
X897717D01*
G01X879724Y208228D02*
X887057D01*
G01X887204D02*
X899213D01*
G01Y209016D02*
X887204D01*
G01X887057D02*
X879724D01*
G01X890551Y209705D02*
X897717D01*
G01X879724Y211378D02*
X887057D01*
G01X887204D02*
X899213D01*
G01Y212165D02*
X887204D01*
G01X887057D02*
X879724D01*
G01X890551Y213130D02*
X897717D01*
G01X879724Y214528D02*
X887057D01*
G01X887204D02*
X899213D01*
G01X890551Y214705D02*
X897717D01*
G01X899213Y215315D02*
X887204D01*
G01X887057D02*
X879724D01*
G01Y217677D02*
X887057D01*
G01X887204D02*
X899213D01*
G01X890551Y218130D02*
X897717D01*
G01X899213Y218465D02*
X887204D01*
G01X887057D02*
X879724D01*
G01X890551Y219705D02*
X897717D01*
G01X879724Y220827D02*
X887057D01*
G01X887204D02*
X899213D01*
G01Y221614D02*
X887204D01*
G01X887057D02*
X879724D01*
G01X890551Y223130D02*
X897717D01*
G01X879724Y223976D02*
X887057D01*
G01X887204D02*
X899213D01*
G01X890551Y224705D02*
X897717D01*
G01X899213Y224764D02*
X887204D01*
G01X887057D02*
X879724D01*
G01X878270Y200512D02*
Y195177D01*
G01X878745Y200512D02*
Y197933D01*
G01X879589Y193957D02*
Y193219D01*
G01X879724Y205079D02*
Y205866D01*
G01Y208228D02*
Y209016D01*
G01Y214528D02*
Y215315D01*
G01Y211378D02*
Y212165D01*
G01Y217677D02*
Y218465D01*
G01Y223976D02*
Y224764D01*
G01Y220827D02*
Y221614D01*
G01X881498Y205079D02*
Y205866D01*
G01Y208228D02*
Y209016D01*
G01Y214528D02*
Y215315D01*
G01Y211378D02*
Y212165D01*
G01Y217677D02*
Y218465D01*
G01Y223976D02*
Y224764D01*
G01Y220827D02*
Y221614D01*
G01X881686Y224764D02*
Y223976D01*
G01Y221614D02*
Y220827D01*
G01Y218465D02*
Y217677D01*
G01Y215315D02*
Y214528D01*
G01Y212165D02*
Y211378D01*
G01Y209016D02*
Y208228D01*
G01Y205866D02*
Y205079D01*
G01X883428Y193292D02*
Y193957D01*
G01X884523Y224764D02*
Y223976D01*
G01Y221614D02*
Y220827D01*
G01Y218465D02*
Y217677D01*
G01Y215315D02*
Y214528D01*
G01Y212165D02*
Y211378D01*
G01Y209016D02*
Y208228D01*
G01Y205866D02*
Y205079D01*
G01X884600Y195177D02*
Y197933D01*
G01X885110Y334902D02*
Y197933D01*
G01X885464Y205079D02*
Y205866D01*
G01Y208228D02*
Y209016D01*
G01Y214528D02*
Y215315D01*
G01Y211378D02*
Y212165D01*
G01Y217677D02*
Y218465D01*
G01Y223976D02*
Y224764D01*
G01Y220827D02*
Y221614D01*
G01X887057Y205079D02*
Y205866D01*
G01Y208228D02*
Y209016D01*
G01Y214528D02*
Y215315D01*
G01Y211378D02*
Y212165D01*
G01Y217677D02*
Y218465D01*
G01Y223976D02*
Y224764D01*
G01Y220827D02*
Y221614D01*
G01X887204Y205079D02*
Y205866D01*
G01Y208228D02*
Y209016D01*
G01Y214528D02*
Y215315D01*
G01Y211378D02*
Y212165D01*
G01Y217677D02*
Y218465D01*
G01Y223976D02*
Y224764D01*
G01Y220827D02*
Y221614D01*
G01X888142Y227126D02*
Y224764D01*
G01Y223976D02*
Y221614D01*
G01Y220827D02*
Y218465D01*
G01Y217677D02*
Y215315D01*
G01Y214528D02*
Y212165D01*
G01Y211378D02*
Y209016D01*
G01Y208228D02*
Y205866D01*
G01Y205079D02*
Y202500D01*
G01X889587Y204921D02*
Y202953D01*
G01X889870Y205079D02*
Y205866D01*
G01Y208228D02*
Y209016D01*
G01Y214528D02*
Y215315D01*
G01Y211378D02*
Y212165D01*
G01Y217677D02*
Y218465D01*
G01Y223976D02*
Y224764D01*
G01Y220827D02*
Y221614D01*
G01X890551Y224705D02*
Y223130D01*
G01Y219705D02*
Y218130D01*
G01Y214705D02*
Y213130D01*
G01Y209705D02*
Y208130D01*
G01Y204705D02*
Y203130D01*
G01X895669Y285295D02*
X894685D01*
G01X895669Y285492D02*
X894685D01*
G01X895669Y287343D02*
X894685D01*
G01X895669Y287539D02*
X894685D01*
G01X895669Y287933D02*
X894685D01*
G01X895669Y289902D02*
X894685D01*
G01X895669Y290295D02*
X894685D01*
G01X895669Y290492D02*
X894685D01*
G01X895669Y292343D02*
X894685D01*
G01X895669Y292539D02*
X894685D01*
G01X895669Y292933D02*
X894685D01*
G01X927953Y293760D02*
X901260D01*
G01X895669Y294902D02*
X894685D01*
G01X895669Y295295D02*
X894685D01*
G01X895669Y295492D02*
X894685D01*
G01X927953Y296122D02*
X901260D01*
G01X895669Y297343D02*
X894685D01*
G01X895669Y297539D02*
X894685D01*
G01X895669Y297933D02*
X894685D01*
G01X895669Y299902D02*
X894685D01*
G01X895669Y300295D02*
X894685D01*
G01X895669Y300492D02*
X894685D01*
G01X895669Y302343D02*
X894685D01*
G01X895669Y302539D02*
X894685D01*
G01X895669Y302933D02*
X894685D01*
G01X895669Y304902D02*
X894685D01*
G01X895669Y305295D02*
X894685D01*
G01X895669Y305492D02*
X894685D01*
G01X895669Y307343D02*
X894685D01*
G01X895669Y307539D02*
X894685D01*
G01X895669Y307933D02*
X894685D01*
G01X895669Y309902D02*
X894685D01*
G01X895669Y310295D02*
X894685D01*
G01X895669Y310492D02*
X894685D01*
G01X899213Y311713D02*
X898110D01*
G01X897638Y312343D02*
X896654D01*
G01X897638Y312539D02*
X896654D01*
G01X927953Y312657D02*
X901260D01*
G01X897638Y312933D02*
X896654D01*
G01X898110Y313130D02*
X892520D01*
G01X898110Y314705D02*
X892520D01*
G01X897638Y314902D02*
X896654D01*
G01X927953Y315020D02*
X901260D01*
G01X897638Y315295D02*
X896654D01*
G01X897638Y315492D02*
X896654D01*
G01X899213Y316122D02*
X898110D01*
G01X895669Y317343D02*
X894685D01*
G01X895669Y317539D02*
X894685D01*
G01X895669Y317933D02*
X894685D01*
G01X895669Y319902D02*
X894685D01*
G01X895669Y320295D02*
X894685D01*
G01X895669Y320492D02*
X894685D01*
G01X895669Y322343D02*
X894685D01*
G01X895669Y322539D02*
X894685D01*
G01X895669Y322933D02*
X894685D01*
G01X895669Y324902D02*
X894685D01*
G01X895669Y325295D02*
X894685D01*
G01X895669Y325492D02*
X894685D01*
G01X895669Y327343D02*
X894685D01*
G01X895669Y327539D02*
X894685D01*
G01X895669Y327933D02*
X894685D01*
G01X895669Y329902D02*
X894685D01*
G01X895669Y330295D02*
X894685D01*
G01X895669Y330492D02*
X894685D01*
G01X898110Y331949D02*
X907480D01*
G01X907795Y332539D02*
X901260D01*
G01X927953Y332736D02*
X909449D01*
G01X929921Y333130D02*
X899213D01*
G01X898110Y333720D02*
X907480D01*
G01X893113Y335295D02*
X899213D01*
G01X893113Y335354D02*
X899213D01*
G01X892308Y338504D02*
X892326Y338448D01*
X892379Y338282D01*
X892457Y338024D01*
X892553Y337696D01*
X892658Y337323D01*
G01X891522Y328701D02*
Y327913D01*
G01Y325551D02*
Y324764D01*
G01Y322402D02*
Y321614D01*
G01Y319252D02*
Y318465D01*
G01Y316102D02*
Y315315D01*
G01Y312953D02*
Y312165D01*
G01Y309803D02*
Y309016D01*
G01Y306654D02*
Y305866D01*
G01Y303504D02*
Y302717D01*
G01Y300354D02*
Y299567D01*
G01Y297205D02*
Y296417D01*
G01Y294055D02*
Y293268D01*
G01Y290906D02*
Y290118D01*
G01Y287756D02*
Y286969D01*
G01X892474Y334902D02*
Y337657D01*
G01X892520Y314705D02*
Y313130D01*
G01X893113Y335354D02*
Y335295D01*
G01X893506Y328701D02*
Y327913D01*
G01Y325551D02*
Y324764D01*
G01Y322402D02*
Y321614D01*
G01Y319252D02*
Y318465D01*
G01Y316102D02*
Y315315D01*
G01Y312953D02*
Y312165D01*
G01Y309803D02*
Y309016D01*
G01Y306654D02*
Y305866D01*
G01Y303504D02*
Y302717D01*
G01Y300354D02*
Y299567D01*
G01Y297205D02*
Y296417D01*
G01Y294055D02*
Y293268D01*
G01Y290906D02*
Y290118D01*
G01Y287756D02*
Y286969D01*
G01X893701Y329705D02*
Y328130D01*
G01Y324705D02*
Y323130D01*
G01Y319705D02*
Y318130D01*
G01Y309705D02*
Y308130D01*
G01Y304705D02*
Y303130D01*
G01Y299705D02*
Y298130D01*
G01Y294705D02*
Y293130D01*
G01Y289705D02*
Y288130D01*
G01X894685Y330492D02*
Y327343D01*
G01Y325492D02*
Y322343D01*
G01Y320492D02*
Y317343D01*
G01Y310492D02*
Y307343D01*
G01Y305492D02*
Y302343D01*
G01Y300492D02*
Y297343D01*
G01Y295492D02*
Y292343D01*
G01Y290492D02*
Y287343D01*
G01X895669Y337657D02*
Y335354D01*
G01Y330492D02*
Y327343D01*
G01Y325492D02*
Y322343D01*
G01Y320492D02*
Y317343D01*
G01Y314705D02*
Y313130D01*
G01Y310492D02*
Y307343D01*
G01Y305492D02*
Y302343D01*
G01Y300492D02*
Y297343D01*
G01Y295492D02*
Y292343D01*
G01Y290492D02*
Y287343D01*
G01X896654Y329705D02*
Y328130D01*
G01Y324705D02*
Y323130D01*
G01Y319705D02*
Y318130D01*
G01Y315492D02*
Y312343D01*
G01Y309705D02*
Y308130D01*
G01Y304705D02*
Y303130D01*
G01Y299705D02*
Y298130D01*
G01Y294705D02*
Y293130D01*
G01Y289705D02*
Y288130D01*
G01X896868Y290118D02*
Y290906D01*
G01Y286969D02*
Y287756D01*
G01Y293268D02*
Y294055D01*
G01Y299567D02*
Y300354D01*
G01Y296417D02*
Y297205D01*
G01Y302717D02*
Y303504D01*
G01Y309016D02*
Y309803D01*
G01Y305866D02*
Y306654D01*
G01Y312165D02*
Y312953D01*
G01Y318465D02*
Y319252D01*
G01Y315315D02*
Y316102D01*
G01Y321614D02*
Y322402D01*
G01Y327913D02*
Y328701D01*
G01Y324764D02*
Y325551D01*
G01X897244Y290118D02*
Y290906D01*
G01Y286969D02*
Y287756D01*
G01Y293268D02*
Y294055D01*
G01Y299567D02*
Y300354D01*
G01Y296417D02*
Y297205D01*
G01Y302717D02*
Y303504D01*
G01Y309016D02*
Y309803D01*
G01Y305866D02*
Y306654D01*
G01Y312165D02*
Y312953D01*
G01Y318465D02*
Y319252D01*
G01Y315315D02*
Y316102D01*
G01Y321614D02*
Y322402D01*
G01Y327913D02*
Y328701D01*
G01Y324764D02*
Y325551D01*
G01X897270Y290118D02*
Y290906D01*
G01Y286969D02*
Y287756D01*
G01Y293268D02*
Y294055D01*
G01Y299567D02*
Y300354D01*
G01Y296417D02*
Y297205D01*
G01Y302717D02*
Y303504D01*
G01Y309016D02*
Y309803D01*
G01Y305866D02*
Y306654D01*
G01Y312165D02*
Y312953D01*
G01Y318465D02*
Y319252D01*
G01Y315315D02*
Y316102D01*
G01Y321614D02*
Y322402D01*
G01Y327913D02*
Y328701D01*
G01Y324764D02*
Y325551D01*
G01X897638Y315492D02*
Y312343D01*
G01X901575Y338287D02*
Y335886D01*
G01X903228Y296122D02*
Y312657D01*
G01Y315020D02*
Y332539D01*
G01X905512Y346004D02*
Y337657D01*
G01X907480Y333720D02*
Y331949D01*
G01X907795Y332539D02*
Y358937D01*
G01X893113Y335295D02*
X892857Y334902D01*
G01X892658Y337323D02*
G03Y345118I-2304J3898D01*
G01X892308Y338504D02*
G03Y343937I-1954J2717D01*
G01X898110Y297736D02*
G03X897717Y298130I-394J0D01*
G01Y299705D02*
G03X898110Y300098I-1J394D01*
G01Y302736D02*
G03X897717Y303130I-394J0D01*
G01Y304705D02*
G03X898110Y305098I-1J394D01*
G01Y292736D02*
G03X897717Y293130I-394J0D01*
G01Y294705D02*
G03X898110Y295098I-1J394D01*
G01Y287736D02*
G03X897717Y288130I-394J0D01*
G01Y289705D02*
G03X898110Y290098I-1J394D01*
G01Y322736D02*
G03X897717Y323130I-394J0D01*
G01Y324705D02*
G03X898110Y325098I-1J394D01*
G01Y317736D02*
G03X897717Y318130I-394J0D01*
G01Y319705D02*
G03X898110Y320098I-1J394D01*
G01Y327736D02*
G03X897717Y328130I-394J0D01*
G01Y329705D02*
G03X898110Y330098I-1J394D01*
G01Y307736D02*
G03X897717Y308130I-394J0D01*
G01Y309705D02*
G03X898110Y310098I-1J394D01*
G01X895669Y267343D02*
X894685D01*
G01X895669Y267539D02*
X894685D01*
G01X895669Y267933D02*
X894685D01*
G01X895669Y269902D02*
X894685D01*
G01X895669Y270295D02*
X894685D01*
G01X895669Y270492D02*
X894685D01*
G01X899213Y271713D02*
X898110D01*
G01X897638Y272343D02*
X896654D01*
G01X897638Y272539D02*
X896654D01*
G01X897638Y272933D02*
X896654D01*
G01X898110Y273130D02*
X892520D01*
G01X898110Y274705D02*
X892520D01*
G01X927953Y274862D02*
X901260D01*
G01X897638Y274902D02*
X896654D01*
G01X897638Y275295D02*
X896654D01*
G01X897638Y275492D02*
X896654D01*
G01X898110Y276122D02*
X899213D01*
G01X927953Y277224D02*
X901260D01*
G01X895669Y277343D02*
X894685D01*
G01X895669Y277539D02*
X894685D01*
G01X895669Y277933D02*
X894685D01*
G01X895669Y279902D02*
X894685D01*
G01X895669Y280295D02*
X894685D01*
G01X895669Y280492D02*
X894685D01*
G01X895669Y282343D02*
X894685D01*
G01X895669Y282539D02*
X894685D01*
G01X895669Y282933D02*
X894685D01*
G01X895669Y284902D02*
X894685D01*
G01X891522Y284606D02*
Y283819D01*
G01Y281457D02*
Y280669D01*
G01Y278307D02*
Y277520D01*
G01Y275157D02*
Y274370D01*
G01Y272008D02*
Y271220D01*
G01Y268858D02*
Y268071D01*
G01X892520Y274705D02*
Y273130D01*
G01X893506Y284606D02*
Y283819D01*
G01Y281457D02*
Y280669D01*
G01Y278307D02*
Y277520D01*
G01Y275157D02*
Y274370D01*
G01Y272008D02*
Y271220D01*
G01Y268858D02*
Y268071D01*
G01X893701Y284705D02*
Y283130D01*
G01Y279705D02*
Y278130D01*
G01Y269705D02*
Y268130D01*
G01X894685Y285492D02*
Y282343D01*
G01Y280492D02*
Y277343D01*
G01Y270492D02*
Y267343D01*
G01X895669Y285492D02*
Y282343D01*
G01Y280492D02*
Y277343D01*
G01Y274705D02*
Y273130D01*
G01Y270492D02*
Y267343D01*
G01X896654Y284705D02*
Y283130D01*
G01Y279705D02*
Y278130D01*
G01Y275492D02*
Y272343D01*
G01Y269705D02*
Y268130D01*
G01X896868Y271220D02*
Y272008D01*
G01Y268071D02*
Y268858D01*
G01Y274370D02*
Y275157D01*
G01Y280669D02*
Y281457D01*
G01Y277520D02*
Y278307D01*
G01Y283819D02*
Y284606D01*
G01X897244Y271220D02*
Y272008D01*
G01Y268071D02*
Y268858D01*
G01Y274370D02*
Y275157D01*
G01Y280669D02*
Y281457D01*
G01Y277520D02*
Y278307D01*
G01Y283819D02*
Y284606D01*
G01X897270Y271220D02*
Y272008D01*
G01Y268071D02*
Y268858D01*
G01Y274370D02*
Y275157D01*
G01Y280669D02*
Y281457D01*
G01Y277520D02*
Y278307D01*
G01Y283819D02*
Y284606D01*
G01X897638Y275492D02*
Y272343D01*
G01X903228Y277224D02*
Y293760D01*
G01X898110Y282736D02*
G03X897717Y283130I-394J0D01*
G01Y284705D02*
G03X898110Y285098I-1J394D01*
G01Y267736D02*
G03X897717Y268130I-394J0D01*
G01Y269705D02*
G03X898110Y270098I-1J394D01*
G01Y277736D02*
G03X897717Y278130I-394J0D01*
G01Y279705D02*
G03X898110Y280098I-1J394D01*
G01X879724Y286969D02*
X887057D01*
G01X887204D02*
X899213D01*
G01Y287756D02*
X887204D01*
G01X887057D02*
X879724D01*
G01X890551Y288130D02*
X897717D01*
G01X890551Y289705D02*
X897717D01*
G01X879724Y290118D02*
X887057D01*
G01X887204D02*
X899213D01*
G01Y290906D02*
X887204D01*
G01X887057D02*
X879724D01*
G01X890551Y293130D02*
X897717D01*
G01X879724Y293268D02*
X887057D01*
G01X887204D02*
X899213D01*
G01Y294055D02*
X887204D01*
G01X887057D02*
X879724D01*
G01X890551Y294705D02*
X897717D01*
G01X879724Y296417D02*
X887057D01*
G01X887204D02*
X899213D01*
G01Y297205D02*
X887204D01*
G01X887057D02*
X879724D01*
G01X890551Y298130D02*
X897717D01*
G01X879724Y299567D02*
X887057D01*
G01X887204D02*
X899213D01*
G01X890551Y299705D02*
X897717D01*
G01X899213Y300354D02*
X887204D01*
G01X887057D02*
X879724D01*
G01Y302717D02*
X887057D01*
G01X887204D02*
X899213D01*
G01X890551Y303130D02*
X897717D01*
G01X899213Y303504D02*
X887204D01*
G01X887057D02*
X879724D01*
G01X890551Y304705D02*
X897717D01*
G01X879724Y305866D02*
X887057D01*
G01X887204D02*
X899213D01*
G01Y306654D02*
X887204D01*
G01X887057D02*
X879724D01*
G01X890551Y308130D02*
X897717D01*
G01X879724Y309016D02*
X887057D01*
G01X887204D02*
X899213D01*
G01X890551Y309705D02*
X897717D01*
G01X899213Y309803D02*
X887204D01*
G01X887057D02*
X879724D01*
G01Y312165D02*
X887057D01*
G01X887204D02*
X899213D01*
G01Y312953D02*
X887204D01*
G01X887057D02*
X879724D01*
G01Y315315D02*
X887057D01*
G01X887204D02*
X899213D01*
G01Y316102D02*
X887204D01*
G01X887057D02*
X879724D01*
G01X890551Y318130D02*
X897717D01*
G01X879724Y318465D02*
X887057D01*
G01X887204D02*
X899213D01*
G01Y319252D02*
X887204D01*
G01X887057D02*
X879724D01*
G01X890551Y319705D02*
X897717D01*
G01X879724Y321614D02*
X887057D01*
G01X887204D02*
X899213D01*
G01Y322402D02*
X887204D01*
G01X887057D02*
X879724D01*
G01X890551Y323130D02*
X897717D01*
G01X890551Y324705D02*
X897717D01*
G01X879724Y324764D02*
X887057D01*
G01X887204D02*
X899213D01*
G01Y325551D02*
X887204D01*
G01X887057D02*
X879724D01*
G01Y327913D02*
X887057D01*
G01X887204D02*
X899213D01*
G01X890551Y328130D02*
X897717D01*
G01X899213Y328701D02*
X887204D01*
G01X887057D02*
X879724D01*
G01X890551Y329705D02*
X897717D01*
G01X894094Y330374D02*
X885110D01*
G01X877953Y332126D02*
X898110D01*
G01X878745Y334902D02*
X899213D01*
G01X877953Y335886D02*
X901575D01*
G01X888050Y337323D02*
X892658D01*
G01X927953Y337657D02*
X877953D01*
G01X901575Y338287D02*
X877953D01*
G01X892308Y338504D02*
X888400D01*
G01X877953Y346004D02*
Y332126D01*
G01X878270Y337657D02*
Y332126D01*
G01X878745Y334902D02*
Y332126D01*
G01X879724Y290118D02*
Y290906D01*
G01Y286969D02*
Y287756D01*
G01Y293268D02*
Y294055D01*
G01Y299567D02*
Y300354D01*
G01Y296417D02*
Y297205D01*
G01Y302717D02*
Y303504D01*
G01Y309016D02*
Y309803D01*
G01Y305866D02*
Y306654D01*
G01Y312165D02*
Y312953D01*
G01Y318465D02*
Y319252D01*
G01Y315315D02*
Y316102D01*
G01Y321614D02*
Y322402D01*
G01Y327913D02*
Y328701D01*
G01Y324764D02*
Y325551D01*
G01X881498Y290118D02*
Y290906D01*
G01Y286969D02*
Y287756D01*
G01Y293268D02*
Y294055D01*
G01Y299567D02*
Y300354D01*
G01Y296417D02*
Y297205D01*
G01Y302717D02*
Y303504D01*
G01Y309016D02*
Y309803D01*
G01Y305866D02*
Y306654D01*
G01Y312165D02*
Y312953D01*
G01Y318465D02*
Y319252D01*
G01Y315315D02*
Y316102D01*
G01Y321614D02*
Y322402D01*
G01Y327913D02*
Y328701D01*
G01Y324764D02*
Y325551D01*
G01X881686Y328701D02*
Y327913D01*
G01Y325551D02*
Y324764D01*
G01Y322402D02*
Y321614D01*
G01Y319252D02*
Y318465D01*
G01Y316102D02*
Y315315D01*
G01Y312953D02*
Y312165D01*
G01Y309803D02*
Y309016D01*
G01Y306654D02*
Y305866D01*
G01Y303504D02*
Y302717D01*
G01Y300354D02*
Y299567D01*
G01Y297205D02*
Y296417D01*
G01Y294055D02*
Y293268D01*
G01Y290906D02*
Y290118D01*
G01Y287756D02*
Y286969D01*
G01X884523Y328701D02*
Y327913D01*
G01Y325551D02*
Y324764D01*
G01Y322402D02*
Y321614D01*
G01Y319252D02*
Y318465D01*
G01Y316102D02*
Y315315D01*
G01Y312953D02*
Y312165D01*
G01Y309803D02*
Y309016D01*
G01Y306654D02*
Y305866D01*
G01Y303504D02*
Y302717D01*
G01Y300354D02*
Y299567D01*
G01Y297205D02*
Y296417D01*
G01Y294055D02*
Y293268D01*
G01Y290906D02*
Y290118D01*
G01Y287756D02*
Y286969D01*
G01X884600Y334902D02*
Y337657D01*
G01X885464Y290118D02*
Y290906D01*
G01Y286969D02*
Y287756D01*
G01Y293268D02*
Y294055D01*
G01Y299567D02*
Y300354D01*
G01Y296417D02*
Y297205D01*
G01Y302717D02*
Y303504D01*
G01Y309016D02*
Y309803D01*
G01Y305866D02*
Y306654D01*
G01Y312165D02*
Y312953D01*
G01Y318465D02*
Y319252D01*
G01Y315315D02*
Y316102D01*
G01Y321614D02*
Y322402D01*
G01Y327913D02*
Y328701D01*
G01Y324764D02*
Y325551D01*
G01X887057Y290118D02*
Y290906D01*
G01Y286969D02*
Y287756D01*
G01Y293268D02*
Y294055D01*
G01Y299567D02*
Y300354D01*
G01Y296417D02*
Y297205D01*
G01Y302717D02*
Y303504D01*
G01Y309016D02*
Y309803D01*
G01Y305866D02*
Y306654D01*
G01Y312165D02*
Y312953D01*
G01Y318465D02*
Y319252D01*
G01Y315315D02*
Y316102D01*
G01Y321614D02*
Y322402D01*
G01Y327913D02*
Y328701D01*
G01Y324764D02*
Y325551D01*
G01X887204Y290118D02*
Y290906D01*
G01Y286969D02*
Y287756D01*
G01Y293268D02*
Y294055D01*
G01Y299567D02*
Y300354D01*
G01Y296417D02*
Y297205D01*
G01Y302717D02*
Y303504D01*
G01Y309016D02*
Y309803D01*
G01Y305866D02*
Y306654D01*
G01Y312165D02*
Y312953D01*
G01Y318465D02*
Y319252D01*
G01Y315315D02*
Y316102D01*
G01Y321614D02*
Y322402D01*
G01Y327913D02*
Y328701D01*
G01Y324764D02*
Y325551D01*
G01X888142Y330374D02*
Y328701D01*
G01Y327913D02*
Y325551D01*
G01Y324764D02*
Y322402D01*
G01Y321614D02*
Y319252D01*
G01Y318465D02*
Y316102D01*
G01Y315315D02*
Y312953D01*
G01Y312165D02*
Y309803D01*
G01Y309016D02*
Y306654D01*
G01Y305866D02*
Y303504D01*
G01Y302717D02*
Y300354D01*
G01Y299567D02*
Y297205D01*
G01Y296417D02*
Y294055D01*
G01Y293268D02*
Y290906D01*
G01Y290118D02*
Y287756D01*
G01X889870Y290118D02*
Y290906D01*
G01Y286969D02*
Y287756D01*
G01Y293268D02*
Y294055D01*
G01Y299567D02*
Y300354D01*
G01Y296417D02*
Y297205D01*
G01Y302717D02*
Y303504D01*
G01Y309016D02*
Y309803D01*
G01Y305866D02*
Y306654D01*
G01Y312165D02*
Y312953D01*
G01Y318465D02*
Y319252D01*
G01Y315315D02*
Y316102D01*
G01Y321614D02*
Y322402D01*
G01Y327913D02*
Y328701D01*
G01Y324764D02*
Y325551D01*
G01X890551Y329705D02*
Y328130D01*
G01Y324705D02*
Y323130D01*
G01Y319705D02*
Y318130D01*
G01Y309705D02*
Y308130D01*
G01Y304705D02*
Y303130D01*
G01Y299705D02*
Y298130D01*
G01Y294705D02*
Y293130D01*
G01Y289705D02*
Y288130D01*
G01X888400Y338504D02*
X888382Y338448D01*
X888330Y338283D01*
X888251Y338024D01*
X888155Y337697D01*
X888050Y337323D01*
G01Y345118D02*
G03Y337323I2304J-3897D01*
G01X893858Y341220D02*
G03I-3504J0D01*
G01X888400Y343937D02*
G03Y338504I1954J-2716D01*
G01X879724Y268071D02*
X887057D01*
G01X887204D02*
X899213D01*
G01X890551Y268130D02*
X897717D01*
G01X899213Y268858D02*
X887204D01*
G01X887057D02*
X879724D01*
G01X890551Y269705D02*
X897717D01*
G01X879724Y271220D02*
X887057D01*
G01X887204D02*
X899213D01*
G01Y272008D02*
X887204D01*
G01X887057D02*
X879724D01*
G01Y274370D02*
X887057D01*
G01X887204D02*
X899213D01*
G01Y275157D02*
X887204D01*
G01X887057D02*
X879724D01*
G01Y277520D02*
X887057D01*
G01X887204D02*
X899213D01*
G01X890551Y278130D02*
X897717D01*
G01X899213Y278307D02*
X887204D01*
G01X887057D02*
X879724D01*
G01X890551Y279705D02*
X897717D01*
G01X879724Y280669D02*
X887057D01*
G01X887204D02*
X899213D01*
G01Y281457D02*
X887204D01*
G01X887057D02*
X879724D01*
G01X890551Y283130D02*
X897717D01*
G01X879724Y283819D02*
X887057D01*
G01X887204D02*
X899213D01*
G01Y284606D02*
X887204D01*
G01X887057D02*
X879724D01*
G01X890551Y284705D02*
X897717D01*
G01X879724Y271220D02*
Y272008D01*
G01Y268071D02*
Y268858D01*
G01Y274370D02*
Y275157D01*
G01Y280669D02*
Y281457D01*
G01Y277520D02*
Y278307D01*
G01Y283819D02*
Y284606D01*
G01X881498Y271220D02*
Y272008D01*
G01Y268071D02*
Y268858D01*
G01Y274370D02*
Y275157D01*
G01Y280669D02*
Y281457D01*
G01Y277520D02*
Y278307D01*
G01Y283819D02*
Y284606D01*
G01X881686D02*
Y283819D01*
G01Y281457D02*
Y280669D01*
G01Y278307D02*
Y277520D01*
G01Y275157D02*
Y274370D01*
G01Y272008D02*
Y271220D01*
G01Y268858D02*
Y268071D01*
G01X884523Y284606D02*
Y283819D01*
G01Y281457D02*
Y280669D01*
G01Y278307D02*
Y277520D01*
G01Y275157D02*
Y274370D01*
G01Y272008D02*
Y271220D01*
G01Y268858D02*
Y268071D01*
G01X885464Y271220D02*
Y272008D01*
G01Y268071D02*
Y268858D01*
G01Y274370D02*
Y275157D01*
G01Y280669D02*
Y281457D01*
G01Y277520D02*
Y278307D01*
G01Y283819D02*
Y284606D01*
G01X887057Y271220D02*
Y272008D01*
G01Y268071D02*
Y268858D01*
G01Y274370D02*
Y275157D01*
G01Y280669D02*
Y281457D01*
G01Y277520D02*
Y278307D01*
G01Y283819D02*
Y284606D01*
G01X887204Y271220D02*
Y272008D01*
G01Y268071D02*
Y268858D01*
G01Y274370D02*
Y275157D01*
G01Y280669D02*
Y281457D01*
G01Y277520D02*
Y278307D01*
G01Y283819D02*
Y284606D01*
G01X888142Y286969D02*
Y284606D01*
G01Y283819D02*
Y281457D01*
G01Y280669D02*
Y278307D01*
G01Y277520D02*
Y275157D01*
G01Y274370D02*
Y272008D01*
G01Y271220D02*
Y268858D01*
G01X889870Y271220D02*
Y272008D01*
G01Y268071D02*
Y268858D01*
G01Y274370D02*
Y275157D01*
G01Y280669D02*
Y281457D01*
G01Y277520D02*
Y278307D01*
G01Y283819D02*
Y284606D01*
G01X890551Y284705D02*
Y283130D01*
G01Y279705D02*
Y278130D01*
G01Y269705D02*
Y268130D01*
G01X907795Y348760D02*
X891417D01*
G01X901772Y351457D02*
X897441D01*
G01X902397Y352244D02*
X896815D01*
G01Y353819D02*
X902397D01*
G01X897441Y354606D02*
X901772D01*
G01X907795Y358937D02*
X891417D01*
G01D02*
Y346004D01*
G01X896815Y353819D02*
Y352244D01*
G01X896850D02*
Y353819D01*
G01X896874Y352244D02*
Y353819D01*
G01X898198D02*
Y352244D01*
G01X898567D02*
Y353819D01*
G01X900645D02*
Y352244D01*
G01X901015D02*
Y353819D01*
G01X902338D02*
Y352244D01*
G01X902362Y353819D02*
Y352244D01*
G01X902397D02*
Y353819D01*
G01X897441Y354606D02*
G03Y351457I0J-1574D01*
G01X901772D02*
G03Y354606I0J1574D01*
G01X877953Y346004D02*
X931890D01*
G01X903771Y340595D02*
X902328D01*
G01X903771Y344602D02*
X902331D01*
G01X900900D02*
X899441D01*
G01X898010D02*
X896618D01*
G01X931890Y344823D02*
X905512D01*
G01X896618Y344602D02*
Y341673D01*
G01X898010Y344602D02*
Y342077D01*
G01X899441D02*
Y344602D01*
G01X900900D02*
Y342077D01*
G01X901575Y344035D02*
Y340256D01*
G01X902328Y341152D02*
Y340595D01*
G01X902331Y342077D02*
Y344602D01*
G01X903771D02*
Y340595D01*
G01X892658Y345118D02*
X892555Y344749D01*
X892458Y344419D01*
X892378Y344157D01*
X892326Y343991D01*
X892308Y343937D01*
G01X894411Y341809D02*
G03Y343493I-2236J842D01*
G01X891596Y341514D02*
G03X892117Y340949I1351J723D01*
G01X892116Y344391D02*
G03X891596Y343826I832J-1287D01*
G01X892117Y340948D02*
G03X895163Y340949I1522J2362D01*
G01Y344393D02*
G03X892116Y344392I-1523J-2362D01*
G01X891596Y343826D02*
G03Y341514I2163J-1156D01*
G01X895684D02*
G03X895683Y343828I-2163J1156D01*
G01X892939Y343493D02*
G03Y341809I2236J-842D01*
G01X895163Y340949D02*
G03X895684Y341514I-830J1288D01*
G01X895683Y343828D02*
G03X895162Y344393I-1351J-723D01*
G01X896618Y341673D02*
G03X896912Y341002I913J0D01*
G01X892938Y341809D02*
G03X894411I737J277D01*
G01Y343493D02*
G03X892938I-737J-277D01*
G01X899547Y341146D02*
G03X902328Y341152I1388J1207D01*
G01X896912Y341002D02*
G03X899547Y341146I1248J1351D01*
G01X898010Y342077D02*
G03X899441I715J0D01*
G01X900900D02*
G03X902331I716J0D01*
G01X890819Y338848D02*
X889358D01*
G01X901575Y340256D02*
X877953D01*
G01X884013Y340595D02*
X882396D01*
G01X881101D02*
X879719D01*
G01X887211Y342177D02*
X885786D01*
G01X887213Y343003D02*
X884213D01*
G01X885847Y343446D02*
X884343D01*
G01X888400Y343937D02*
X892308D01*
G01X901575Y344035D02*
X877953D01*
G01X890819Y344602D02*
X889358D01*
G01X884187D02*
X882779D01*
G01X881243D02*
X879693D01*
G01X892658Y345118D02*
X888050D01*
G01X882744Y342455D02*
X884013Y340595D01*
G01X881791Y341581D02*
X882396Y340595D01*
G01X879693Y344602D02*
X881014Y342446D01*
G01X881243Y344602D02*
X881988Y343324D01*
G01X888400Y343937D02*
X888382Y343993D01*
X888330Y344158D01*
X888251Y344417D01*
X888155Y344744D01*
X888050Y345118D01*
G01X889358Y344602D02*
Y338848D01*
G01X890819Y344602D02*
Y338848D01*
G01X882779Y344602D02*
X881988Y343324D01*
G01X884187Y344602D02*
X882744Y342455D01*
G01X881791Y341581D02*
X881101Y340595D01*
G01X881014Y342446D02*
X879719Y340595D01*
G01X886772Y344802D02*
G03X885186Y344515I-263J-3073D01*
G01X885786Y342177D02*
G03X887211I713J-82D01*
G01X888594Y341769D02*
G03X888767Y342429I-4020J1406D01*
G01D02*
G03Y342926I-3524J249D01*
G01X884213Y343003D02*
G03X884552Y341560I3015J-53D01*
G01X888767Y342924D02*
G03X888506Y343787I-2971J-428D01*
G01X885786Y340587D02*
G03X887429Y340630I757J2475D01*
G01X888507Y343785D02*
G03X886768Y344802I-1807J-1094D01*
G01X887429Y340630D02*
G03X888593Y341769I-730J1910D01*
G01X884552Y341560D02*
G03X885786Y340586I1735J930D01*
G01X885186Y344515D02*
G03X884343Y343446I704J-1422D01*
G01X887211Y343003D02*
G03X886438Y343811I-791J17D01*
G01D02*
G03X885847Y343446I-9J-646D01*
G01X892520Y341220D02*
G03I-2166J0D01*
G01X903139Y606929D02*
X903487Y607014D01*
G01X901484Y607185D02*
X901832Y607270D01*
G01X896815Y586102D02*
X902397D01*
G01X897441Y586890D02*
X901772D01*
G01X907795Y589587D02*
X891417D01*
G01X905512Y593524D02*
X931890D01*
G01X894943Y593563D02*
X898856D01*
G01X900775D02*
X901661D01*
G01X898856Y594301D02*
X895977D01*
G01X895239Y597770D02*
X896050D01*
G01X900037Y598730D02*
X902989D01*
G01X903875Y599469D02*
X900037D01*
G01X899213Y602992D02*
X893113D01*
G01Y603051D02*
X899213D01*
G01X898110Y604626D02*
X907480D01*
G01X899213Y605217D02*
X929921D01*
G01X927953Y605610D02*
X909449D01*
G01X907795Y605807D02*
X901260D01*
G01X898110Y606398D02*
X907480D01*
G01X901135Y607185D02*
X901484D01*
G01X901397Y607697D02*
X901222D01*
G01X895669Y607854D02*
X894685D01*
G01X895669Y608051D02*
X894685D01*
G01X895669Y608445D02*
X894685D01*
G01X902965Y609573D02*
X903226D01*
G01X903313Y610085D02*
X902878D01*
G01X895669Y610413D02*
X894685D01*
G01X901484Y610768D02*
X900787D01*
G01X895669Y610807D02*
X894685D01*
G01X895669Y611004D02*
X894685D01*
G01X904272Y611280D02*
X900874D01*
G01X900177Y611791D02*
X904272D01*
G01X895669Y612854D02*
X894685D01*
G01X895669Y613051D02*
X894685D01*
G01X895669Y613445D02*
X894685D01*
G01X895669Y615413D02*
X894685D01*
G01X895669Y615807D02*
X894685D01*
G01X895669Y616004D02*
X894685D01*
G01X895669Y617854D02*
X894685D01*
G01X895669Y618051D02*
X894685D01*
G01X895669Y618445D02*
X894685D01*
G01X895669Y620413D02*
X894685D01*
G01X895669Y620807D02*
X894685D01*
G01X895669Y621004D02*
X894685D01*
G01X927953Y622224D02*
X901260D01*
G01X895669Y622854D02*
X894685D01*
G01X895669Y623051D02*
X894685D01*
G01X895669Y623445D02*
X894685D01*
G01X927953Y624587D02*
X901260D01*
G01X896949Y598730D02*
X897296Y598661D01*
G01X900787Y607270D02*
X901135Y607185D01*
G01X901222Y607697D02*
X900961Y607782D01*
G01X903662Y609915D02*
X903313Y610085D01*
G01X892118Y598665D02*
X892400Y598487D01*
X892588Y598222D01*
X892655Y597920D01*
X892590Y597620D01*
X892405Y597353D01*
X892119Y597172D01*
X891769Y597106D01*
G01X897296Y598661D02*
X897576Y598480D01*
G01X903226Y609573D02*
X903487Y609403D01*
G01X892192Y596364D02*
X892552Y596128D01*
X892791Y595778D01*
X892876Y595374D01*
X892794Y594972D01*
X892557Y594620D01*
X892194Y594380D01*
X891769Y594295D01*
G01X900787Y610768D02*
X900177Y611280D01*
G01X900874D02*
X901484Y610768D01*
G01X900438Y607611D02*
X900787Y607270D01*
G01X904010Y609573D02*
X903662Y609915D01*
G01X897575Y598481D02*
X897758Y598216D01*
X897822Y597917D01*
X897757Y597620D01*
G01X900961Y607782D02*
X900787Y608038D01*
G01X903487Y609403D02*
X903662Y609147D01*
G01X892857Y603445D02*
X893113Y603051D01*
G01X900264Y607953D02*
X900438Y607611D01*
G01X904184Y609232D02*
X904010Y609573D01*
G01X900787Y608038D02*
X900700Y608294D01*
G01X900177D02*
X900264Y607953D01*
G01X903662Y609147D02*
X903749Y608806D01*
G01X904272D02*
X904184Y609232D01*
G01X891522Y623976D02*
Y623189D01*
G01Y620827D02*
Y620039D01*
G01Y617677D02*
Y616890D01*
G01Y614528D02*
Y613740D01*
G01Y611378D02*
Y610591D01*
G01X892474Y600689D02*
Y603445D01*
G01X893113Y603051D02*
Y602992D01*
G01X893506Y623976D02*
Y623189D01*
G01Y620827D02*
Y620039D01*
G01Y617677D02*
Y616890D01*
G01Y614528D02*
Y613740D01*
G01Y611378D02*
Y610591D01*
G01X893640Y606024D02*
Y737638D01*
G01X893701Y625217D02*
Y623642D01*
G01Y620217D02*
Y618642D01*
G01Y615217D02*
Y613642D01*
G01Y610217D02*
Y608642D01*
G01X894094Y603445D02*
Y740413D01*
G01X894685Y626004D02*
Y622854D01*
G01Y621004D02*
Y617854D01*
G01Y616004D02*
Y612854D01*
G01Y611004D02*
Y607854D01*
G01X894943Y594006D02*
Y593563D01*
G01X895239Y597918D02*
Y597770D01*
G01X895669Y626004D02*
Y622854D01*
G01Y621004D02*
Y617854D01*
G01Y616004D02*
Y612854D01*
G01Y611004D02*
Y607854D01*
G01Y602992D02*
Y600689D01*
G01X896050Y597770D02*
Y597918D01*
G01X896654Y625217D02*
Y623642D01*
G01Y620217D02*
Y618642D01*
G01Y615217D02*
Y613642D01*
G01Y610217D02*
Y608642D01*
G01X896868Y610591D02*
Y611378D01*
G01Y616890D02*
Y617677D01*
G01Y613740D02*
Y614528D01*
G01Y620039D02*
Y620827D01*
G01Y623189D02*
Y623976D01*
G01X897244Y610591D02*
Y611378D01*
G01Y616890D02*
Y617677D01*
G01Y613740D02*
Y614528D01*
G01Y620039D02*
Y620827D01*
G01Y623189D02*
Y623976D01*
G01X897270Y610591D02*
Y611378D01*
G01Y616890D02*
Y617677D01*
G01Y613740D02*
Y614528D01*
G01Y620039D02*
Y620827D01*
G01Y623189D02*
Y623976D01*
G01X897657Y608465D02*
Y610433D01*
G01X898110Y603445D02*
Y740413D01*
G01X898856Y593563D02*
Y594301D01*
G01X899213Y740866D02*
Y602992D01*
G01X900037Y599469D02*
Y598730D01*
G01X900177Y608720D02*
Y608294D01*
G01Y611280D02*
Y611791D01*
G01X900700Y608294D02*
Y608806D01*
G01X901135Y609317D02*
Y609829D01*
G01X901260Y605807D02*
Y738051D01*
G01X901575Y602500D02*
Y600059D01*
G01Y598091D02*
Y594311D01*
G01X901919Y608806D02*
Y608294D01*
G01X902442D02*
Y608806D01*
G01X903139Y607441D02*
Y606929D01*
G01X903228Y639823D02*
Y624587D01*
G01Y622224D02*
Y605807D01*
G01X903749Y608806D02*
Y608123D01*
G01X903875Y598804D02*
Y599469D01*
G01X904272Y611791D02*
Y611280D01*
G01Y608123D02*
Y608806D01*
G01X905512Y592343D02*
Y600689D01*
G01X907480Y606398D02*
Y604626D01*
G01X909449Y738248D02*
Y605610D01*
G01X895239Y597918D02*
X895325Y598395D01*
X895573Y598837D01*
X895961Y599189D01*
X896468Y599409D01*
X897045Y599465D01*
X897609Y599343D01*
X898085Y599061D01*
X898424Y598656D01*
X898604Y598199D01*
X898619Y597719D01*
X898462Y597248D01*
X898147Y596831D01*
G01X900264Y609147D02*
X900177Y608720D01*
G01X902006Y609232D02*
X901919Y608806D01*
G01X904184Y607697D02*
X904272Y608123D01*
G01X896118Y598223D02*
X896050Y597918D01*
G01X902442Y608806D02*
X902529Y609147D01*
G01X902355Y607953D02*
X902442Y608294D01*
G01X903749Y608123D02*
X903662Y607782D01*
G01X900700Y608806D02*
X900787Y609061D01*
G01X901919Y608294D02*
X901832Y608038D01*
G01X902181Y609573D02*
X902006Y609232D01*
G01X902181Y607611D02*
X902355Y607953D01*
G01X903923Y607270D02*
X904184Y607697D01*
G01X902529Y609147D02*
X902704Y609403D01*
G01X901832Y608038D02*
X901658Y607782D01*
G01X897576Y597356D02*
X897759Y597622D01*
X897822Y597919D01*
X897757Y598217D01*
G01X896307Y598490D02*
X896118Y598222D01*
G01X900526Y609488D02*
X900264Y609147D01*
G01X900874Y609744D02*
X900526Y609488D01*
G01X892192Y594379D02*
X892552Y594615D01*
X892791Y594965D01*
X892876Y595369D01*
X892794Y595771D01*
X892557Y596123D01*
X892194Y596363D01*
X891769Y596448D01*
G01X902704Y609403D02*
X902965Y609573D01*
G01X892118Y597171D02*
X892400Y597349D01*
X892588Y597614D01*
X892655Y597916D01*
X892590Y598216D01*
X892405Y598483D01*
X892119Y598665D01*
X891769Y598730D01*
G01X896307Y598490D02*
X896594Y598668D01*
X896948Y598730D01*
G01X903487Y607014D02*
X903923Y607270D01*
G01X900961Y609232D02*
X901135Y609317D01*
G01X902878Y610085D02*
X902529Y609915D01*
G01X901135Y609829D02*
X900874Y609744D01*
G01X901658Y607782D02*
X901397Y607697D01*
G01X903400Y607526D02*
X903139Y607441D01*
G01X898147Y596831D02*
X898484Y597293D01*
X898630Y597812D01*
X898570Y598330D01*
X898319Y598813D01*
X897882Y599208D01*
X897309Y599431D01*
X896674Y599450D01*
X896090Y599264D01*
X895635Y598911D01*
X895342Y598439D01*
X895239Y597918D01*
G01X900787Y609061D02*
X900961Y609232D01*
G01X902529Y609915D02*
X902181Y609573D01*
G01X901832Y607270D02*
X902181Y607611D01*
G01X903662Y607782D02*
X903400Y607526D01*
G01X897576Y597356D02*
X896013Y595829D01*
G01X898147Y596831D02*
X896519Y595285D01*
G01D02*
G03X895977Y594301I1276J-1344D01*
G01X898110Y613248D02*
G03X897717Y613642I-394J0D01*
G01Y615217D02*
G03X898110Y615610I0J393D01*
G01Y623248D02*
G03X897717Y623642I-394J0D01*
G01Y625217D02*
G03X898110Y625610I0J393D01*
G01Y618248D02*
G03X897717Y618642I-394J0D01*
G01Y620217D02*
G03X898110Y620610I0J393D01*
G01Y608248D02*
G03X897717Y608642I-394J0D01*
G01Y610217D02*
G03X898110Y610610I0J393D01*
G01X903875Y598804D02*
G03X901661Y593563I7143J-6105D01*
G01X902989Y598730D02*
G03X900775Y593563I6938J-6031D01*
G01X896013Y595829D02*
G03X894943Y594006I2809J-2874D01*
G01X931890Y592343D02*
X877953D01*
G01X880327Y593563D02*
X881213D01*
G01X901575Y594311D02*
X877953D01*
G01X901575Y598091D02*
X877953D01*
G01X879589Y598730D02*
X882542D01*
G01X883428Y599469D02*
X879589D01*
G01X877953Y600059D02*
X901575D01*
G01X927953Y600689D02*
X877953D01*
G01X901575Y602500D02*
X877953D01*
G01X878745Y603445D02*
X899213D01*
G01X898110Y606024D02*
X877953D01*
G01X894094Y608012D02*
X885110D01*
G01X889587Y608465D02*
X897657D01*
G01X890551Y608642D02*
X897717D01*
G01X890551Y610217D02*
X897717D01*
G01X897657Y610433D02*
X889587D01*
G01X879724Y610591D02*
X887057D01*
G01X887204D02*
X899213D01*
G01Y611378D02*
X887204D01*
G01X887057D02*
X879724D01*
G01X890551Y613642D02*
X897717D01*
G01X879724Y613740D02*
X887057D01*
G01X887204D02*
X899213D01*
G01Y614528D02*
X887204D01*
G01X887057D02*
X879724D01*
G01X890551Y615217D02*
X897717D01*
G01X879724Y616890D02*
X887057D01*
G01X887204D02*
X899213D01*
G01Y617677D02*
X887204D01*
G01X887057D02*
X879724D01*
G01X890551Y618642D02*
X897717D01*
G01X879724Y620039D02*
X887057D01*
G01X887204D02*
X899213D01*
G01X890551Y620217D02*
X897717D01*
G01X899213Y620827D02*
X887204D01*
G01X887057D02*
X879724D01*
G01Y623189D02*
X887057D01*
G01X887204D02*
X899213D01*
G01X890551Y623642D02*
X897717D01*
G01X899213Y623976D02*
X887204D01*
G01X887057D02*
X879724D01*
G01X890551Y625217D02*
X897717D01*
G01X886253Y597171D02*
X885970Y597349D01*
X885783Y597614D01*
X885716Y597916D01*
X885780Y598216D01*
X885966Y598483D01*
X886251Y598665D01*
X886602Y598730D01*
G01X886951Y598665D02*
X887233Y598487D01*
X887420Y598222D01*
X887487Y597920D01*
X887423Y597620D01*
X887237Y597353D01*
X886952Y597172D01*
X886602Y597106D01*
G01X891420Y597171D02*
X891137Y597349D01*
X890950Y597614D01*
X890883Y597916D01*
X890948Y598216D01*
X891133Y598483D01*
X891419Y598665D01*
X891769Y598730D01*
G01X886179Y594379D02*
X885819Y594615D01*
X885580Y594965D01*
X885494Y595369D01*
X885577Y595771D01*
X885813Y596123D01*
X886177Y596363D01*
X886602Y596448D01*
G01X887025Y596364D02*
X887385Y596128D01*
X887624Y595778D01*
X887709Y595374D01*
X887626Y594972D01*
X887390Y594620D01*
X887026Y594380D01*
X886602Y594295D01*
G01X891346Y594379D02*
X890986Y594615D01*
X890747Y594965D01*
X890662Y595369D01*
X890744Y595771D01*
X890981Y596123D01*
X891344Y596363D01*
X891769Y596448D01*
G01X887800Y596819D02*
X888251Y596379D01*
X888521Y595843D01*
X888592Y595273D01*
X888450Y594709D01*
X888103Y594184D01*
X887576Y593791D01*
X886933Y593588D01*
X886254Y593590D01*
X885614Y593798D01*
X885091Y594194D01*
X884750Y594718D01*
X884611Y595279D01*
X884683Y595847D01*
X884954Y596381D01*
G01X892967Y596819D02*
X893419Y596379D01*
X893689Y595843D01*
X893759Y595273D01*
X893617Y594709D01*
X893270Y594184D01*
X892743Y593791D01*
X892100Y593588D01*
X891421Y593590D01*
X890781Y593798D01*
X890258Y594194D01*
X889917Y594718D01*
X889779Y595279D01*
X889850Y595847D01*
X890121Y596381D01*
G01X885404Y596819D02*
X885081Y597239D01*
X884919Y597722D01*
X884941Y598227D01*
X885143Y598704D01*
X885510Y599107D01*
X886017Y599374D01*
X886607Y599469D01*
X887197Y599371D01*
X887699Y599102D01*
X888063Y598698D01*
X888265Y598220D01*
X888284Y597716D01*
X888120Y597235D01*
X887800Y596819D01*
G01X890571D02*
X890249Y597239D01*
X890086Y597722D01*
X890108Y598227D01*
X890311Y598704D01*
X890678Y599107D01*
X891184Y599374D01*
X891775Y599469D01*
X892364Y599371D01*
X892867Y599102D01*
X893231Y598698D01*
X893432Y598220D01*
X893451Y597716D01*
X893287Y597235D01*
X892967Y596819D01*
G01X877953Y606024D02*
Y592343D01*
G01X878270Y606024D02*
Y600689D01*
G01X878745Y606024D02*
Y603445D01*
G01X879589Y599469D02*
Y598730D01*
G01X879724Y610591D02*
Y611378D01*
G01Y616890D02*
Y617677D01*
G01Y613740D02*
Y614528D01*
G01Y620039D02*
Y620827D01*
G01Y623189D02*
Y623976D01*
G01X881498Y610591D02*
Y611378D01*
G01Y616890D02*
Y617677D01*
G01Y613740D02*
Y614528D01*
G01Y620039D02*
Y620827D01*
G01Y623189D02*
Y623976D01*
G01X881686D02*
Y623189D01*
G01Y620827D02*
Y620039D01*
G01Y617677D02*
Y616890D01*
G01Y614528D02*
Y613740D01*
G01Y611378D02*
Y610591D01*
G01X883428Y598804D02*
Y599469D01*
G01X884523Y623976D02*
Y623189D01*
G01Y620827D02*
Y620039D01*
G01Y617677D02*
Y616890D01*
G01Y614528D02*
Y613740D01*
G01Y611378D02*
Y610591D01*
G01X884600Y600689D02*
Y603445D01*
G01X885110Y740413D02*
Y603445D01*
G01X885464Y610591D02*
Y611378D01*
G01Y616890D02*
Y617677D01*
G01Y613740D02*
Y614528D01*
G01Y620039D02*
Y620827D01*
G01Y623189D02*
Y623976D01*
G01X887057Y610591D02*
Y611378D01*
G01Y616890D02*
Y617677D01*
G01Y613740D02*
Y614528D01*
G01Y620039D02*
Y620827D01*
G01Y623189D02*
Y623976D01*
G01X887204Y610591D02*
Y611378D01*
G01Y616890D02*
Y617677D01*
G01Y613740D02*
Y614528D01*
G01Y620039D02*
Y620827D01*
G01Y623189D02*
Y623976D01*
G01X888142Y626339D02*
Y623976D01*
G01Y623189D02*
Y620827D01*
G01Y620039D02*
Y617677D01*
G01Y616890D02*
Y614528D01*
G01Y610591D02*
Y608012D01*
G01Y613740D02*
Y611378D01*
G01X889587Y610433D02*
Y608465D01*
G01X889870Y610591D02*
Y611378D01*
G01Y616890D02*
Y617677D01*
G01Y613740D02*
Y614528D01*
G01Y620039D02*
Y620827D01*
G01Y623189D02*
Y623976D01*
G01X890551Y625217D02*
Y623642D01*
G01Y620217D02*
Y618642D01*
G01Y615217D02*
Y613642D01*
G01Y610217D02*
Y608642D01*
G01X887800Y596819D02*
X888122Y597239D01*
X888285Y597722D01*
X888263Y598227D01*
X888060Y598704D01*
X887693Y599107D01*
X887187Y599374D01*
X886596Y599469D01*
X886007Y599371D01*
X885504Y599102D01*
X885140Y598698D01*
X884939Y598220D01*
X884920Y597716D01*
X885083Y597235D01*
X885404Y596819D01*
G01X886179Y596364D02*
X885819Y596128D01*
X885580Y595778D01*
X885494Y595374D01*
X885577Y594972D01*
X885813Y594620D01*
X886177Y594380D01*
X886602Y594295D01*
G01X887025Y594379D02*
X887385Y594615D01*
X887624Y594965D01*
X887709Y595369D01*
X887626Y595771D01*
X887390Y596123D01*
X887026Y596363D01*
X886602Y596448D01*
G01X891346Y596364D02*
X890986Y596128D01*
X890747Y595778D01*
X890662Y595374D01*
X890744Y594972D01*
X890981Y594620D01*
X891344Y594380D01*
X891769Y594295D01*
G01X886253Y598665D02*
X885970Y598487D01*
X885783Y598222D01*
X885716Y597920D01*
X885780Y597620D01*
X885966Y597353D01*
X886251Y597172D01*
X886602Y597106D01*
G01X886951Y597171D02*
X887233Y597349D01*
X887420Y597614D01*
X887487Y597916D01*
X887423Y598216D01*
X887237Y598483D01*
X886952Y598665D01*
X886602Y598730D01*
G01X891420Y598665D02*
X891137Y598487D01*
X890950Y598222D01*
X890883Y597920D01*
X890948Y597620D01*
X891133Y597353D01*
X891419Y597172D01*
X891769Y597106D01*
G01X892967Y596819D02*
X893289Y597239D01*
X893452Y597722D01*
X893430Y598227D01*
X893227Y598704D01*
X892861Y599107D01*
X892354Y599374D01*
X891763Y599469D01*
X891174Y599371D01*
X890672Y599102D01*
X890307Y598698D01*
X890106Y598220D01*
X890087Y597716D01*
X890251Y597235D01*
X890571Y596819D01*
G01X885404D02*
X884952Y596379D01*
X884682Y595843D01*
X884612Y595273D01*
X884754Y594709D01*
X885100Y594184D01*
X885628Y593791D01*
X886270Y593588D01*
X886950Y593590D01*
X887590Y593798D01*
X888112Y594194D01*
X888454Y594718D01*
X888592Y595279D01*
X888520Y595847D01*
X888250Y596381D01*
G01X890571Y596819D02*
X890120Y596379D01*
X889850Y595843D01*
X889779Y595273D01*
X889921Y594709D01*
X890268Y594184D01*
X890795Y593791D01*
X891437Y593588D01*
X892117Y593590D01*
X892757Y593798D01*
X893280Y594194D01*
X893621Y594718D01*
X893759Y595279D01*
X893687Y595847D01*
X893417Y596381D01*
G01X883428Y598804D02*
G03X881213Y593563I7141J-6107D01*
G01X882542Y598730D02*
G03X880327Y593563I6937J-6032D01*
G01X894882Y597126D02*
G03I-4528J0D01*
G01X893858D02*
G03I-3504J0D01*
G01X893701D02*
G03I-3347J0D01*
G01X892520D02*
G03I-2166J0D01*
G01X895669Y625413D02*
X894685D01*
G01X895669Y625807D02*
X894685D01*
G01X895669Y626004D02*
X894685D01*
G01X895669Y627854D02*
X894685D01*
G01X895669Y628051D02*
X894685D01*
G01X895669Y628445D02*
X894685D01*
G01X891522Y630276D02*
Y629488D01*
G01Y627126D02*
Y626339D01*
G01X893506Y630276D02*
Y629488D01*
G01Y627126D02*
Y626339D01*
G01X893701Y630217D02*
Y628642D01*
G01X894685Y631004D02*
Y627854D01*
G01X895669Y631004D02*
Y627854D01*
G01X896654Y630217D02*
Y628642D01*
G01X896868Y626339D02*
Y627126D01*
G01Y629488D02*
Y630276D01*
G01X897244Y626339D02*
Y627126D01*
G01Y629488D02*
Y630276D01*
G01X897270Y626339D02*
Y627126D01*
G01Y629488D02*
Y630276D01*
G01X898110Y628248D02*
G03X897717Y628642I-394J0D01*
G01X879724Y626339D02*
X887057D01*
G01X887204D02*
X899213D01*
G01Y627126D02*
X887204D01*
G01X887057D02*
X879724D01*
G01X890551Y628642D02*
X897717D01*
G01X879724Y629488D02*
X887057D01*
G01X887204D02*
X899213D01*
G01X879724Y626339D02*
Y627126D01*
G01Y629488D02*
Y630276D01*
G01X881498Y626339D02*
Y627126D01*
G01Y629488D02*
Y630276D01*
G01X881686D02*
Y629488D01*
G01Y627126D02*
Y626339D01*
G01X884523Y630276D02*
Y629488D01*
G01Y627126D02*
Y626339D01*
G01X885464D02*
Y627126D01*
G01Y629488D02*
Y630276D01*
G01X887057Y626339D02*
Y627126D01*
G01Y629488D02*
Y630276D01*
G01X887204Y626339D02*
Y627126D01*
G01Y629488D02*
Y630276D01*
G01X888142Y629488D02*
Y627126D01*
G01X889870Y626339D02*
Y627126D01*
G01Y629488D02*
Y630276D01*
G01X890551Y630217D02*
Y628642D01*
G01X896457Y564764D02*
X902756D01*
G01X898031Y565059D02*
X894882D01*
G01X901181D02*
X904331D01*
G01X896561Y565535D02*
X896467D01*
G01Y566283D02*
X896561D01*
G01X904331Y567028D02*
X901181D01*
G01X894882D02*
X898031D01*
G01X904331Y567618D02*
X901181D01*
G01X894882D02*
X898031D01*
G01Y569587D02*
X894882D01*
G01X901181D02*
X904331D01*
G01X902756Y569882D02*
X896457D01*
G01X907795Y579409D02*
X891417D01*
G01X901772Y583740D02*
X897441D01*
G01X902397Y584528D02*
X896815D01*
G01X891417Y592343D02*
Y579409D01*
G01X894882Y569587D02*
Y567618D01*
G01Y565059D02*
Y567028D01*
G01X896374Y566044D02*
Y566172D01*
G01X896457Y569882D02*
Y569291D01*
G01Y568110D02*
Y566535D01*
G01Y565354D02*
Y564764D01*
G01X896467Y565535D02*
Y566156D01*
G01X896561Y566283D02*
Y565535D01*
G01X896815Y586102D02*
Y584528D01*
G01X896850D02*
Y586102D01*
G01X896874Y584528D02*
Y586102D01*
G01X897441Y564764D02*
Y569882D01*
G01X897638D02*
Y564764D01*
G01X898031Y567028D02*
Y565059D01*
G01Y567618D02*
Y569587D01*
G01X898198Y586102D02*
Y584528D01*
G01X898567D02*
Y586102D01*
G01X900645D02*
Y584528D01*
G01X901015D02*
Y586102D01*
G01X901181Y567028D02*
Y565059D01*
G01Y567618D02*
Y569587D01*
G01X901575Y569882D02*
Y564764D01*
G01X901772D02*
Y569882D01*
G01X902338Y586102D02*
Y584528D01*
G01X902362Y586102D02*
Y584528D01*
G01X902397D02*
Y586102D01*
G01X902756Y564764D02*
Y565354D01*
G01Y569291D02*
Y569882D01*
G01Y566535D02*
Y568110D01*
G01X904331Y569587D02*
Y567618D01*
G01Y565059D02*
Y567028D01*
G01X907795Y579409D02*
Y605807D01*
G01X896374Y566172D02*
X896467Y566283D01*
G01Y566156D02*
X896374Y566044D01*
G01X897441Y586890D02*
G03Y583740I0J-1575D01*
G01X896457Y568110D02*
G03Y569291I0J590D01*
G01Y565354D02*
G03Y566535I0J590D01*
G01X901772Y583740D02*
G03Y586890I0J1575D01*
G01X902756Y569291D02*
G03Y568110I0J-591D01*
G01Y566535D02*
G03Y565354I0J-591D01*
G01X897203Y646220D02*
X896219D01*
G01X897203Y646417D02*
X896219D01*
G01X898110Y646614D02*
X892085D01*
G01X898110Y647795D02*
X892085D01*
G01X897203Y647992D02*
X896219D01*
G01X897203Y648189D02*
X896219D01*
G01X897203Y649370D02*
X896219D01*
G01X897203Y649567D02*
X896219D01*
G01X898110Y649764D02*
X892085D01*
G01X898110Y650945D02*
X892085D01*
G01X897203Y651142D02*
X896219D01*
G01X897203Y651339D02*
X896219D01*
G01X897203Y652520D02*
X896219D01*
G01X897203Y652717D02*
X896219D01*
G01X898110Y652913D02*
X892085D01*
G01X898110Y654094D02*
X892085D01*
G01X897203Y654291D02*
X896219D01*
G01X897203Y654488D02*
X896219D01*
G01X897203Y655669D02*
X896219D01*
G01X897203Y655866D02*
X896219D01*
G01X898110Y656063D02*
X892085D01*
G01X898110Y657244D02*
X892085D01*
G01X897203Y657441D02*
X896219D01*
G01X897203Y657638D02*
X896219D01*
G01X897203Y658819D02*
X896219D01*
G01X897203Y659016D02*
X896219D01*
G01X898110Y659213D02*
X892085D01*
G01X898110Y660394D02*
X892085D01*
G01X897203Y660591D02*
X896219D01*
G01X897203Y660787D02*
X896219D01*
G01Y661083D02*
X894094D01*
G01X899213Y661575D02*
X891678D01*
G01X923452Y661673D02*
X901260D01*
G01X899213Y661693D02*
X898110D01*
G01X909449D02*
X927953D01*
G01X895669Y662854D02*
X894685D01*
G01X895669Y663051D02*
X894685D01*
G01X895669Y663445D02*
X894685D01*
G01X927953Y664035D02*
X901260D01*
G01X895669Y665413D02*
X894685D01*
G01X895669Y665807D02*
X894685D01*
G01X895669Y666004D02*
X894685D01*
G01X895669Y667854D02*
X894685D01*
G01X895669Y668051D02*
X894685D01*
G01X928910Y668130D02*
X909449D01*
G01X895669Y668445D02*
X894685D01*
G01X895669Y670413D02*
X894685D01*
G01X895669Y670807D02*
X894685D01*
G01X895669Y671004D02*
X894685D01*
G01X895669Y672854D02*
X894685D01*
G01X895669Y673051D02*
X894685D01*
G01X895669Y673445D02*
X894685D01*
G01X895669Y675413D02*
X894685D01*
G01X895669Y675807D02*
X894685D01*
G01X895669Y676004D02*
X894685D01*
G01X899213Y677224D02*
X898110D01*
G01X897638Y677854D02*
X896654D01*
G01X897638Y678051D02*
X896654D01*
G01X897638Y678445D02*
X896654D01*
G01X898110Y678642D02*
X892520D01*
G01X898110Y680217D02*
X892520D01*
G01X927953Y680374D02*
X901260D01*
G01X897638Y680413D02*
X896654D01*
G01X897638Y680807D02*
X896654D01*
G01X897638Y681004D02*
X896654D01*
G01X898110Y681634D02*
X899213D01*
G01X927953Y682736D02*
X901260D01*
G01X895669Y682854D02*
X894685D01*
G01X895669Y683051D02*
X894685D01*
G01X895669Y683445D02*
X894685D01*
G01X895669Y685413D02*
X894685D01*
G01X895669Y685807D02*
X894685D01*
G01X895669Y686004D02*
X894685D01*
G01X895669Y687854D02*
X894685D01*
G01X895669Y688051D02*
X894685D01*
G01X895669Y688445D02*
X894685D01*
G01X895669Y690413D02*
X894685D01*
G01X895669Y690807D02*
X894685D01*
G01X895669Y691004D02*
X894685D01*
G01X895669Y692854D02*
X894685D01*
G01X895669Y693051D02*
X894685D01*
G01X895669Y693445D02*
X894685D01*
G01X895669Y695413D02*
X894685D01*
G01X895669Y695807D02*
X894685D01*
G01X895669Y696004D02*
X894685D01*
G01X895669Y697854D02*
X894685D01*
G01X895669Y698051D02*
X894685D01*
G01X895669Y698445D02*
X894685D01*
G01X927953Y699272D02*
X901260D01*
G01X895669Y700413D02*
X894685D01*
G01X895669Y700807D02*
X894685D01*
G01X895669Y701004D02*
X894685D01*
G01X927953Y701634D02*
X901260D01*
G01X891522Y702717D02*
Y701929D01*
G01Y699567D02*
Y698780D01*
G01Y696417D02*
Y695630D01*
G01Y693268D02*
Y692480D01*
G01Y690118D02*
Y689331D01*
G01Y686969D02*
Y686181D01*
G01Y683819D02*
Y683031D01*
G01Y680669D02*
Y679882D01*
G01Y677520D02*
Y676732D01*
G01Y674370D02*
Y673583D01*
G01Y671220D02*
Y670433D01*
G01Y668071D02*
Y667283D01*
G01Y664921D02*
Y664134D01*
G01Y661772D02*
Y660984D01*
G01Y658622D02*
Y657835D01*
G01Y655472D02*
Y654685D01*
G01Y652323D02*
Y651535D01*
G01Y649173D02*
Y648386D01*
G01X891678Y648307D02*
Y655551D01*
G01Y657756D02*
Y661575D01*
G01X892085Y657244D02*
Y656063D01*
G01Y660394D02*
Y659213D01*
G01Y654094D02*
Y652913D01*
G01Y650945D02*
Y649764D01*
G01Y647795D02*
Y646614D01*
G01X892104Y657756D02*
Y655551D01*
G01Y648307D02*
Y646102D01*
G01X892520Y680217D02*
Y678642D01*
G01X893506Y702717D02*
Y701929D01*
G01Y699567D02*
Y698780D01*
G01Y696417D02*
Y695630D01*
G01Y693268D02*
Y692480D01*
G01Y690118D02*
Y689331D01*
G01Y686969D02*
Y686181D01*
G01Y683819D02*
Y683031D01*
G01Y680669D02*
Y679882D01*
G01Y677520D02*
Y676732D01*
G01Y674370D02*
Y673583D01*
G01Y671220D02*
Y670433D01*
G01Y668071D02*
Y667283D01*
G01Y664921D02*
Y664134D01*
G01Y661772D02*
Y660984D01*
G01Y658622D02*
Y657835D01*
G01Y655472D02*
Y654685D01*
G01Y652323D02*
Y651535D01*
G01Y649173D02*
Y648386D01*
G01X893701Y700217D02*
Y698642D01*
G01Y695217D02*
Y693642D01*
G01Y690217D02*
Y688642D01*
G01Y685217D02*
Y683642D01*
G01Y675217D02*
Y673642D01*
G01Y670217D02*
Y668642D01*
G01Y665217D02*
Y663642D01*
G01X894685Y701004D02*
Y697854D01*
G01Y696004D02*
Y692854D01*
G01Y691004D02*
Y687854D01*
G01Y686004D02*
Y682854D01*
G01Y676004D02*
Y672854D01*
G01Y671004D02*
Y667854D01*
G01Y666004D02*
Y662854D01*
G01X895235Y657244D02*
Y656063D01*
G01Y660394D02*
Y659213D01*
G01Y654094D02*
Y652913D01*
G01Y650945D02*
Y649764D01*
G01Y647795D02*
Y646614D01*
G01X895669Y701004D02*
Y697854D01*
G01Y696004D02*
Y692854D01*
G01Y691004D02*
Y687854D01*
G01Y686004D02*
Y682854D01*
G01Y680217D02*
Y678642D01*
G01Y676004D02*
Y672854D01*
G01Y671004D02*
Y667854D01*
G01Y666004D02*
Y662854D01*
G01X896654Y700217D02*
Y698642D01*
G01Y695217D02*
Y693642D01*
G01Y690217D02*
Y688642D01*
G01Y685217D02*
Y683642D01*
G01Y681004D02*
Y677854D01*
G01Y675217D02*
Y673642D01*
G01Y670217D02*
Y668642D01*
G01Y665217D02*
Y663642D01*
G01X896868Y648386D02*
Y649173D01*
G01Y654685D02*
Y655472D01*
G01Y651535D02*
Y652323D01*
G01Y657835D02*
Y658622D01*
G01Y664134D02*
Y664921D01*
G01Y660984D02*
Y661772D01*
G01Y667283D02*
Y668071D01*
G01Y673583D02*
Y674370D01*
G01Y670433D02*
Y671220D01*
G01Y676732D02*
Y677520D01*
G01Y683031D02*
Y683819D01*
G01Y679882D02*
Y680669D01*
G01Y686181D02*
Y686969D01*
G01Y692480D02*
Y693268D01*
G01Y689331D02*
Y690118D01*
G01Y695630D02*
Y696417D01*
G01Y701929D02*
Y702717D01*
G01Y698780D02*
Y699567D01*
G01X897203Y660984D02*
Y658622D01*
G01Y657835D02*
Y655472D01*
G01Y654685D02*
Y652323D01*
G01Y651535D02*
Y649173D01*
G01Y648386D02*
Y646024D01*
G01X897244Y648386D02*
Y649173D01*
G01Y654685D02*
Y655472D01*
G01Y651535D02*
Y652323D01*
G01Y657835D02*
Y658622D01*
G01Y664134D02*
Y664921D01*
G01Y660984D02*
Y661772D01*
G01Y667283D02*
Y668071D01*
G01Y673583D02*
Y674370D01*
G01Y670433D02*
Y671220D01*
G01Y676732D02*
Y677520D01*
G01Y683031D02*
Y683819D01*
G01Y679882D02*
Y680669D01*
G01Y686181D02*
Y686969D01*
G01Y692480D02*
Y693268D01*
G01Y689331D02*
Y690118D01*
G01Y695630D02*
Y696417D01*
G01Y701929D02*
Y702717D01*
G01Y698780D02*
Y699567D01*
G01X897270Y648386D02*
Y649173D01*
G01Y654685D02*
Y655472D01*
G01Y651535D02*
Y652323D01*
G01Y657835D02*
Y658622D01*
G01Y664134D02*
Y664921D01*
G01Y660984D02*
Y661772D01*
G01Y667283D02*
Y668071D01*
G01Y673583D02*
Y674370D01*
G01Y670433D02*
Y671220D01*
G01Y676732D02*
Y677520D01*
G01Y683031D02*
Y683819D01*
G01Y679882D02*
Y680669D01*
G01Y686181D02*
Y686969D01*
G01Y692480D02*
Y693268D01*
G01Y689331D02*
Y690118D01*
G01Y695630D02*
Y696417D01*
G01Y701929D02*
Y702717D01*
G01Y698780D02*
Y699567D01*
G01X897638Y681004D02*
Y677854D01*
G01X903228Y664035D02*
Y680374D01*
G01Y682736D02*
Y699272D01*
G01Y701634D02*
Y718169D01*
G01X898110Y663248D02*
G03X897717Y663642I-394J0D01*
G01Y665217D02*
G03X898110Y665610I0J393D01*
G01Y688248D02*
G03X897717Y688642I-394J0D01*
G01Y690217D02*
G03X898110Y690610I0J393D01*
G01Y698248D02*
G03X897717Y698642I-394J0D01*
G01Y700217D02*
G03X898110Y700610I0J393D01*
G01Y693248D02*
G03X897717Y693642I-394J0D01*
G01Y695217D02*
G03X898110Y695610I0J393D01*
G01Y673248D02*
G03X897717Y673642I-394J0D01*
G01Y675217D02*
G03X898110Y675610I0J393D01*
G01Y668248D02*
G03X897717Y668642I-394J0D01*
G01Y670217D02*
G03X898110Y670610I0J393D01*
G01Y683248D02*
G03X897717Y683642I-394J0D01*
G01Y685217D02*
G03X898110Y685610I0J393D01*
G01X895669Y630413D02*
X894685D01*
G01X895669Y630807D02*
X894685D01*
G01X895669Y631004D02*
X894685D01*
G01X895669Y632854D02*
X894685D01*
G01X895669Y633051D02*
X894685D01*
G01X895669Y633445D02*
X894685D01*
G01X895669Y635413D02*
X894685D01*
G01X895669Y635807D02*
X894685D01*
G01X928910Y635827D02*
X909449D01*
G01X895669Y636004D02*
X894685D01*
G01X895669Y637854D02*
X894685D01*
G01X895669Y638051D02*
X894685D01*
G01X895669Y638445D02*
X894685D01*
G01X927953Y639823D02*
X901260D01*
G01X895669Y640413D02*
X894685D01*
G01X895669Y640807D02*
X894685D01*
G01X895669Y641004D02*
X894685D01*
G01X927953Y642165D02*
X909449D01*
G01X899213D02*
X898110D01*
G01X923452Y642185D02*
X901260D01*
G01X891678Y642283D02*
X899213D01*
G01X896219Y642776D02*
X894094D01*
G01X897203Y643071D02*
X896219D01*
G01X897203Y643268D02*
X896219D01*
G01X898110Y643465D02*
X892085D01*
G01X898110Y644646D02*
X892085D01*
G01X897203Y644843D02*
X896219D01*
G01X897203Y645039D02*
X896219D01*
G01X891522Y646024D02*
Y645236D01*
G01Y642874D02*
Y642087D01*
G01Y639724D02*
Y638937D01*
G01Y636575D02*
Y635787D01*
G01Y633425D02*
Y632638D01*
G01X891678Y642283D02*
Y646102D01*
G01X892085Y644646D02*
Y643465D01*
G01X892156Y642283D02*
Y661575D01*
G01X893506Y646024D02*
Y645236D01*
G01Y642874D02*
Y642087D01*
G01Y639724D02*
Y638937D01*
G01Y636575D02*
Y635787D01*
G01Y633425D02*
Y632638D01*
G01X893701Y640217D02*
Y638642D01*
G01Y635217D02*
Y633642D01*
G01X894685Y641004D02*
Y637854D01*
G01Y636004D02*
Y632854D01*
G01X895235Y644646D02*
Y643465D01*
G01X895512Y642283D02*
Y661575D01*
G01X895669Y641004D02*
Y637854D01*
G01Y636004D02*
Y632854D01*
G01X896219Y642776D02*
Y661083D01*
G01X896429Y661575D02*
Y642283D01*
G01X896654Y640217D02*
Y638642D01*
G01Y635217D02*
Y633642D01*
G01X896868Y635787D02*
Y636575D01*
G01Y632638D02*
Y633425D01*
G01Y638937D02*
Y639724D01*
G01Y645236D02*
Y646024D01*
G01Y642087D02*
Y642874D01*
G01X896929Y661575D02*
Y642283D01*
G01X897203Y645236D02*
Y642874D01*
G01X897244Y635787D02*
Y636575D01*
G01Y632638D02*
Y633425D01*
G01Y638937D02*
Y639724D01*
G01Y645236D02*
Y646024D01*
G01Y642087D02*
Y642874D01*
G01X897270Y635787D02*
Y636575D01*
G01Y632638D02*
Y633425D01*
G01Y638937D02*
Y639724D01*
G01Y645236D02*
Y646024D01*
G01Y642087D02*
Y642874D01*
G01X897717Y642283D02*
Y661575D01*
G01X898031D02*
Y642283D01*
G01X903228Y661673D02*
Y642185D01*
G01X897717Y630217D02*
G03X898110Y630610I0J393D01*
G01Y633248D02*
G03X897717Y633642I-394J0D01*
G01Y635217D02*
G03X898110Y635610I0J393D01*
G01Y638248D02*
G03X897717Y638642I-394J0D01*
G01Y640217D02*
G03X898110Y640610I0J393D01*
G01X899213Y646024D02*
X887204D01*
G01X887057D02*
X879724D01*
G01X890221Y646102D02*
X892104D01*
G01Y648307D02*
X890221D01*
G01X879724Y648386D02*
X887057D01*
G01X887204D02*
X899213D01*
G01Y649173D02*
X887204D01*
G01X887057D02*
X879724D01*
G01Y651535D02*
X887057D01*
G01X887204D02*
X899213D01*
G01Y652323D02*
X887204D01*
G01X887057D02*
X879724D01*
G01Y654685D02*
X887057D01*
G01X887204D02*
X899213D01*
G01Y655472D02*
X887204D01*
G01X887057D02*
X879724D01*
G01X890221Y655551D02*
X892104D01*
G01Y657756D02*
X890221D01*
G01X879724Y657835D02*
X887057D01*
G01X887204D02*
X899213D01*
G01Y658622D02*
X887204D01*
G01X887057D02*
X879724D01*
G01Y660984D02*
X887057D01*
G01X887204D02*
X899213D01*
G01Y661772D02*
X887204D01*
G01X887057D02*
X879724D01*
G01X890551Y663642D02*
X897717D01*
G01X879724Y664134D02*
X887057D01*
G01X887204D02*
X899213D01*
G01Y664921D02*
X887204D01*
G01X887057D02*
X879724D01*
G01X890551Y665217D02*
X897717D01*
G01X879724Y667283D02*
X887057D01*
G01X887204D02*
X899213D01*
G01Y668071D02*
X887204D01*
G01X887057D02*
X879724D01*
G01X890551Y668642D02*
X897717D01*
G01X890551Y670217D02*
X897717D01*
G01X879724Y670433D02*
X887057D01*
G01X887204D02*
X899213D01*
G01Y671220D02*
X887204D01*
G01X887057D02*
X879724D01*
G01Y673583D02*
X887057D01*
G01X887204D02*
X899213D01*
G01X890551Y673642D02*
X897717D01*
G01X899213Y674370D02*
X887204D01*
G01X887057D02*
X879724D01*
G01X890551Y675217D02*
X897717D01*
G01X879724Y676732D02*
X887057D01*
G01X887204D02*
X899213D01*
G01Y677520D02*
X887204D01*
G01X887057D02*
X879724D01*
G01Y679882D02*
X887057D01*
G01X887204D02*
X899213D01*
G01Y680669D02*
X887204D01*
G01X887057D02*
X879724D01*
G01Y683031D02*
X887057D01*
G01X887204D02*
X899213D01*
G01X890551Y683642D02*
X897717D01*
G01X899213Y683819D02*
X887204D01*
G01X887057D02*
X879724D01*
G01X890551Y685217D02*
X897717D01*
G01X879724Y686181D02*
X887057D01*
G01X887204D02*
X899213D01*
G01Y686969D02*
X887204D01*
G01X887057D02*
X879724D01*
G01X890551Y688642D02*
X897717D01*
G01X879724Y689331D02*
X887057D01*
G01X887204D02*
X899213D01*
G01Y690118D02*
X887204D01*
G01X887057D02*
X879724D01*
G01X890551Y690217D02*
X897717D01*
G01X879724Y692480D02*
X887057D01*
G01X887204D02*
X899213D01*
G01Y693268D02*
X887204D01*
G01X887057D02*
X879724D01*
G01X890551Y693642D02*
X897717D01*
G01X890551Y695217D02*
X897717D01*
G01X879724Y695630D02*
X887057D01*
G01X887204D02*
X899213D01*
G01Y696417D02*
X887204D01*
G01X887057D02*
X879724D01*
G01X890551Y698642D02*
X897717D01*
G01X879724Y698780D02*
X887057D01*
G01X887204D02*
X899213D01*
G01Y699567D02*
X887204D01*
G01X887057D02*
X879724D01*
G01X890551Y700217D02*
X897717D01*
G01X879724Y701929D02*
X887057D01*
G01X887204D02*
X899213D01*
G01X879724Y648386D02*
Y649173D01*
G01Y654685D02*
Y655472D01*
G01Y651535D02*
Y652323D01*
G01Y657835D02*
Y658622D01*
G01Y664134D02*
Y664921D01*
G01Y660984D02*
Y661772D01*
G01Y667283D02*
Y668071D01*
G01Y673583D02*
Y674370D01*
G01Y670433D02*
Y671220D01*
G01Y676732D02*
Y677520D01*
G01Y683031D02*
Y683819D01*
G01Y679882D02*
Y680669D01*
G01Y686181D02*
Y686969D01*
G01Y692480D02*
Y693268D01*
G01Y689331D02*
Y690118D01*
G01Y695630D02*
Y696417D01*
G01Y701929D02*
Y702717D01*
G01Y698780D02*
Y699567D01*
G01X881498Y648386D02*
Y649173D01*
G01Y654685D02*
Y655472D01*
G01Y651535D02*
Y652323D01*
G01Y657835D02*
Y658622D01*
G01Y664134D02*
Y664921D01*
G01Y660984D02*
Y661772D01*
G01Y667283D02*
Y668071D01*
G01Y673583D02*
Y674370D01*
G01Y670433D02*
Y671220D01*
G01Y676732D02*
Y677520D01*
G01Y683031D02*
Y683819D01*
G01Y679882D02*
Y680669D01*
G01Y686181D02*
Y686969D01*
G01Y692480D02*
Y693268D01*
G01Y689331D02*
Y690118D01*
G01Y695630D02*
Y696417D01*
G01Y701929D02*
Y702717D01*
G01Y698780D02*
Y699567D01*
G01X881686Y702717D02*
Y701929D01*
G01Y699567D02*
Y698780D01*
G01Y696417D02*
Y695630D01*
G01Y693268D02*
Y692480D01*
G01Y690118D02*
Y689331D01*
G01Y686969D02*
Y686181D01*
G01Y683819D02*
Y683031D01*
G01Y680669D02*
Y679882D01*
G01Y677520D02*
Y676732D01*
G01Y674370D02*
Y673583D01*
G01Y671220D02*
Y670433D01*
G01Y668071D02*
Y667283D01*
G01Y664921D02*
Y664134D01*
G01Y661772D02*
Y660984D01*
G01Y658622D02*
Y657835D01*
G01Y655472D02*
Y654685D01*
G01Y652323D02*
Y651535D01*
G01Y649173D02*
Y648386D01*
G01X884523Y702717D02*
Y701929D01*
G01Y699567D02*
Y698780D01*
G01Y696417D02*
Y695630D01*
G01Y693268D02*
Y692480D01*
G01Y690118D02*
Y689331D01*
G01Y686969D02*
Y686181D01*
G01Y683819D02*
Y683031D01*
G01Y680669D02*
Y679882D01*
G01Y677520D02*
Y676732D01*
G01Y674370D02*
Y673583D01*
G01Y671220D02*
Y670433D01*
G01Y668071D02*
Y667283D01*
G01Y664921D02*
Y664134D01*
G01Y661772D02*
Y660984D01*
G01Y658622D02*
Y657835D01*
G01Y655472D02*
Y654685D01*
G01Y652323D02*
Y651535D01*
G01Y649173D02*
Y648386D01*
G01X885464D02*
Y649173D01*
G01Y654685D02*
Y655472D01*
G01Y651535D02*
Y652323D01*
G01Y657835D02*
Y658622D01*
G01Y664134D02*
Y664921D01*
G01Y660984D02*
Y661772D01*
G01Y667283D02*
Y668071D01*
G01Y673583D02*
Y674370D01*
G01Y670433D02*
Y671220D01*
G01Y676732D02*
Y677520D01*
G01Y683031D02*
Y683819D01*
G01Y679882D02*
Y680669D01*
G01Y686181D02*
Y686969D01*
G01Y692480D02*
Y693268D01*
G01Y689331D02*
Y690118D01*
G01Y695630D02*
Y696417D01*
G01Y701929D02*
Y702717D01*
G01Y698780D02*
Y699567D01*
G01X887057Y648386D02*
Y649173D01*
G01Y654685D02*
Y655472D01*
G01Y651535D02*
Y652323D01*
G01Y657835D02*
Y658622D01*
G01Y664134D02*
Y664921D01*
G01Y660984D02*
Y661772D01*
G01Y667283D02*
Y668071D01*
G01Y673583D02*
Y674370D01*
G01Y670433D02*
Y671220D01*
G01Y676732D02*
Y677520D01*
G01Y683031D02*
Y683819D01*
G01Y679882D02*
Y680669D01*
G01Y686181D02*
Y686969D01*
G01Y692480D02*
Y693268D01*
G01Y689331D02*
Y690118D01*
G01Y695630D02*
Y696417D01*
G01Y701929D02*
Y702717D01*
G01Y698780D02*
Y699567D01*
G01X887204Y648386D02*
Y649173D01*
G01Y654685D02*
Y655472D01*
G01Y651535D02*
Y652323D01*
G01Y657835D02*
Y658622D01*
G01Y664134D02*
Y664921D01*
G01Y660984D02*
Y661772D01*
G01Y667283D02*
Y668071D01*
G01Y673583D02*
Y674370D01*
G01Y670433D02*
Y671220D01*
G01Y676732D02*
Y677520D01*
G01Y683031D02*
Y683819D01*
G01Y679882D02*
Y680669D01*
G01Y686181D02*
Y686969D01*
G01Y692480D02*
Y693268D01*
G01Y689331D02*
Y690118D01*
G01Y695630D02*
Y696417D01*
G01Y701929D02*
Y702717D01*
G01Y698780D02*
Y699567D01*
G01X888142Y701929D02*
Y699567D01*
G01Y698780D02*
Y696417D01*
G01Y695630D02*
Y693268D01*
G01Y692480D02*
Y690118D01*
G01Y689331D02*
Y686969D01*
G01Y686181D02*
Y683819D01*
G01Y683031D02*
Y680669D01*
G01Y679882D02*
Y677520D01*
G01Y676732D02*
Y674370D01*
G01Y673583D02*
Y671220D01*
G01Y670433D02*
Y668071D01*
G01Y667283D02*
Y664921D01*
G01Y664134D02*
Y661772D01*
G01Y660984D02*
Y658622D01*
G01Y657835D02*
Y655472D01*
G01Y654685D02*
Y652323D01*
G01Y651535D02*
Y649173D01*
G01Y648386D02*
Y646024D01*
G01X889870Y648386D02*
Y649173D01*
G01Y654685D02*
Y655472D01*
G01Y651535D02*
Y652323D01*
G01Y657835D02*
Y658622D01*
G01Y664134D02*
Y664921D01*
G01Y660984D02*
Y661772D01*
G01Y667283D02*
Y668071D01*
G01Y673583D02*
Y674370D01*
G01Y670433D02*
Y671220D01*
G01Y676732D02*
Y677520D01*
G01Y683031D02*
Y683819D01*
G01Y679882D02*
Y680669D01*
G01Y686181D02*
Y686969D01*
G01Y692480D02*
Y693268D01*
G01Y689331D02*
Y690118D01*
G01Y695630D02*
Y696417D01*
G01Y701929D02*
Y702717D01*
G01Y698780D02*
Y699567D01*
G01X890221Y646102D02*
Y648307D01*
G01Y655551D02*
Y657756D01*
G01X890551Y700217D02*
Y698642D01*
G01Y695217D02*
Y693642D01*
G01Y690217D02*
Y688642D01*
G01Y685217D02*
Y683642D01*
G01Y675217D02*
Y673642D01*
G01Y670217D02*
Y668642D01*
G01Y665217D02*
Y663642D01*
G01Y630217D02*
X897717D01*
G01X899213Y630276D02*
X887204D01*
G01X887057D02*
X879724D01*
G01Y632638D02*
X887057D01*
G01X887204D02*
X899213D01*
G01Y633425D02*
X887204D01*
G01X887057D02*
X879724D01*
G01X890551Y633642D02*
X897717D01*
G01X890551Y635217D02*
X897717D01*
G01X879724Y635787D02*
X887057D01*
G01X887204D02*
X899213D01*
G01Y636575D02*
X887204D01*
G01X887057D02*
X879724D01*
G01X890551Y638642D02*
X897717D01*
G01X879724Y638937D02*
X887057D01*
G01X887204D02*
X899213D01*
G01Y639724D02*
X887204D01*
G01X887057D02*
X879724D01*
G01X890551Y640217D02*
X897717D01*
G01X879724Y642087D02*
X887057D01*
G01X887204D02*
X899213D01*
G01Y642874D02*
X887204D01*
G01X887057D02*
X879724D01*
G01Y645236D02*
X887057D01*
G01X887204D02*
X899213D01*
G01X879724Y635787D02*
Y636575D01*
G01Y632638D02*
Y633425D01*
G01Y638937D02*
Y639724D01*
G01Y645236D02*
Y646024D01*
G01Y642087D02*
Y642874D01*
G01X881498Y635787D02*
Y636575D01*
G01Y632638D02*
Y633425D01*
G01Y638937D02*
Y639724D01*
G01Y645236D02*
Y646024D01*
G01Y642087D02*
Y642874D01*
G01X881686Y646024D02*
Y645236D01*
G01Y642874D02*
Y642087D01*
G01Y639724D02*
Y638937D01*
G01Y636575D02*
Y635787D01*
G01Y633425D02*
Y632638D01*
G01X884523Y646024D02*
Y645236D01*
G01Y642874D02*
Y642087D01*
G01Y639724D02*
Y638937D01*
G01Y636575D02*
Y635787D01*
G01Y633425D02*
Y632638D01*
G01X885464Y635787D02*
Y636575D01*
G01Y632638D02*
Y633425D01*
G01Y638937D02*
Y639724D01*
G01Y645236D02*
Y646024D01*
G01Y642087D02*
Y642874D01*
G01X887057Y635787D02*
Y636575D01*
G01Y632638D02*
Y633425D01*
G01Y638937D02*
Y639724D01*
G01Y645236D02*
Y646024D01*
G01Y642087D02*
Y642874D01*
G01X887204Y635787D02*
Y636575D01*
G01Y632638D02*
Y633425D01*
G01Y638937D02*
Y639724D01*
G01Y645236D02*
Y646024D01*
G01Y642087D02*
Y642874D01*
G01X888142Y645236D02*
Y642874D01*
G01Y642087D02*
Y639724D01*
G01Y638937D02*
Y636575D01*
G01Y635787D02*
Y633425D01*
G01Y632638D02*
Y630276D01*
G01X889870Y635787D02*
Y636575D01*
G01Y632638D02*
Y633425D01*
G01Y638937D02*
Y639724D01*
G01Y645236D02*
Y646024D01*
G01Y642087D02*
Y642874D01*
G01X890551Y640217D02*
Y638642D01*
G01Y635217D02*
Y633642D01*
G01X895669Y705413D02*
X894685D01*
G01X895669Y705807D02*
X894685D01*
G01X895669Y706004D02*
X894685D01*
G01X895669Y707854D02*
X894685D01*
G01X895669Y708051D02*
X894685D01*
G01X895669Y708445D02*
X894685D01*
G01X895669Y710413D02*
X894685D01*
G01X895669Y710807D02*
X894685D01*
G01X895669Y711004D02*
X894685D01*
G01X895669Y712854D02*
X894685D01*
G01X895669Y713051D02*
X894685D01*
G01X895669Y713445D02*
X894685D01*
G01X895669Y715413D02*
X894685D01*
G01X895669Y715807D02*
X894685D01*
G01X895669Y716004D02*
X894685D01*
G01X899213Y717224D02*
X898110D01*
G01X897638Y717854D02*
X896654D01*
G01X897638Y718051D02*
X896654D01*
G01X927953Y718169D02*
X901260D01*
G01X897638Y718445D02*
X896654D01*
G01X898110Y718642D02*
X892520D01*
G01X898110Y720217D02*
X892520D01*
G01X897638Y720413D02*
X896654D01*
G01X927953Y720531D02*
X901260D01*
G01X897638Y720807D02*
X896654D01*
G01X897638Y721004D02*
X896654D01*
G01X899213Y721634D02*
X898110D01*
G01X895669Y722854D02*
X894685D01*
G01X895669Y723051D02*
X894685D01*
G01X895669Y723445D02*
X894685D01*
G01X895669Y725413D02*
X894685D01*
G01X895669Y725807D02*
X894685D01*
G01X895669Y726004D02*
X894685D01*
G01X895669Y727854D02*
X894685D01*
G01X895669Y728051D02*
X894685D01*
G01X895669Y728445D02*
X894685D01*
G01X895669Y730413D02*
X894685D01*
G01X895669Y730807D02*
X894685D01*
G01X895669Y731004D02*
X894685D01*
G01X895669Y732854D02*
X894685D01*
G01X895669Y733051D02*
X894685D01*
G01X895669Y733445D02*
X894685D01*
G01X895669Y735413D02*
X894685D01*
G01X895669Y735807D02*
X894685D01*
G01X895669Y736004D02*
X894685D01*
G01X898110Y737461D02*
X907480D01*
G01X907795Y738051D02*
X901260D01*
G01X927953Y738248D02*
X909449D01*
G01X929921Y738642D02*
X899213D01*
G01X898110Y739232D02*
X907480D01*
G01X893113Y740807D02*
X899213D01*
G01X893113Y740866D02*
X899213D01*
G01X892308Y744016D02*
X892326Y743960D01*
X892379Y743794D01*
X892457Y743536D01*
X892553Y743208D01*
X892658Y742835D01*
G01X891522Y734213D02*
Y733425D01*
G01Y731063D02*
Y730276D01*
G01Y727913D02*
Y727126D01*
G01Y724764D02*
Y723976D01*
G01Y721614D02*
Y720827D01*
G01Y718465D02*
Y717677D01*
G01Y715315D02*
Y714528D01*
G01Y712165D02*
Y711378D01*
G01Y709016D02*
Y708228D01*
G01X892474Y740413D02*
Y743169D01*
G01X892520Y720217D02*
Y718642D01*
G01X893113Y740866D02*
Y740807D01*
G01X893506Y734213D02*
Y733425D01*
G01Y731063D02*
Y730276D01*
G01Y727913D02*
Y727126D01*
G01Y724764D02*
Y723976D01*
G01Y721614D02*
Y720827D01*
G01Y718465D02*
Y717677D01*
G01Y715315D02*
Y714528D01*
G01Y712165D02*
Y711378D01*
G01Y709016D02*
Y708228D01*
G01X893701Y735217D02*
Y733642D01*
G01Y730217D02*
Y728642D01*
G01Y725217D02*
Y723642D01*
G01Y715217D02*
Y713642D01*
G01Y710217D02*
Y708642D01*
G01X894685Y736004D02*
Y732854D01*
G01Y731004D02*
Y727854D01*
G01Y726004D02*
Y722854D01*
G01Y716004D02*
Y712854D01*
G01Y711004D02*
Y707854D01*
G01X895669Y743169D02*
Y740866D01*
G01Y736004D02*
Y732854D01*
G01Y731004D02*
Y727854D01*
G01Y726004D02*
Y722854D01*
G01Y720217D02*
Y718642D01*
G01Y716004D02*
Y712854D01*
G01Y711004D02*
Y707854D01*
G01X896654Y735217D02*
Y733642D01*
G01Y730217D02*
Y728642D01*
G01Y725217D02*
Y723642D01*
G01Y721004D02*
Y717854D01*
G01Y715217D02*
Y713642D01*
G01Y710217D02*
Y708642D01*
G01X896868Y711378D02*
Y712165D01*
G01Y708228D02*
Y709016D01*
G01Y714528D02*
Y715315D01*
G01Y720827D02*
Y721614D01*
G01Y717677D02*
Y718465D01*
G01Y723976D02*
Y724764D01*
G01Y730276D02*
Y731063D01*
G01Y727126D02*
Y727913D01*
G01Y733425D02*
Y734213D01*
G01X897244Y711378D02*
Y712165D01*
G01Y708228D02*
Y709016D01*
G01Y714528D02*
Y715315D01*
G01Y720827D02*
Y721614D01*
G01Y717677D02*
Y718465D01*
G01Y723976D02*
Y724764D01*
G01Y730276D02*
Y731063D01*
G01Y727126D02*
Y727913D01*
G01Y733425D02*
Y734213D01*
G01X897270Y711378D02*
Y712165D01*
G01Y708228D02*
Y709016D01*
G01Y714528D02*
Y715315D01*
G01Y720827D02*
Y721614D01*
G01Y717677D02*
Y718465D01*
G01Y723976D02*
Y724764D01*
G01Y730276D02*
Y731063D01*
G01Y727126D02*
Y727913D01*
G01Y733425D02*
Y734213D01*
G01X897638Y721004D02*
Y717854D01*
G01X901575Y743799D02*
Y741398D01*
G01X903228Y720531D02*
Y738051D01*
G01X905512Y751516D02*
Y743169D01*
G01X907480Y739232D02*
Y737461D01*
G01X907795Y738051D02*
Y764449D01*
G01X893113Y740807D02*
X892857Y740413D01*
G01X892658Y742835D02*
G03Y750630I-2304J3897D01*
G01X892308Y744016D02*
G03Y749449I-1954J2717D01*
G01X898110Y708248D02*
G03X897717Y708642I-394J0D01*
G01Y710217D02*
G03X898110Y710610I0J393D01*
G01Y728248D02*
G03X897717Y728642I-394J0D01*
G01Y730217D02*
G03X898110Y730610I0J393D01*
G01Y723248D02*
G03X897717Y723642I-394J0D01*
G01Y725217D02*
G03X898110Y725610I0J393D01*
G01Y733248D02*
G03X897717Y733642I-394J0D01*
G01Y735217D02*
G03X898110Y735610I0J393D01*
G01Y713248D02*
G03X897717Y713642I-394J0D01*
G01Y715217D02*
G03X898110Y715610I0J393D01*
G01X899213Y705866D02*
X887204D01*
G01X887057D02*
X879724D01*
G01Y708228D02*
X887057D01*
G01X887204D02*
X899213D01*
G01X890551Y708642D02*
X897717D01*
G01X899213Y709016D02*
X887204D01*
G01X887057D02*
X879724D01*
G01X890551Y710217D02*
X897717D01*
G01X879724Y711378D02*
X887057D01*
G01X887204D02*
X899213D01*
G01Y712165D02*
X887204D01*
G01X887057D02*
X879724D01*
G01X890551Y713642D02*
X897717D01*
G01X879724Y714528D02*
X887057D01*
G01X887204D02*
X899213D01*
G01X890551Y715217D02*
X897717D01*
G01X899213Y715315D02*
X887204D01*
G01X887057D02*
X879724D01*
G01Y717677D02*
X887057D01*
G01X887204D02*
X899213D01*
G01Y718465D02*
X887204D01*
G01X887057D02*
X879724D01*
G01Y720827D02*
X887057D01*
G01X887204D02*
X899213D01*
G01Y721614D02*
X887204D01*
G01X887057D02*
X879724D01*
G01X890551Y723642D02*
X897717D01*
G01X879724Y723976D02*
X887057D01*
G01X887204D02*
X899213D01*
G01Y724764D02*
X887204D01*
G01X887057D02*
X879724D01*
G01X890551Y725217D02*
X897717D01*
G01X879724Y727126D02*
X887057D01*
G01X887204D02*
X899213D01*
G01Y727913D02*
X887204D01*
G01X887057D02*
X879724D01*
G01X890551Y728642D02*
X897717D01*
G01X890551Y730217D02*
X897717D01*
G01X879724Y730276D02*
X887057D01*
G01X887204D02*
X899213D01*
G01Y731063D02*
X887204D01*
G01X887057D02*
X879724D01*
G01Y733425D02*
X887057D01*
G01X887204D02*
X899213D01*
G01X890551Y733642D02*
X897717D01*
G01X899213Y734213D02*
X887204D01*
G01X887057D02*
X879724D01*
G01X890551Y735217D02*
X897717D01*
G01X894094Y735886D02*
X885110D01*
G01X877953Y737638D02*
X898110D01*
G01X878745Y740413D02*
X899213D01*
G01X877953Y741398D02*
X901575D01*
G01X888050Y742835D02*
X892658D01*
G01X927953Y743169D02*
X877953D01*
G01X901575Y743799D02*
X877953D01*
G01X892308Y744016D02*
X888400D01*
G01X890819Y744360D02*
X889358D01*
G01X877953Y751516D02*
Y737638D01*
G01X878270Y743169D02*
Y737638D01*
G01X878745Y740413D02*
Y737638D01*
G01X879724Y711378D02*
Y712165D01*
G01Y708228D02*
Y709016D01*
G01Y714528D02*
Y715315D01*
G01Y720827D02*
Y721614D01*
G01Y717677D02*
Y718465D01*
G01Y723976D02*
Y724764D01*
G01Y730276D02*
Y731063D01*
G01Y727126D02*
Y727913D01*
G01Y733425D02*
Y734213D01*
G01X881498Y711378D02*
Y712165D01*
G01Y708228D02*
Y709016D01*
G01Y714528D02*
Y715315D01*
G01Y720827D02*
Y721614D01*
G01Y717677D02*
Y718465D01*
G01Y723976D02*
Y724764D01*
G01Y730276D02*
Y731063D01*
G01Y727126D02*
Y727913D01*
G01Y733425D02*
Y734213D01*
G01X881686D02*
Y733425D01*
G01Y731063D02*
Y730276D01*
G01Y727913D02*
Y727126D01*
G01Y724764D02*
Y723976D01*
G01Y721614D02*
Y720827D01*
G01Y718465D02*
Y717677D01*
G01Y715315D02*
Y714528D01*
G01Y712165D02*
Y711378D01*
G01Y709016D02*
Y708228D01*
G01X884523Y734213D02*
Y733425D01*
G01Y731063D02*
Y730276D01*
G01Y727913D02*
Y727126D01*
G01Y724764D02*
Y723976D01*
G01Y721614D02*
Y720827D01*
G01Y718465D02*
Y717677D01*
G01Y715315D02*
Y714528D01*
G01Y712165D02*
Y711378D01*
G01Y709016D02*
Y708228D01*
G01X884600Y740413D02*
Y743169D01*
G01X885464Y711378D02*
Y712165D01*
G01Y708228D02*
Y709016D01*
G01Y714528D02*
Y715315D01*
G01Y720827D02*
Y721614D01*
G01Y717677D02*
Y718465D01*
G01Y723976D02*
Y724764D01*
G01Y730276D02*
Y731063D01*
G01Y727126D02*
Y727913D01*
G01Y733425D02*
Y734213D01*
G01X887057Y711378D02*
Y712165D01*
G01Y708228D02*
Y709016D01*
G01Y714528D02*
Y715315D01*
G01Y720827D02*
Y721614D01*
G01Y717677D02*
Y718465D01*
G01Y723976D02*
Y724764D01*
G01Y730276D02*
Y731063D01*
G01Y727126D02*
Y727913D01*
G01Y733425D02*
Y734213D01*
G01X887204Y711378D02*
Y712165D01*
G01Y708228D02*
Y709016D01*
G01Y714528D02*
Y715315D01*
G01Y720827D02*
Y721614D01*
G01Y717677D02*
Y718465D01*
G01Y723976D02*
Y724764D01*
G01Y730276D02*
Y731063D01*
G01Y727126D02*
Y727913D01*
G01Y733425D02*
Y734213D01*
G01X888142Y735886D02*
Y734213D01*
G01Y733425D02*
Y731063D01*
G01Y730276D02*
Y727913D01*
G01Y727126D02*
Y724764D01*
G01Y723976D02*
Y721614D01*
G01Y720827D02*
Y718465D01*
G01Y717677D02*
Y715315D01*
G01Y714528D02*
Y712165D01*
G01Y711378D02*
Y709016D01*
G01Y708228D02*
Y705866D01*
G01X889358Y750114D02*
Y744360D01*
G01X889870Y711378D02*
Y712165D01*
G01Y708228D02*
Y709016D01*
G01Y714528D02*
Y715315D01*
G01Y720827D02*
Y721614D01*
G01Y717677D02*
Y718465D01*
G01Y723976D02*
Y724764D01*
G01Y730276D02*
Y731063D01*
G01Y727126D02*
Y727913D01*
G01Y733425D02*
Y734213D01*
G01X890551Y735217D02*
Y733642D01*
G01Y730217D02*
Y728642D01*
G01Y725217D02*
Y723642D01*
G01Y715217D02*
Y713642D01*
G01Y710217D02*
Y708642D01*
G01X890819Y750114D02*
Y744360D01*
G01X888400Y744016D02*
X888382Y743960D01*
X888330Y743794D01*
X888251Y743536D01*
X888155Y743209D01*
X888050Y742835D01*
G01Y750630D02*
G03Y742835I2304J-3898D01*
G01X893858Y746732D02*
G03I-3504J0D01*
G01X888400Y749449D02*
G03Y744016I1954J-2717D01*
G01X892520Y746732D02*
G03I-2166J0D01*
G01X903771Y746107D02*
X902328D01*
G01X903771Y750114D02*
X902331D01*
G01X900900D02*
X899441D01*
G01X898010D02*
X896618D01*
G01X931890Y750335D02*
X905512D01*
G01X907795Y754272D02*
X891417D01*
G01X901772Y756969D02*
X897441D01*
G01X902397Y757756D02*
X896815D01*
G01Y759331D02*
X902397D01*
G01X897441Y760118D02*
X901772D01*
G01X907795Y764449D02*
X891417D01*
G01D02*
Y751516D01*
G01X896618Y750114D02*
Y747185D01*
G01X896815Y759331D02*
Y757756D01*
G01X896850D02*
Y759331D01*
G01X896874Y757756D02*
Y759331D01*
G01X898010Y750114D02*
Y747589D01*
G01X898198Y759331D02*
Y757756D01*
G01X898567D02*
Y759331D01*
G01X899441Y747589D02*
Y750114D01*
G01X900645Y759331D02*
Y757756D01*
G01X900900Y750114D02*
Y747589D01*
G01X901015Y757756D02*
Y759331D01*
G01X901575Y749547D02*
Y745768D01*
G01X902328Y746664D02*
Y746107D01*
G01X902331Y747589D02*
Y750114D01*
G01X902338Y759331D02*
Y757756D01*
G01X902362Y759331D02*
Y757756D01*
G01X902397D02*
Y759331D01*
G01X903771Y750114D02*
Y746107D01*
G01X892658Y750630D02*
X892555Y750261D01*
X892458Y749931D01*
X892378Y749669D01*
X892326Y749503D01*
X892308Y749449D01*
G01X892117Y746460D02*
G03X895163Y746461I1522J2362D01*
G01Y749905D02*
G03X892116Y749904I-1523J-2362D01*
G01X891596Y749338D02*
G03Y747026I2163J-1156D01*
G01X895684D02*
G03X895683Y749340I-2163J1156D01*
G01X894411Y747320D02*
G03Y749005I-2236J842D01*
G01X895163Y746461D02*
G03X895684Y747026I-830J1288D01*
G01X891596D02*
G03X892117Y746461I1351J723D01*
G01X892116Y749903D02*
G03X891596Y749338I832J-1287D01*
G01X895683Y749340D02*
G03X895162Y749905I-1351J-723D01*
G01X892938Y747320D02*
G03X894411I737J278D01*
G01Y749005D02*
G03X892938I-737J-277D01*
G01X892939D02*
G03Y747320I2236J-842D01*
G01X897441Y760118D02*
G03Y756969I0J-1574D01*
G01X896618Y747185D02*
G03X896912Y746514I913J0D01*
G01X899547Y746658D02*
G03X902328Y746664I1388J1207D01*
G01X896912Y746514D02*
G03X899547Y746658I1248J1351D01*
G01X901772Y756969D02*
G03Y760118I0J1575D01*
G01X898010Y747589D02*
G03X899441I715J0D01*
G01X900900D02*
G03X902331I716J0D01*
G01X901575Y745768D02*
X877953D01*
G01X884013Y746107D02*
X882396D01*
G01X881101D02*
X879719D01*
G01X887211Y747689D02*
X885786D01*
G01X887213Y748515D02*
X884213D01*
G01X885847Y748958D02*
X884343D01*
G01X888400Y749449D02*
X892308D01*
G01X901575Y749547D02*
X877953D01*
G01X890819Y750114D02*
X889358D01*
G01X884187D02*
X882779D01*
G01X881243D02*
X879693D01*
G01X892658Y750630D02*
X888050D01*
G01X877953Y751516D02*
X931890D01*
G01X882744Y747967D02*
X884013Y746107D01*
G01X881791Y747093D02*
X882396Y746107D01*
G01X879693Y750114D02*
X881014Y747958D01*
G01X881243Y750114D02*
X881988Y748836D01*
G01X888400Y749449D02*
X888382Y749505D01*
X888330Y749670D01*
X888251Y749929D01*
X888155Y750256D01*
X888050Y750630D01*
G01X882779Y750114D02*
X881988Y748836D01*
G01X884187Y750114D02*
X882744Y747967D01*
G01X881791Y747093D02*
X881101Y746107D01*
G01X881014Y747958D02*
X879719Y746107D01*
G01X886772Y750313D02*
G03X885186Y750027I-265J-3073D01*
G01X885786Y747689D02*
G03X887211I713J-83D01*
G01X888594Y747280D02*
G03X888767Y747941I-4021J1405D01*
G01D02*
G03Y748438I-3524J249D01*
G01X884213Y748515D02*
G03X884552Y747072I3015J-53D01*
G01X888767Y748436D02*
G03X888506Y749299I-2971J-428D01*
G01X885786Y746098D02*
G03X887429Y746142I756J2476D01*
G01X888507Y749296D02*
G03X886768Y750314I-1807J-1093D01*
G01X887429Y746142D02*
G03X888593Y747280I-730J1911D01*
G01X884552Y747072D02*
G03X885786Y746098I1735J930D01*
G01X885186Y750027D02*
G03X884343Y748958I704J-1422D01*
G01X887211Y748515D02*
G03X886438Y749323I-792J17D01*
G01D02*
G03X885847Y748958I-9J-646D01*
G01X895669Y702854D02*
X894685D01*
G01X895669Y703051D02*
X894685D01*
G01X895669Y703445D02*
X894685D01*
G01X891522Y705866D02*
Y705079D01*
G01X893506Y705866D02*
Y705079D01*
G01X893701Y705217D02*
Y703642D01*
G01X894685Y706004D02*
Y702854D01*
G01X895669Y706004D02*
Y702854D01*
G01X896654Y705217D02*
Y703642D01*
G01X896868Y705079D02*
Y705866D01*
G01X897244Y705079D02*
Y705866D01*
G01X897270Y705079D02*
Y705866D01*
G01X898110Y703248D02*
G03X897717Y703642I-394J0D01*
G01Y705217D02*
G03X898110Y705610I0J393D01*
G01X899213Y702717D02*
X887204D01*
G01X887057D02*
X879724D01*
G01X890551Y703642D02*
X897717D01*
G01X879724Y705079D02*
X887057D01*
G01X887204D02*
X899213D01*
G01X890551Y705217D02*
X897717D01*
G01X879724Y705079D02*
Y705866D01*
G01X881498Y705079D02*
Y705866D01*
G01X881686D02*
Y705079D01*
G01X884523Y705866D02*
Y705079D01*
G01X885464D02*
Y705866D01*
G01X887057Y705079D02*
Y705866D01*
G01X887204Y705079D02*
Y705866D01*
G01X888142Y705079D02*
Y702717D01*
G01X889870Y705079D02*
Y705866D01*
G01X890551Y705217D02*
Y703642D01*
G01X896457Y970276D02*
X902756D01*
G01X898031Y970571D02*
X894882D01*
G01X901181D02*
X904331D01*
G01X896561Y971047D02*
X896467D01*
G01Y971795D02*
X896561D01*
G01X904331Y972539D02*
X901181D01*
G01X894882D02*
X898031D01*
G01X904331Y973130D02*
X901181D01*
G01X894882D02*
X898031D01*
G01Y975098D02*
X894882D01*
G01X901181D02*
X904331D01*
G01X902756Y975394D02*
X896457D01*
G01X907795Y984921D02*
X891417D01*
G01X896374Y971684D02*
X896467Y971795D01*
G01Y971668D02*
X896374Y971556D01*
G01X891417Y997854D02*
Y984921D01*
G01X894882Y975098D02*
Y973130D01*
G01Y970571D02*
Y972539D01*
G01X896374Y971556D02*
Y971684D01*
G01X896457Y975394D02*
Y974803D01*
G01Y973622D02*
Y972047D01*
G01Y970866D02*
Y970276D01*
G01X896467Y971047D02*
Y971668D01*
G01X896561Y971795D02*
Y971047D01*
G01X897441Y970276D02*
Y975394D01*
G01X897638D02*
Y970276D01*
G01X898031Y972539D02*
Y970571D01*
G01Y973130D02*
Y975098D01*
G01X901181Y972539D02*
Y970571D01*
G01Y973130D02*
Y975098D01*
G01X901575Y975394D02*
Y970276D01*
G01X901772D02*
Y975394D01*
G01X902756Y970276D02*
Y970866D01*
G01Y972047D02*
Y973622D01*
G01Y974803D02*
Y975394D01*
G01X904331Y975098D02*
Y973130D01*
G01Y970571D02*
Y972539D01*
G01X907795Y984921D02*
Y1011319D01*
G01X896457Y973622D02*
G03Y974803I0J591D01*
G01Y970866D02*
G03Y972047I0J591D01*
G01X902756Y974803D02*
G03Y973622I0J-591D01*
G01Y972047D02*
G03Y970866I0J-590D01*
G01X901772Y989252D02*
X897441D01*
G01X902397Y990039D02*
X896815D01*
G01Y991614D02*
X902397D01*
G01X897441Y992402D02*
X901772D01*
G01X896815Y991614D02*
Y990039D01*
G01X896850D02*
Y991614D01*
G01X896874Y990039D02*
Y991614D01*
G01X898198D02*
Y990039D01*
G01X898567D02*
Y991614D01*
G01X900645D02*
Y990039D01*
G01X901015D02*
Y991614D01*
G01X902338D02*
Y990039D01*
G01X902362Y991614D02*
Y990039D01*
G01X902397D02*
Y991614D01*
G01X897441Y992402D02*
G03Y989252I0J-1575D01*
G01X901772D02*
G03Y992402I0J1575D01*
G01X898110Y1065906D02*
X892085D01*
G01X897203Y1066102D02*
X896219D01*
G01X903139Y1012441D02*
X903487Y1012526D01*
G01X901484Y1012697D02*
X901832Y1012782D01*
G01X899213Y1008504D02*
X893113D01*
G01Y1008563D02*
X899213D01*
G01X898110Y1010138D02*
X907480D01*
G01X899213Y1010728D02*
X929921D01*
G01X927953Y1011122D02*
X909449D01*
G01X907795Y1011319D02*
X901260D01*
G01X898110Y1011909D02*
X907480D01*
G01X901135Y1012697D02*
X901484D01*
G01X901397Y1013209D02*
X901222D01*
G01X895669Y1013366D02*
X894685D01*
G01X895669Y1013563D02*
X894685D01*
G01X895669Y1013957D02*
X894685D01*
G01X902965Y1015085D02*
X903226D01*
G01X903313Y1015597D02*
X902878D01*
G01X895669Y1015925D02*
X894685D01*
G01X901484Y1016280D02*
X900787D01*
G01X895669Y1016319D02*
X894685D01*
G01X895669Y1016516D02*
X894685D01*
G01X904272Y1016791D02*
X900874D01*
G01X900177Y1017303D02*
X904272D01*
G01X895669Y1018366D02*
X894685D01*
G01X895669Y1018563D02*
X894685D01*
G01X895669Y1018957D02*
X894685D01*
G01X895669Y1020925D02*
X894685D01*
G01X895669Y1021319D02*
X894685D01*
G01X895669Y1021516D02*
X894685D01*
G01X895669Y1023366D02*
X894685D01*
G01X895669Y1023563D02*
X894685D01*
G01X895669Y1023957D02*
X894685D01*
G01X895669Y1025925D02*
X894685D01*
G01X895669Y1026319D02*
X894685D01*
G01X895669Y1026516D02*
X894685D01*
G01X927953Y1027736D02*
X901260D01*
G01X895669Y1028366D02*
X894685D01*
G01X895669Y1028563D02*
X894685D01*
G01X895669Y1028957D02*
X894685D01*
G01X927953Y1030098D02*
X901260D01*
G01X895669Y1030925D02*
X894685D01*
G01X895669Y1031319D02*
X894685D01*
G01X895669Y1031516D02*
X894685D01*
G01X895669Y1033366D02*
X894685D01*
G01X895669Y1033563D02*
X894685D01*
G01X895669Y1033957D02*
X894685D01*
G01X895669Y1035925D02*
X894685D01*
G01X895669Y1036319D02*
X894685D01*
G01X895669Y1036516D02*
X894685D01*
G01X895669Y1038366D02*
X894685D01*
G01X895669Y1038563D02*
X894685D01*
G01X895669Y1038957D02*
X894685D01*
G01X895669Y1040925D02*
X894685D01*
G01X895669Y1041319D02*
X894685D01*
G01X928910Y1041339D02*
X909449D01*
G01X895669Y1041516D02*
X894685D01*
G01X895669Y1043366D02*
X894685D01*
G01X895669Y1043563D02*
X894685D01*
G01X895669Y1043957D02*
X894685D01*
G01X927953Y1045335D02*
X901260D01*
G01X895669Y1045925D02*
X894685D01*
G01X895669Y1046319D02*
X894685D01*
G01X895669Y1046516D02*
X894685D01*
G01X927953Y1047677D02*
X909449D01*
G01X899213D02*
X898110D01*
G01X923452Y1047697D02*
X901260D01*
G01X891678Y1047795D02*
X899213D01*
G01X896219Y1048287D02*
X894094D01*
G01X897203Y1048583D02*
X896219D01*
G01X897203Y1048780D02*
X896219D01*
G01X898110Y1048976D02*
X892085D01*
G01X898110Y1050157D02*
X892085D01*
G01X897203Y1050354D02*
X896219D01*
G01X897203Y1050551D02*
X896219D01*
G01X897203Y1051732D02*
X896219D01*
G01X897203Y1051929D02*
X896219D01*
G01X898110Y1052126D02*
X892085D01*
G01X898110Y1053307D02*
X892085D01*
G01X897203Y1053504D02*
X896219D01*
G01X897203Y1053701D02*
X896219D01*
G01X897203Y1054882D02*
X896219D01*
G01X897203Y1055079D02*
X896219D01*
G01X898110Y1055276D02*
X892085D01*
G01X898110Y1056457D02*
X892085D01*
G01X897203Y1056654D02*
X896219D01*
G01X897203Y1056850D02*
X896219D01*
G01X897203Y1058031D02*
X896219D01*
G01X897203Y1058228D02*
X896219D01*
G01X898110Y1058425D02*
X892085D01*
G01X898110Y1059606D02*
X892085D01*
G01X897203Y1059803D02*
X896219D01*
G01X897203Y1060000D02*
X896219D01*
G01X897203Y1061181D02*
X896219D01*
G01X897203Y1061378D02*
X896219D01*
G01X898110Y1061575D02*
X892085D01*
G01X898110Y1062756D02*
X892085D01*
G01X897203Y1062953D02*
X896219D01*
G01X897203Y1063150D02*
X896219D01*
G01X897203Y1064331D02*
X896219D01*
G01X897203Y1064528D02*
X896219D01*
G01X898110Y1064724D02*
X892085D01*
G01X900961Y1014744D02*
X901135Y1014829D01*
G01X902878Y1015597D02*
X902529Y1015426D01*
G01X901135Y1015341D02*
X900874Y1015256D01*
G01X901658Y1013294D02*
X901397Y1013209D01*
G01X903400Y1013038D02*
X903139Y1012953D01*
G01X900787Y1012782D02*
X901135Y1012697D01*
G01X901222Y1013209D02*
X900961Y1013294D01*
G01X900874Y1015256D02*
X900526Y1015000D01*
G01X902704Y1014915D02*
X902965Y1015085D01*
G01X903487Y1012526D02*
X903923Y1012782D01*
G01X903662Y1015426D02*
X903313Y1015597D01*
G01X903226Y1015085D02*
X903487Y1014915D01*
G01X902529Y1014659D02*
X902704Y1014915D01*
G01X901832Y1013550D02*
X901658Y1013294D01*
G01X900526Y1015000D02*
X900264Y1014659D01*
G01X900787Y1014573D02*
X900961Y1014744D01*
G01X902529Y1015426D02*
X902181Y1015085D01*
G01X901832Y1012782D02*
X902181Y1013123D01*
G01X903662Y1013294D02*
X903400Y1013038D01*
G01X900787Y1016280D02*
X900177Y1016791D01*
G01X900874D02*
X901484Y1016280D01*
G01X900438Y1013123D02*
X900787Y1012782D01*
G01X904010Y1015085D02*
X903662Y1015426D01*
G01X891522Y1064134D02*
Y1063346D01*
G01Y1060984D02*
Y1060197D01*
G01Y1057835D02*
Y1057047D01*
G01Y1054685D02*
Y1053898D01*
G01Y1051535D02*
Y1050748D01*
G01Y1048386D02*
Y1047598D01*
G01Y1045236D02*
Y1044449D01*
G01Y1042087D02*
Y1041299D01*
G01Y1038937D02*
Y1038150D01*
G01Y1035787D02*
Y1035000D01*
G01Y1032638D02*
Y1031850D01*
G01Y1029488D02*
Y1028701D01*
G01Y1026339D02*
Y1025551D01*
G01Y1023189D02*
Y1022402D01*
G01Y1020039D02*
Y1019252D01*
G01Y1016890D02*
Y1016102D01*
G01X891678Y1047795D02*
Y1051614D01*
G01Y1053819D02*
Y1061063D01*
G01Y1063268D02*
Y1067087D01*
G01X892085Y1065906D02*
Y1064724D01*
G01Y1062756D02*
Y1061575D01*
G01Y1059606D02*
Y1058425D01*
G01Y1056457D02*
Y1055276D01*
G01Y1053307D02*
Y1052126D01*
G01Y1050157D02*
Y1048976D01*
G01X892104Y1063268D02*
Y1061063D01*
G01Y1053819D02*
Y1051614D01*
G01X892156Y1047795D02*
Y1067087D01*
G01X892474Y1006201D02*
Y1008957D01*
G01X893113Y1008563D02*
Y1008504D01*
G01X893506Y1064134D02*
Y1063346D01*
G01Y1060984D02*
Y1060197D01*
G01Y1057835D02*
Y1057047D01*
G01Y1054685D02*
Y1053898D01*
G01Y1051535D02*
Y1050748D01*
G01Y1048386D02*
Y1047598D01*
G01Y1045236D02*
Y1044449D01*
G01Y1042087D02*
Y1041299D01*
G01Y1038937D02*
Y1038150D01*
G01Y1035787D02*
Y1035000D01*
G01Y1032638D02*
Y1031850D01*
G01Y1029488D02*
Y1028701D01*
G01Y1026339D02*
Y1025551D01*
G01Y1023189D02*
Y1022402D01*
G01Y1020039D02*
Y1019252D01*
G01Y1016890D02*
Y1016102D01*
G01X893640Y1011535D02*
Y1143150D01*
G01X893701Y1045728D02*
Y1044154D01*
G01Y1040728D02*
Y1039154D01*
G01Y1035728D02*
Y1034154D01*
G01Y1030728D02*
Y1029154D01*
G01Y1025728D02*
Y1024154D01*
G01Y1020728D02*
Y1019154D01*
G01Y1015728D02*
Y1014154D01*
G01X894094Y1008957D02*
Y1145925D01*
G01X894685Y1046516D02*
Y1043366D01*
G01Y1041516D02*
Y1038366D01*
G01Y1036516D02*
Y1033366D01*
G01Y1031516D02*
Y1028366D01*
G01Y1026516D02*
Y1023366D01*
G01Y1021516D02*
Y1018366D01*
G01Y1016516D02*
Y1013366D01*
G01X895235Y1065906D02*
Y1064724D01*
G01Y1062756D02*
Y1061575D01*
G01Y1059606D02*
Y1058425D01*
G01Y1056457D02*
Y1055276D01*
G01Y1053307D02*
Y1052126D01*
G01Y1050157D02*
Y1048976D01*
G01X895512Y1047795D02*
Y1067087D01*
G01X895669Y1046516D02*
Y1043366D01*
G01Y1041516D02*
Y1038366D01*
G01Y1036516D02*
Y1033366D01*
G01Y1031516D02*
Y1028366D01*
G01Y1026516D02*
Y1023366D01*
G01Y1021516D02*
Y1018366D01*
G01Y1016516D02*
Y1013366D01*
G01Y1008504D02*
Y1006201D01*
G01X896219Y1048287D02*
Y1066594D01*
G01X896429Y1067087D02*
Y1047795D01*
G01X896654Y1045728D02*
Y1044154D01*
G01Y1040728D02*
Y1039154D01*
G01Y1035728D02*
Y1034154D01*
G01Y1030728D02*
Y1029154D01*
G01Y1025728D02*
Y1024154D01*
G01Y1020728D02*
Y1019154D01*
G01Y1015728D02*
Y1014154D01*
G01X896868Y1019252D02*
Y1020039D01*
G01Y1016102D02*
Y1016890D01*
G01Y1022402D02*
Y1023189D01*
G01Y1028701D02*
Y1029488D01*
G01Y1025551D02*
Y1026339D01*
G01Y1031850D02*
Y1032638D01*
G01Y1038150D02*
Y1038937D01*
G01Y1035000D02*
Y1035787D01*
G01Y1041299D02*
Y1042087D01*
G01Y1047598D02*
Y1048386D01*
G01Y1044449D02*
Y1045236D01*
G01Y1050748D02*
Y1051535D01*
G01Y1057047D02*
Y1057835D01*
G01Y1053898D02*
Y1054685D01*
G01Y1060197D02*
Y1060984D01*
G01Y1063346D02*
Y1064134D01*
G01X896929Y1067087D02*
Y1047795D01*
G01X897203Y1066496D02*
Y1064134D01*
G01Y1063346D02*
Y1060984D01*
G01Y1060197D02*
Y1057835D01*
G01Y1057047D02*
Y1054685D01*
G01Y1053898D02*
Y1051535D01*
G01Y1050748D02*
Y1048386D01*
G01X897244Y1019252D02*
Y1020039D01*
G01Y1016102D02*
Y1016890D01*
G01Y1022402D02*
Y1023189D01*
G01Y1028701D02*
Y1029488D01*
G01Y1025551D02*
Y1026339D01*
G01Y1031850D02*
Y1032638D01*
G01Y1038150D02*
Y1038937D01*
G01Y1035000D02*
Y1035787D01*
G01Y1041299D02*
Y1042087D01*
G01Y1047598D02*
Y1048386D01*
G01Y1044449D02*
Y1045236D01*
G01Y1050748D02*
Y1051535D01*
G01Y1057047D02*
Y1057835D01*
G01Y1053898D02*
Y1054685D01*
G01Y1060197D02*
Y1060984D01*
G01Y1063346D02*
Y1064134D01*
G01X897270Y1019252D02*
Y1020039D01*
G01Y1016102D02*
Y1016890D01*
G01Y1022402D02*
Y1023189D01*
G01Y1028701D02*
Y1029488D01*
G01Y1025551D02*
Y1026339D01*
G01Y1031850D02*
Y1032638D01*
G01Y1038150D02*
Y1038937D01*
G01Y1035000D02*
Y1035787D01*
G01Y1041299D02*
Y1042087D01*
G01Y1047598D02*
Y1048386D01*
G01Y1044449D02*
Y1045236D01*
G01Y1050748D02*
Y1051535D01*
G01Y1057047D02*
Y1057835D01*
G01Y1053898D02*
Y1054685D01*
G01Y1060197D02*
Y1060984D01*
G01Y1063346D02*
Y1064134D01*
G01X897657Y1013976D02*
Y1015945D01*
G01X897717Y1047795D02*
Y1067087D01*
G01X898031D02*
Y1047795D01*
G01X898110Y1008957D02*
Y1145925D01*
G01X899213Y1146378D02*
Y1008504D01*
G01X900177Y1014232D02*
Y1013806D01*
G01Y1016791D02*
Y1017303D01*
G01X900700Y1013806D02*
Y1014317D01*
G01X901135Y1014829D02*
Y1015341D01*
G01X901260Y1011319D02*
Y1143563D01*
G01X901575Y1008012D02*
Y1005571D01*
G01X901919Y1014317D02*
Y1013806D01*
G01X902442D02*
Y1014317D01*
G01X903139Y1012953D02*
Y1012441D01*
G01X903228Y1067185D02*
Y1047697D01*
G01Y1045335D02*
Y1030098D01*
G01Y1027736D02*
Y1011319D01*
G01X903749Y1014317D02*
Y1013635D01*
G01X900264Y1014659D02*
X900177Y1014232D01*
G01X902006Y1014744D02*
X901919Y1014317D01*
G01X904184Y1013209D02*
X904272Y1013635D01*
G01X902442Y1014317D02*
X902529Y1014659D01*
G01X902355Y1013465D02*
X902442Y1013806D01*
G01X903749Y1013635D02*
X903662Y1013294D01*
G01X900700Y1014317D02*
X900787Y1014573D01*
G01X901919Y1013806D02*
X901832Y1013550D01*
G01X902181Y1015085D02*
X902006Y1014744D01*
G01X902181Y1013123D02*
X902355Y1013465D01*
G01X903923Y1012782D02*
X904184Y1013209D01*
G01X900961Y1013294D02*
X900787Y1013550D01*
G01X903487Y1014915D02*
X903662Y1014659D01*
G01X892857Y1008957D02*
X893113Y1008563D01*
G01X900264Y1013465D02*
X900438Y1013123D01*
G01X904184Y1014744D02*
X904010Y1015085D01*
G01X900787Y1013550D02*
X900700Y1013806D01*
G01X900177D02*
X900264Y1013465D01*
G01X903662Y1014659D02*
X903749Y1014317D01*
G01X904272D02*
X904184Y1014744D01*
G01X904272Y1017303D02*
Y1016791D01*
G01Y1013635D02*
Y1014317D01*
G01X907480Y1011909D02*
Y1010138D01*
G01X909449Y1143760D02*
Y1011122D01*
G01X898110Y1018760D02*
G03X897717Y1019154I-394J0D01*
G01Y1020728D02*
G03X898110Y1021122I-1J394D01*
G01Y1028760D02*
G03X897717Y1029154I-394J0D01*
G01Y1030728D02*
G03X898110Y1031122I-1J394D01*
G01Y1023760D02*
G03X897717Y1024154I-394J0D01*
G01Y1025728D02*
G03X898110Y1026122I-1J394D01*
G01Y1033760D02*
G03X897717Y1034154I-394J0D01*
G01Y1035728D02*
G03X898110Y1036122I-1J394D01*
G01Y1038760D02*
G03X897717Y1039154I-394J0D01*
G01Y1040728D02*
G03X898110Y1041122I-1J394D01*
G01Y1043760D02*
G03X897717Y1044154I-394J0D01*
G01Y1045728D02*
G03X898110Y1046122I-1J394D01*
G01Y1013760D02*
G03X897717Y1014154I-394J0D01*
G01Y1015728D02*
G03X898110Y1016122I-1J394D01*
G01X907795Y995098D02*
X891417D01*
G01X905512Y999035D02*
X931890D01*
G01X894943Y999075D02*
X898856D01*
G01X900775D02*
X901661D01*
G01X898856Y999813D02*
X895977D01*
G01X895239Y1003282D02*
X896050D01*
G01X900037Y1004242D02*
X902989D01*
G01X903875Y1004980D02*
X900037D01*
G01X896949Y1004242D02*
X897296Y1004173D01*
G01X892192Y999891D02*
X892552Y1000127D01*
X892791Y1000477D01*
X892876Y1000881D01*
X892794Y1001283D01*
X892557Y1001635D01*
X892194Y1001875D01*
X891769Y1001960D01*
G01X892118Y1002683D02*
X892400Y1002861D01*
X892588Y1003126D01*
X892655Y1003428D01*
X892590Y1003728D01*
X892405Y1003995D01*
X892119Y1004176D01*
X891769Y1004242D01*
G01X896307Y1004002D02*
X896594Y1004180D01*
X896948Y1004242D01*
G01X892118Y1004177D02*
X892400Y1003999D01*
X892588Y1003734D01*
X892655Y1003432D01*
X892590Y1003132D01*
X892405Y1002865D01*
X892119Y1002683D01*
X891769Y1002618D01*
G01X897296Y1004173D02*
X897576Y1003992D01*
G01X892192Y1001876D02*
X892552Y1001640D01*
X892791Y1001290D01*
X892876Y1000886D01*
X892794Y1000484D01*
X892557Y1000131D01*
X892194Y999892D01*
X891769Y999807D01*
G01X897576Y1002868D02*
X897759Y1003134D01*
X897822Y1003431D01*
X897757Y1003729D01*
G01X896307Y1004002D02*
X896118Y1003734D01*
G01X898147Y1002343D02*
X898484Y1002805D01*
X898630Y1003324D01*
X898570Y1003841D01*
X898319Y1004325D01*
X897882Y1004720D01*
X897309Y1004943D01*
X896674Y1004962D01*
X896090Y1004776D01*
X895635Y1004423D01*
X895342Y1003951D01*
X895239Y1003430D01*
G01X897576Y1002868D02*
X896013Y1001341D01*
G01X898147Y1002343D02*
X896519Y1000797D01*
G01X894943Y999518D02*
Y999075D01*
G01X895239Y1003430D02*
Y1003282D01*
G01X896050D02*
Y1003430D01*
G01X898856Y999075D02*
Y999813D01*
G01X900037Y1004980D02*
Y1004242D01*
G01X901575Y1003602D02*
Y999823D01*
G01X895239Y1003430D02*
X895325Y1003907D01*
X895573Y1004349D01*
X895961Y1004701D01*
X896468Y1004921D01*
X897045Y1004977D01*
X897609Y1004855D01*
X898085Y1004572D01*
X898424Y1004168D01*
X898604Y1003711D01*
X898619Y1003231D01*
X898462Y1002760D01*
X898147Y1002343D01*
G01X896118Y1003735D02*
X896050Y1003430D01*
G01X897575Y1003993D02*
X897758Y1003728D01*
X897822Y1003429D01*
X897757Y1003132D01*
G01X903875Y1004316D02*
Y1004980D01*
G01X905512Y997854D02*
Y1006201D01*
G01X896519Y1000797D02*
G03X895977Y999813I1276J-1344D01*
G01X903875Y1004316D02*
G03X901661Y999075I7143J-6105D01*
G01X902989Y1004242D02*
G03X900775Y999075I6938J-6031D01*
G01X896013Y1001341D02*
G03X894943Y999518I2809J-2875D01*
G01X877953Y1005571D02*
X901575D01*
G01X927953Y1006201D02*
X877953D01*
G01X901575Y1008012D02*
X877953D01*
G01X878745Y1008957D02*
X899213D01*
G01X898110Y1011535D02*
X877953D01*
G01X894094Y1013524D02*
X885110D01*
G01X889587Y1013976D02*
X897657D01*
G01X890551Y1014154D02*
X897717D01*
G01X890551Y1015728D02*
X897717D01*
G01X897657Y1015945D02*
X889587D01*
G01X879724Y1016102D02*
X887057D01*
G01X887204D02*
X899213D01*
G01Y1016890D02*
X887204D01*
G01X887057D02*
X879724D01*
G01X890551Y1019154D02*
X897717D01*
G01X879724Y1019252D02*
X887057D01*
G01X887204D02*
X899213D01*
G01Y1020039D02*
X887204D01*
G01X887057D02*
X879724D01*
G01X890551Y1020728D02*
X897717D01*
G01X879724Y1022402D02*
X887057D01*
G01X887204D02*
X899213D01*
G01Y1023189D02*
X887204D01*
G01X887057D02*
X879724D01*
G01X890551Y1024154D02*
X897717D01*
G01X879724Y1025551D02*
X887057D01*
G01X887204D02*
X899213D01*
G01X890551Y1025728D02*
X897717D01*
G01X899213Y1026339D02*
X887204D01*
G01X887057D02*
X879724D01*
G01Y1028701D02*
X887057D01*
G01X887204D02*
X899213D01*
G01X890551Y1029154D02*
X897717D01*
G01X899213Y1029488D02*
X887204D01*
G01X887057D02*
X879724D01*
G01X890551Y1030728D02*
X897717D01*
G01X879724Y1031850D02*
X887057D01*
G01X887204D02*
X899213D01*
G01Y1032638D02*
X887204D01*
G01X887057D02*
X879724D01*
G01X890551Y1034154D02*
X897717D01*
G01X879724Y1035000D02*
X887057D01*
G01X887204D02*
X899213D01*
G01X890551Y1035728D02*
X897717D01*
G01X899213Y1035787D02*
X887204D01*
G01X887057D02*
X879724D01*
G01Y1038150D02*
X887057D01*
G01X887204D02*
X899213D01*
G01Y1038937D02*
X887204D01*
G01X887057D02*
X879724D01*
G01X890551Y1039154D02*
X897717D01*
G01X890551Y1040728D02*
X897717D01*
G01X879724Y1041299D02*
X887057D01*
G01X887204D02*
X899213D01*
G01Y1042087D02*
X887204D01*
G01X887057D02*
X879724D01*
G01X890551Y1044154D02*
X897717D01*
G01X879724Y1044449D02*
X887057D01*
G01X887204D02*
X899213D01*
G01Y1045236D02*
X887204D01*
G01X887057D02*
X879724D01*
G01X890551Y1045728D02*
X897717D01*
G01X879724Y1047598D02*
X887057D01*
G01X887204D02*
X899213D01*
G01Y1048386D02*
X887204D01*
G01X887057D02*
X879724D01*
G01Y1050748D02*
X887057D01*
G01X887204D02*
X899213D01*
G01Y1051535D02*
X887204D01*
G01X887057D02*
X879724D01*
G01X890221Y1051614D02*
X892104D01*
G01Y1053819D02*
X890221D01*
G01X879724Y1053898D02*
X887057D01*
G01X887204D02*
X899213D01*
G01Y1054685D02*
X887204D01*
G01X887057D02*
X879724D01*
G01Y1057047D02*
X887057D01*
G01X887204D02*
X899213D01*
G01Y1057835D02*
X887204D01*
G01X887057D02*
X879724D01*
G01Y1060197D02*
X887057D01*
G01X887204D02*
X899213D01*
G01Y1060984D02*
X887204D01*
G01X887057D02*
X879724D01*
G01X890221Y1061063D02*
X892104D01*
G01Y1063268D02*
X890221D01*
G01X879724Y1063346D02*
X887057D01*
G01X887204D02*
X899213D01*
G01Y1064134D02*
X887204D01*
G01X887057D02*
X879724D01*
G01X878270Y1011535D02*
Y1006201D01*
G01X878745Y1011535D02*
Y1008957D01*
G01X879724Y1019252D02*
Y1020039D01*
G01Y1016102D02*
Y1016890D01*
G01Y1022402D02*
Y1023189D01*
G01Y1028701D02*
Y1029488D01*
G01Y1025551D02*
Y1026339D01*
G01Y1031850D02*
Y1032638D01*
G01Y1038150D02*
Y1038937D01*
G01Y1035000D02*
Y1035787D01*
G01Y1041299D02*
Y1042087D01*
G01Y1047598D02*
Y1048386D01*
G01Y1044449D02*
Y1045236D01*
G01Y1050748D02*
Y1051535D01*
G01Y1057047D02*
Y1057835D01*
G01Y1053898D02*
Y1054685D01*
G01Y1060197D02*
Y1060984D01*
G01Y1063346D02*
Y1064134D01*
G01X881498Y1019252D02*
Y1020039D01*
G01Y1016102D02*
Y1016890D01*
G01Y1022402D02*
Y1023189D01*
G01Y1028701D02*
Y1029488D01*
G01Y1025551D02*
Y1026339D01*
G01Y1031850D02*
Y1032638D01*
G01Y1038150D02*
Y1038937D01*
G01Y1035000D02*
Y1035787D01*
G01Y1041299D02*
Y1042087D01*
G01Y1047598D02*
Y1048386D01*
G01Y1044449D02*
Y1045236D01*
G01Y1050748D02*
Y1051535D01*
G01Y1057047D02*
Y1057835D01*
G01Y1053898D02*
Y1054685D01*
G01Y1060197D02*
Y1060984D01*
G01Y1063346D02*
Y1064134D01*
G01X881686D02*
Y1063346D01*
G01Y1060984D02*
Y1060197D01*
G01Y1057835D02*
Y1057047D01*
G01Y1054685D02*
Y1053898D01*
G01Y1051535D02*
Y1050748D01*
G01Y1048386D02*
Y1047598D01*
G01Y1045236D02*
Y1044449D01*
G01Y1042087D02*
Y1041299D01*
G01Y1038937D02*
Y1038150D01*
G01Y1035787D02*
Y1035000D01*
G01Y1032638D02*
Y1031850D01*
G01Y1029488D02*
Y1028701D01*
G01Y1026339D02*
Y1025551D01*
G01Y1023189D02*
Y1022402D01*
G01Y1020039D02*
Y1019252D01*
G01Y1016890D02*
Y1016102D01*
G01X884523Y1064134D02*
Y1063346D01*
G01Y1060984D02*
Y1060197D01*
G01Y1057835D02*
Y1057047D01*
G01Y1054685D02*
Y1053898D01*
G01Y1051535D02*
Y1050748D01*
G01Y1048386D02*
Y1047598D01*
G01Y1045236D02*
Y1044449D01*
G01Y1042087D02*
Y1041299D01*
G01Y1038937D02*
Y1038150D01*
G01Y1035787D02*
Y1035000D01*
G01Y1032638D02*
Y1031850D01*
G01Y1029488D02*
Y1028701D01*
G01Y1026339D02*
Y1025551D01*
G01Y1023189D02*
Y1022402D01*
G01Y1020039D02*
Y1019252D01*
G01Y1016890D02*
Y1016102D01*
G01X884600Y1006201D02*
Y1008957D01*
G01X885110Y1145925D02*
Y1008957D01*
G01X885464Y1019252D02*
Y1020039D01*
G01Y1016102D02*
Y1016890D01*
G01Y1022402D02*
Y1023189D01*
G01Y1028701D02*
Y1029488D01*
G01Y1025551D02*
Y1026339D01*
G01Y1031850D02*
Y1032638D01*
G01Y1038150D02*
Y1038937D01*
G01Y1035000D02*
Y1035787D01*
G01Y1041299D02*
Y1042087D01*
G01Y1047598D02*
Y1048386D01*
G01Y1044449D02*
Y1045236D01*
G01Y1050748D02*
Y1051535D01*
G01Y1057047D02*
Y1057835D01*
G01Y1053898D02*
Y1054685D01*
G01Y1060197D02*
Y1060984D01*
G01Y1063346D02*
Y1064134D01*
G01X887057Y1019252D02*
Y1020039D01*
G01Y1016102D02*
Y1016890D01*
G01Y1022402D02*
Y1023189D01*
G01Y1028701D02*
Y1029488D01*
G01Y1025551D02*
Y1026339D01*
G01Y1031850D02*
Y1032638D01*
G01Y1038150D02*
Y1038937D01*
G01Y1035000D02*
Y1035787D01*
G01Y1041299D02*
Y1042087D01*
G01Y1047598D02*
Y1048386D01*
G01Y1044449D02*
Y1045236D01*
G01Y1050748D02*
Y1051535D01*
G01Y1057047D02*
Y1057835D01*
G01Y1053898D02*
Y1054685D01*
G01Y1060197D02*
Y1060984D01*
G01Y1063346D02*
Y1064134D01*
G01X887204Y1019252D02*
Y1020039D01*
G01Y1016102D02*
Y1016890D01*
G01Y1022402D02*
Y1023189D01*
G01Y1028701D02*
Y1029488D01*
G01Y1025551D02*
Y1026339D01*
G01Y1031850D02*
Y1032638D01*
G01Y1038150D02*
Y1038937D01*
G01Y1035000D02*
Y1035787D01*
G01Y1041299D02*
Y1042087D01*
G01Y1047598D02*
Y1048386D01*
G01Y1044449D02*
Y1045236D01*
G01Y1050748D02*
Y1051535D01*
G01Y1057047D02*
Y1057835D01*
G01Y1053898D02*
Y1054685D01*
G01Y1060197D02*
Y1060984D01*
G01Y1063346D02*
Y1064134D01*
G01X888142Y1066496D02*
Y1064134D01*
G01Y1063346D02*
Y1060984D01*
G01Y1060197D02*
Y1057835D01*
G01Y1057047D02*
Y1054685D01*
G01Y1053898D02*
Y1051535D01*
G01Y1050748D02*
Y1048386D01*
G01Y1047598D02*
Y1045236D01*
G01Y1044449D02*
Y1042087D01*
G01Y1041299D02*
Y1038937D01*
G01Y1038150D02*
Y1035787D01*
G01Y1035000D02*
Y1032638D01*
G01Y1031850D02*
Y1029488D01*
G01Y1028701D02*
Y1026339D01*
G01Y1025551D02*
Y1023189D01*
G01Y1022402D02*
Y1020039D01*
G01Y1019252D02*
Y1016890D01*
G01Y1016102D02*
Y1013524D01*
G01X889587Y1015945D02*
Y1013976D01*
G01X889870Y1019252D02*
Y1020039D01*
G01Y1016102D02*
Y1016890D01*
G01Y1022402D02*
Y1023189D01*
G01Y1028701D02*
Y1029488D01*
G01Y1025551D02*
Y1026339D01*
G01Y1031850D02*
Y1032638D01*
G01Y1038150D02*
Y1038937D01*
G01Y1035000D02*
Y1035787D01*
G01Y1041299D02*
Y1042087D01*
G01Y1047598D02*
Y1048386D01*
G01Y1044449D02*
Y1045236D01*
G01Y1050748D02*
Y1051535D01*
G01Y1057047D02*
Y1057835D01*
G01Y1053898D02*
Y1054685D01*
G01Y1060197D02*
Y1060984D01*
G01Y1063346D02*
Y1064134D01*
G01X890221Y1051614D02*
Y1053819D01*
G01Y1061063D02*
Y1063268D01*
G01X890551Y1045728D02*
Y1044154D01*
G01Y1040728D02*
Y1039154D01*
G01Y1035728D02*
Y1034154D01*
G01Y1030728D02*
Y1029154D01*
G01Y1025728D02*
Y1024154D01*
G01Y1020728D02*
Y1019154D01*
G01Y1015728D02*
Y1014154D01*
G01X931890Y997854D02*
X877953D01*
G01X880327Y999075D02*
X881213D01*
G01X901575Y999823D02*
X877953D01*
G01X901575Y1003602D02*
X877953D01*
G01X879589Y1004242D02*
X882542D01*
G01X883428Y1004980D02*
X879589D01*
G01X886179Y1001876D02*
X885819Y1001640D01*
X885580Y1001290D01*
X885494Y1000886D01*
X885577Y1000484D01*
X885813Y1000131D01*
X886177Y999892D01*
X886602Y999807D01*
G01X887025Y999891D02*
X887385Y1000127D01*
X887624Y1000477D01*
X887709Y1000881D01*
X887626Y1001283D01*
X887390Y1001635D01*
X887026Y1001875D01*
X886602Y1001960D01*
G01X891346Y1001876D02*
X890986Y1001640D01*
X890747Y1001290D01*
X890662Y1000886D01*
X890744Y1000484D01*
X890981Y1000131D01*
X891344Y999892D01*
X891769Y999807D01*
G01X886253Y1004177D02*
X885970Y1003999D01*
X885783Y1003734D01*
X885716Y1003432D01*
X885780Y1003132D01*
X885966Y1002865D01*
X886251Y1002683D01*
X886602Y1002618D01*
G01X886951Y1002683D02*
X887233Y1002861D01*
X887420Y1003126D01*
X887487Y1003428D01*
X887423Y1003728D01*
X887237Y1003995D01*
X886952Y1004176D01*
X886602Y1004242D01*
G01X891420Y1004177D02*
X891137Y1003999D01*
X890950Y1003734D01*
X890883Y1003432D01*
X890948Y1003132D01*
X891133Y1002865D01*
X891419Y1002683D01*
X891769Y1002618D01*
G01X886253Y1002683D02*
X885970Y1002861D01*
X885783Y1003126D01*
X885716Y1003428D01*
X885780Y1003728D01*
X885966Y1003995D01*
X886251Y1004176D01*
X886602Y1004242D01*
G01X886951Y1004177D02*
X887233Y1003999D01*
X887420Y1003734D01*
X887487Y1003432D01*
X887423Y1003132D01*
X887237Y1002865D01*
X886952Y1002683D01*
X886602Y1002618D01*
G01X891420Y1002683D02*
X891137Y1002861D01*
X890950Y1003126D01*
X890883Y1003428D01*
X890948Y1003728D01*
X891133Y1003995D01*
X891419Y1004176D01*
X891769Y1004242D01*
G01X886179Y999891D02*
X885819Y1000127D01*
X885580Y1000477D01*
X885494Y1000881D01*
X885577Y1001283D01*
X885813Y1001635D01*
X886177Y1001875D01*
X886602Y1001960D01*
G01X887025Y1001876D02*
X887385Y1001640D01*
X887624Y1001290D01*
X887709Y1000886D01*
X887626Y1000484D01*
X887390Y1000131D01*
X887026Y999892D01*
X886602Y999807D01*
G01X891346Y999891D02*
X890986Y1000127D01*
X890747Y1000477D01*
X890662Y1000881D01*
X890744Y1001283D01*
X890981Y1001635D01*
X891344Y1001875D01*
X891769Y1001960D01*
G01X887800Y1002331D02*
X888122Y1002751D01*
X888285Y1003234D01*
X888263Y1003739D01*
X888060Y1004216D01*
X887693Y1004619D01*
X887187Y1004886D01*
X886596Y1004980D01*
X886007Y1004883D01*
X885504Y1004614D01*
X885140Y1004210D01*
X884939Y1003732D01*
X884920Y1003228D01*
X885083Y1002746D01*
X885404Y1002331D01*
G01X892967D02*
X893289Y1002751D01*
X893452Y1003234D01*
X893430Y1003739D01*
X893227Y1004216D01*
X892861Y1004619D01*
X892354Y1004886D01*
X891763Y1004980D01*
X891174Y1004883D01*
X890672Y1004614D01*
X890307Y1004210D01*
X890106Y1003732D01*
X890087Y1003228D01*
X890251Y1002746D01*
X890571Y1002331D01*
G01X885404D02*
X884952Y1001891D01*
X884682Y1001355D01*
X884612Y1000785D01*
X884754Y1000221D01*
X885100Y999696D01*
X885628Y999303D01*
X886270Y999100D01*
X886950Y999102D01*
X887590Y999310D01*
X888112Y999706D01*
X888454Y1000230D01*
X888592Y1000791D01*
X888520Y1001359D01*
X888250Y1001893D01*
G01X890571Y1002331D02*
X890120Y1001891D01*
X889850Y1001355D01*
X889779Y1000785D01*
X889921Y1000221D01*
X890268Y999696D01*
X890795Y999303D01*
X891437Y999100D01*
X892117Y999102D01*
X892757Y999310D01*
X893280Y999706D01*
X893621Y1000230D01*
X893759Y1000791D01*
X893687Y1001359D01*
X893417Y1001893D01*
G01X887800Y1002331D02*
X888251Y1001891D01*
X888521Y1001355D01*
X888592Y1000785D01*
X888450Y1000221D01*
X888103Y999696D01*
X887576Y999303D01*
X886933Y999100D01*
X886254Y999102D01*
X885614Y999310D01*
X885091Y999706D01*
X884750Y1000230D01*
X884611Y1000791D01*
X884683Y1001359D01*
X884954Y1001893D01*
G01X892967Y1002331D02*
X893419Y1001891D01*
X893689Y1001355D01*
X893759Y1000785D01*
X893617Y1000221D01*
X893270Y999696D01*
X892743Y999303D01*
X892100Y999100D01*
X891421Y999102D01*
X890781Y999310D01*
X890258Y999706D01*
X889917Y1000230D01*
X889779Y1000791D01*
X889850Y1001359D01*
X890121Y1001893D01*
G01X885404Y1002331D02*
X885081Y1002751D01*
X884919Y1003234D01*
X884941Y1003739D01*
X885143Y1004216D01*
X885510Y1004619D01*
X886017Y1004886D01*
X886607Y1004980D01*
X887197Y1004883D01*
X887699Y1004614D01*
X888063Y1004210D01*
X888265Y1003732D01*
X888284Y1003228D01*
X888120Y1002746D01*
X887800Y1002331D01*
G01X890571D02*
X890249Y1002751D01*
X890086Y1003234D01*
X890108Y1003739D01*
X890311Y1004216D01*
X890678Y1004619D01*
X891184Y1004886D01*
X891775Y1004980D01*
X892364Y1004883D01*
X892867Y1004614D01*
X893231Y1004210D01*
X893432Y1003732D01*
X893451Y1003228D01*
X893287Y1002746D01*
X892967Y1002331D01*
G01X877953Y1011535D02*
Y997854D01*
G01X879589Y1004980D02*
Y1004242D01*
G01X883428Y1004316D02*
Y1004980D01*
G01Y1004316D02*
G03X881213Y999075I7141J-6107D01*
G01X882542Y1004242D02*
G03X880327Y999075I6937J-6032D01*
G01X894882Y1002638D02*
G03I-4528J0D01*
G01X893858D02*
G03I-3504J0D01*
G01X893701D02*
G03I-3347J0D01*
G01X892520D02*
G03I-2166J0D01*
G01X897203Y1066299D02*
X896219D01*
G01Y1066594D02*
X894094D01*
G01X899213Y1067087D02*
X891678D01*
G01X923452Y1067185D02*
X901260D01*
G01X899213Y1067205D02*
X898110D01*
G01X909449D02*
X927953D01*
G01X895669Y1068366D02*
X894685D01*
G01X895669Y1068563D02*
X894685D01*
G01X895669Y1068957D02*
X894685D01*
G01X927953Y1069547D02*
X901260D01*
G01X895669Y1070925D02*
X894685D01*
G01X895669Y1071319D02*
X894685D01*
G01X895669Y1071516D02*
X894685D01*
G01X895669Y1073366D02*
X894685D01*
G01X895669Y1073563D02*
X894685D01*
G01X928910Y1073642D02*
X909449D01*
G01X895669Y1073957D02*
X894685D01*
G01X895669Y1075925D02*
X894685D01*
G01X895669Y1076319D02*
X894685D01*
G01X895669Y1076516D02*
X894685D01*
G01X895669Y1078366D02*
X894685D01*
G01X895669Y1078563D02*
X894685D01*
G01X895669Y1078957D02*
X894685D01*
G01X895669Y1080925D02*
X894685D01*
G01X895669Y1081319D02*
X894685D01*
G01X895669Y1081516D02*
X894685D01*
G01X899213Y1082736D02*
X898110D01*
G01X897638Y1083366D02*
X896654D01*
G01X897638Y1083563D02*
X896654D01*
G01X897638Y1083957D02*
X896654D01*
G01X898110Y1084154D02*
X892520D01*
G01X898110Y1085728D02*
X892520D01*
G01X927953Y1085886D02*
X901260D01*
G01X897638Y1085925D02*
X896654D01*
G01X897638Y1086319D02*
X896654D01*
G01X897638Y1086516D02*
X896654D01*
G01X898110Y1087146D02*
X899213D01*
G01X927953Y1088248D02*
X901260D01*
G01X895669Y1088366D02*
X894685D01*
G01X895669Y1088563D02*
X894685D01*
G01X895669Y1088957D02*
X894685D01*
G01X895669Y1090925D02*
X894685D01*
G01X895669Y1091319D02*
X894685D01*
G01X895669Y1091516D02*
X894685D01*
G01X895669Y1093366D02*
X894685D01*
G01X895669Y1093563D02*
X894685D01*
G01X895669Y1093957D02*
X894685D01*
G01X895669Y1095925D02*
X894685D01*
G01X895669Y1096319D02*
X894685D01*
G01X895669Y1096516D02*
X894685D01*
G01X895669Y1098366D02*
X894685D01*
G01X895669Y1098563D02*
X894685D01*
G01X895669Y1098957D02*
X894685D01*
G01X895669Y1100925D02*
X894685D01*
G01X895669Y1101319D02*
X894685D01*
G01X895669Y1101516D02*
X894685D01*
G01X895669Y1103366D02*
X894685D01*
G01X895669Y1103563D02*
X894685D01*
G01X895669Y1103957D02*
X894685D01*
G01X927953Y1104783D02*
X901260D01*
G01X891522Y1105079D02*
Y1104291D01*
G01Y1101929D02*
Y1101142D01*
G01Y1098780D02*
Y1097992D01*
G01Y1095630D02*
Y1094843D01*
G01Y1092480D02*
Y1091693D01*
G01Y1089331D02*
Y1088543D01*
G01Y1086181D02*
Y1085394D01*
G01Y1083031D02*
Y1082244D01*
G01Y1079882D02*
Y1079094D01*
G01Y1076732D02*
Y1075945D01*
G01Y1073583D02*
Y1072795D01*
G01Y1070433D02*
Y1069646D01*
G01Y1067283D02*
Y1066496D01*
G01X892520Y1085728D02*
Y1084154D01*
G01X893506Y1105079D02*
Y1104291D01*
G01Y1101929D02*
Y1101142D01*
G01Y1098780D02*
Y1097992D01*
G01Y1095630D02*
Y1094843D01*
G01Y1092480D02*
Y1091693D01*
G01Y1089331D02*
Y1088543D01*
G01Y1086181D02*
Y1085394D01*
G01Y1083031D02*
Y1082244D01*
G01Y1079882D02*
Y1079094D01*
G01Y1076732D02*
Y1075945D01*
G01Y1073583D02*
Y1072795D01*
G01Y1070433D02*
Y1069646D01*
G01Y1067283D02*
Y1066496D01*
G01X893701Y1105728D02*
Y1104154D01*
G01Y1100728D02*
Y1099154D01*
G01Y1095728D02*
Y1094154D01*
G01Y1090728D02*
Y1089154D01*
G01Y1080728D02*
Y1079154D01*
G01Y1075728D02*
Y1074154D01*
G01Y1070728D02*
Y1069154D01*
G01X894685Y1106516D02*
Y1103366D01*
G01Y1101516D02*
Y1098366D01*
G01Y1096516D02*
Y1093366D01*
G01Y1091516D02*
Y1088366D01*
G01Y1081516D02*
Y1078366D01*
G01Y1076516D02*
Y1073366D01*
G01Y1071516D02*
Y1068366D01*
G01X895669Y1106516D02*
Y1103366D01*
G01Y1101516D02*
Y1098366D01*
G01Y1096516D02*
Y1093366D01*
G01Y1091516D02*
Y1088366D01*
G01Y1085728D02*
Y1084154D01*
G01Y1081516D02*
Y1078366D01*
G01Y1076516D02*
Y1073366D01*
G01Y1071516D02*
Y1068366D01*
G01X896654Y1105728D02*
Y1104154D01*
G01Y1100728D02*
Y1099154D01*
G01Y1095728D02*
Y1094154D01*
G01Y1090728D02*
Y1089154D01*
G01Y1086516D02*
Y1083366D01*
G01Y1080728D02*
Y1079154D01*
G01Y1075728D02*
Y1074154D01*
G01Y1070728D02*
Y1069154D01*
G01X896868Y1066496D02*
Y1067283D01*
G01Y1069646D02*
Y1070433D01*
G01Y1075945D02*
Y1076732D01*
G01Y1072795D02*
Y1073583D01*
G01Y1079094D02*
Y1079882D01*
G01Y1085394D02*
Y1086181D01*
G01Y1082244D02*
Y1083031D01*
G01Y1088543D02*
Y1089331D01*
G01Y1094843D02*
Y1095630D01*
G01Y1091693D02*
Y1092480D01*
G01Y1097992D02*
Y1098780D01*
G01Y1104291D02*
Y1105079D01*
G01Y1101142D02*
Y1101929D01*
G01X897244Y1066496D02*
Y1067283D01*
G01Y1069646D02*
Y1070433D01*
G01Y1075945D02*
Y1076732D01*
G01Y1072795D02*
Y1073583D01*
G01Y1079094D02*
Y1079882D01*
G01Y1085394D02*
Y1086181D01*
G01Y1082244D02*
Y1083031D01*
G01Y1088543D02*
Y1089331D01*
G01Y1094843D02*
Y1095630D01*
G01Y1091693D02*
Y1092480D01*
G01Y1097992D02*
Y1098780D01*
G01Y1104291D02*
Y1105079D01*
G01Y1101142D02*
Y1101929D01*
G01X897270Y1066496D02*
Y1067283D01*
G01Y1069646D02*
Y1070433D01*
G01Y1075945D02*
Y1076732D01*
G01Y1072795D02*
Y1073583D01*
G01Y1079094D02*
Y1079882D01*
G01Y1085394D02*
Y1086181D01*
G01Y1082244D02*
Y1083031D01*
G01Y1088543D02*
Y1089331D01*
G01Y1094843D02*
Y1095630D01*
G01Y1091693D02*
Y1092480D01*
G01Y1097992D02*
Y1098780D01*
G01Y1104291D02*
Y1105079D01*
G01Y1101142D02*
Y1101929D01*
G01X897638Y1086516D02*
Y1083366D01*
G01X903228Y1069547D02*
Y1085886D01*
G01Y1088248D02*
Y1104783D01*
G01X898110Y1068760D02*
G03X897717Y1069154I-394J0D01*
G01Y1070728D02*
G03X898110Y1071122I-1J394D01*
G01Y1078760D02*
G03X897717Y1079154I-394J0D01*
G01Y1080728D02*
G03X898110Y1081122I-1J394D01*
G01Y1073760D02*
G03X897717Y1074154I-394J0D01*
G01Y1075728D02*
G03X898110Y1076122I-1J394D01*
G01Y1093760D02*
G03X897717Y1094154I-394J0D01*
G01Y1095728D02*
G03X898110Y1096122I-1J394D01*
G01Y1103760D02*
G03X897717Y1104154I-394J0D01*
G01X898110Y1098760D02*
G03X897717Y1099154I-394J0D01*
G01Y1100728D02*
G03X898110Y1101122I-1J394D01*
G01Y1088760D02*
G03X897717Y1089154I-394J0D01*
G01Y1090728D02*
G03X898110Y1091122I-1J394D01*
G01X879724Y1066496D02*
X887057D01*
G01X887204D02*
X899213D01*
G01Y1067283D02*
X887204D01*
G01X887057D02*
X879724D01*
G01X890551Y1069154D02*
X897717D01*
G01X879724Y1069646D02*
X887057D01*
G01X887204D02*
X899213D01*
G01Y1070433D02*
X887204D01*
G01X887057D02*
X879724D01*
G01X890551Y1070728D02*
X897717D01*
G01X879724Y1072795D02*
X887057D01*
G01X887204D02*
X899213D01*
G01Y1073583D02*
X887204D01*
G01X887057D02*
X879724D01*
G01X890551Y1074154D02*
X897717D01*
G01X890551Y1075728D02*
X897717D01*
G01X879724Y1075945D02*
X887057D01*
G01X887204D02*
X899213D01*
G01Y1076732D02*
X887204D01*
G01X887057D02*
X879724D01*
G01Y1079094D02*
X887057D01*
G01X887204D02*
X899213D01*
G01X890551Y1079154D02*
X897717D01*
G01X899213Y1079882D02*
X887204D01*
G01X887057D02*
X879724D01*
G01X890551Y1080728D02*
X897717D01*
G01X879724Y1082244D02*
X887057D01*
G01X887204D02*
X899213D01*
G01Y1083031D02*
X887204D01*
G01X887057D02*
X879724D01*
G01Y1085394D02*
X887057D01*
G01X887204D02*
X899213D01*
G01Y1086181D02*
X887204D01*
G01X887057D02*
X879724D01*
G01Y1088543D02*
X887057D01*
G01X887204D02*
X899213D01*
G01X890551Y1089154D02*
X897717D01*
G01X899213Y1089331D02*
X887204D01*
G01X887057D02*
X879724D01*
G01X890551Y1090728D02*
X897717D01*
G01X879724Y1091693D02*
X887057D01*
G01X887204D02*
X899213D01*
G01Y1092480D02*
X887204D01*
G01X887057D02*
X879724D01*
G01X890551Y1094154D02*
X897717D01*
G01X879724Y1094843D02*
X887057D01*
G01X887204D02*
X899213D01*
G01Y1095630D02*
X887204D01*
G01X887057D02*
X879724D01*
G01X890551Y1095728D02*
X897717D01*
G01X879724Y1097992D02*
X887057D01*
G01X887204D02*
X899213D01*
G01Y1098780D02*
X887204D01*
G01X887057D02*
X879724D01*
G01X890551Y1099154D02*
X897717D01*
G01X890551Y1100728D02*
X897717D01*
G01X879724Y1101142D02*
X887057D01*
G01X887204D02*
X899213D01*
G01Y1101929D02*
X887204D01*
G01X887057D02*
X879724D01*
G01X890551Y1104154D02*
X897717D01*
G01X879724Y1104291D02*
X887057D01*
G01X887204D02*
X899213D01*
G01Y1105079D02*
X887204D01*
G01X887057D02*
X879724D01*
G01Y1066496D02*
Y1067283D01*
G01Y1069646D02*
Y1070433D01*
G01Y1075945D02*
Y1076732D01*
G01Y1072795D02*
Y1073583D01*
G01Y1079094D02*
Y1079882D01*
G01Y1085394D02*
Y1086181D01*
G01Y1082244D02*
Y1083031D01*
G01Y1088543D02*
Y1089331D01*
G01Y1094843D02*
Y1095630D01*
G01Y1091693D02*
Y1092480D01*
G01Y1097992D02*
Y1098780D01*
G01Y1104291D02*
Y1105079D01*
G01Y1101142D02*
Y1101929D01*
G01X881498Y1066496D02*
Y1067283D01*
G01Y1069646D02*
Y1070433D01*
G01Y1075945D02*
Y1076732D01*
G01Y1072795D02*
Y1073583D01*
G01Y1079094D02*
Y1079882D01*
G01Y1085394D02*
Y1086181D01*
G01Y1082244D02*
Y1083031D01*
G01Y1088543D02*
Y1089331D01*
G01Y1094843D02*
Y1095630D01*
G01Y1091693D02*
Y1092480D01*
G01Y1097992D02*
Y1098780D01*
G01Y1104291D02*
Y1105079D01*
G01Y1101142D02*
Y1101929D01*
G01X881686Y1105079D02*
Y1104291D01*
G01Y1101929D02*
Y1101142D01*
G01Y1098780D02*
Y1097992D01*
G01Y1095630D02*
Y1094843D01*
G01Y1092480D02*
Y1091693D01*
G01Y1089331D02*
Y1088543D01*
G01Y1086181D02*
Y1085394D01*
G01Y1083031D02*
Y1082244D01*
G01Y1079882D02*
Y1079094D01*
G01Y1076732D02*
Y1075945D01*
G01Y1073583D02*
Y1072795D01*
G01Y1070433D02*
Y1069646D01*
G01Y1067283D02*
Y1066496D01*
G01X884523Y1105079D02*
Y1104291D01*
G01Y1101929D02*
Y1101142D01*
G01Y1098780D02*
Y1097992D01*
G01Y1095630D02*
Y1094843D01*
G01Y1092480D02*
Y1091693D01*
G01Y1089331D02*
Y1088543D01*
G01Y1086181D02*
Y1085394D01*
G01Y1083031D02*
Y1082244D01*
G01Y1079882D02*
Y1079094D01*
G01Y1076732D02*
Y1075945D01*
G01Y1073583D02*
Y1072795D01*
G01Y1070433D02*
Y1069646D01*
G01Y1067283D02*
Y1066496D01*
G01X885464D02*
Y1067283D01*
G01Y1069646D02*
Y1070433D01*
G01Y1075945D02*
Y1076732D01*
G01Y1072795D02*
Y1073583D01*
G01Y1079094D02*
Y1079882D01*
G01Y1085394D02*
Y1086181D01*
G01Y1082244D02*
Y1083031D01*
G01Y1088543D02*
Y1089331D01*
G01Y1094843D02*
Y1095630D01*
G01Y1091693D02*
Y1092480D01*
G01Y1097992D02*
Y1098780D01*
G01Y1104291D02*
Y1105079D01*
G01Y1101142D02*
Y1101929D01*
G01X887057Y1066496D02*
Y1067283D01*
G01Y1069646D02*
Y1070433D01*
G01Y1075945D02*
Y1076732D01*
G01Y1072795D02*
Y1073583D01*
G01Y1079094D02*
Y1079882D01*
G01Y1085394D02*
Y1086181D01*
G01Y1082244D02*
Y1083031D01*
G01Y1088543D02*
Y1089331D01*
G01Y1094843D02*
Y1095630D01*
G01Y1091693D02*
Y1092480D01*
G01Y1097992D02*
Y1098780D01*
G01Y1104291D02*
Y1105079D01*
G01Y1101142D02*
Y1101929D01*
G01X887204Y1066496D02*
Y1067283D01*
G01Y1069646D02*
Y1070433D01*
G01Y1075945D02*
Y1076732D01*
G01Y1072795D02*
Y1073583D01*
G01Y1079094D02*
Y1079882D01*
G01Y1085394D02*
Y1086181D01*
G01Y1082244D02*
Y1083031D01*
G01Y1088543D02*
Y1089331D01*
G01Y1094843D02*
Y1095630D01*
G01Y1091693D02*
Y1092480D01*
G01Y1097992D02*
Y1098780D01*
G01Y1104291D02*
Y1105079D01*
G01Y1101142D02*
Y1101929D01*
G01X888142Y1107441D02*
Y1105079D01*
G01Y1104291D02*
Y1101929D01*
G01Y1101142D02*
Y1098780D01*
G01Y1097992D02*
Y1095630D01*
G01Y1094843D02*
Y1092480D01*
G01Y1091693D02*
Y1089331D01*
G01Y1088543D02*
Y1086181D01*
G01Y1085394D02*
Y1083031D01*
G01Y1082244D02*
Y1079882D01*
G01Y1079094D02*
Y1076732D01*
G01Y1075945D02*
Y1073583D01*
G01Y1072795D02*
Y1070433D01*
G01Y1069646D02*
Y1067283D01*
G01X889870Y1066496D02*
Y1067283D01*
G01Y1069646D02*
Y1070433D01*
G01Y1075945D02*
Y1076732D01*
G01Y1072795D02*
Y1073583D01*
G01Y1079094D02*
Y1079882D01*
G01Y1085394D02*
Y1086181D01*
G01Y1082244D02*
Y1083031D01*
G01Y1088543D02*
Y1089331D01*
G01Y1094843D02*
Y1095630D01*
G01Y1091693D02*
Y1092480D01*
G01Y1097992D02*
Y1098780D01*
G01Y1104291D02*
Y1105079D01*
G01Y1101142D02*
Y1101929D01*
G01X890551Y1105728D02*
Y1104154D01*
G01Y1100728D02*
Y1099154D01*
G01Y1095728D02*
Y1094154D01*
G01Y1090728D02*
Y1089154D01*
G01Y1080728D02*
Y1079154D01*
G01Y1075728D02*
Y1074154D01*
G01Y1070728D02*
Y1069154D01*
G01X898110Y1125728D02*
X892520D01*
G01X897638Y1125925D02*
X896654D01*
G01X927953Y1126043D02*
X901260D01*
G01X897638Y1126319D02*
X896654D01*
G01X897638Y1126516D02*
X896654D01*
G01X899213Y1127146D02*
X898110D01*
G01X895669Y1128366D02*
X894685D01*
G01X895669Y1128563D02*
X894685D01*
G01X895669Y1128957D02*
X894685D01*
G01X895669Y1130925D02*
X894685D01*
G01X895669Y1131319D02*
X894685D01*
G01X895669Y1131516D02*
X894685D01*
G01X895669Y1133366D02*
X894685D01*
G01X895669Y1133563D02*
X894685D01*
G01X895669Y1133957D02*
X894685D01*
G01X895669Y1135925D02*
X894685D01*
G01X895669Y1136319D02*
X894685D01*
G01X895669Y1136516D02*
X894685D01*
G01X895669Y1138366D02*
X894685D01*
G01X895669Y1138563D02*
X894685D01*
G01X891522Y1136575D02*
Y1135787D01*
G01Y1133425D02*
Y1132638D01*
G01Y1130276D02*
Y1129488D01*
G01Y1127126D02*
Y1126339D01*
G01X893506Y1136575D02*
Y1135787D01*
G01Y1133425D02*
Y1132638D01*
G01Y1130276D02*
Y1129488D01*
G01Y1127126D02*
Y1126339D01*
G01X893701Y1135728D02*
Y1134154D01*
G01Y1130728D02*
Y1129154D01*
G01X894685Y1141516D02*
Y1138366D01*
G01Y1136516D02*
Y1133366D01*
G01Y1131516D02*
Y1128366D01*
G01X895669Y1141516D02*
Y1138366D01*
G01Y1136516D02*
Y1133366D01*
G01Y1131516D02*
Y1128366D01*
G01X896654Y1135728D02*
Y1134154D01*
G01Y1130728D02*
Y1129154D01*
G01X896868Y1126339D02*
Y1127126D01*
G01Y1132638D02*
Y1133425D01*
G01Y1129488D02*
Y1130276D01*
G01Y1135787D02*
Y1136575D01*
G01X897244Y1126339D02*
Y1127126D01*
G01Y1132638D02*
Y1133425D01*
G01Y1129488D02*
Y1130276D01*
G01Y1135787D02*
Y1136575D01*
G01X897270Y1126339D02*
Y1127126D01*
G01Y1132638D02*
Y1133425D01*
G01Y1129488D02*
Y1130276D01*
G01Y1135787D02*
Y1136575D01*
G01X903228Y1126043D02*
Y1143563D01*
G01X898110Y1133760D02*
G03X897717Y1134154I-394J0D01*
G01Y1135728D02*
G03X898110Y1136122I-1J394D01*
G01Y1128760D02*
G03X897717Y1129154I-394J0D01*
G01Y1130728D02*
G03X898110Y1131122I-1J394D01*
G01Y1138760D02*
G03X897717Y1139154I-394J0D01*
G01X895669Y1105925D02*
X894685D01*
G01X895669Y1106319D02*
X894685D01*
G01X895669Y1106516D02*
X894685D01*
G01X927953Y1107146D02*
X901260D01*
G01X895669Y1108366D02*
X894685D01*
G01X895669Y1108563D02*
X894685D01*
G01X895669Y1108957D02*
X894685D01*
G01X895669Y1110925D02*
X894685D01*
G01X895669Y1111319D02*
X894685D01*
G01X895669Y1111516D02*
X894685D01*
G01X895669Y1113366D02*
X894685D01*
G01X895669Y1113563D02*
X894685D01*
G01X895669Y1113957D02*
X894685D01*
G01X895669Y1115925D02*
X894685D01*
G01X895669Y1116319D02*
X894685D01*
G01X895669Y1116516D02*
X894685D01*
G01X895669Y1118366D02*
X894685D01*
G01X895669Y1118563D02*
X894685D01*
G01X895669Y1118957D02*
X894685D01*
G01X895669Y1120925D02*
X894685D01*
G01X895669Y1121319D02*
X894685D01*
G01X895669Y1121516D02*
X894685D01*
G01X899213Y1122736D02*
X898110D01*
G01X897638Y1123366D02*
X896654D01*
G01X897638Y1123563D02*
X896654D01*
G01X927953Y1123681D02*
X901260D01*
G01X897638Y1123957D02*
X896654D01*
G01X898110Y1124154D02*
X892520D01*
G01X891522Y1123976D02*
Y1123189D01*
G01Y1120827D02*
Y1120039D01*
G01Y1117677D02*
Y1116890D01*
G01Y1114528D02*
Y1113740D01*
G01Y1111378D02*
Y1110591D01*
G01Y1108228D02*
Y1107441D01*
G01X892520Y1125728D02*
Y1124154D01*
G01X893506Y1123976D02*
Y1123189D01*
G01Y1120827D02*
Y1120039D01*
G01Y1117677D02*
Y1116890D01*
G01Y1114528D02*
Y1113740D01*
G01Y1111378D02*
Y1110591D01*
G01Y1108228D02*
Y1107441D01*
G01X893701Y1120728D02*
Y1119154D01*
G01Y1115728D02*
Y1114154D01*
G01Y1110728D02*
Y1109154D01*
G01X894685Y1121516D02*
Y1118366D01*
G01Y1116516D02*
Y1113366D01*
G01Y1111516D02*
Y1108366D01*
G01X895669Y1125728D02*
Y1124154D01*
G01Y1121516D02*
Y1118366D01*
G01Y1116516D02*
Y1113366D01*
G01Y1111516D02*
Y1108366D01*
G01X896654Y1126516D02*
Y1123366D01*
G01Y1120728D02*
Y1119154D01*
G01Y1115728D02*
Y1114154D01*
G01Y1110728D02*
Y1109154D01*
G01X896868Y1107441D02*
Y1108228D01*
G01Y1113740D02*
Y1114528D01*
G01Y1110591D02*
Y1111378D01*
G01Y1116890D02*
Y1117677D01*
G01Y1123189D02*
Y1123976D01*
G01Y1120039D02*
Y1120827D01*
G01X897244Y1107441D02*
Y1108228D01*
G01Y1113740D02*
Y1114528D01*
G01Y1110591D02*
Y1111378D01*
G01Y1116890D02*
Y1117677D01*
G01Y1123189D02*
Y1123976D01*
G01Y1120039D02*
Y1120827D01*
G01X897270Y1107441D02*
Y1108228D01*
G01Y1113740D02*
Y1114528D01*
G01Y1110591D02*
Y1111378D01*
G01Y1116890D02*
Y1117677D01*
G01Y1123189D02*
Y1123976D01*
G01Y1120039D02*
Y1120827D01*
G01X897638Y1126516D02*
Y1123366D01*
G01X903228Y1107146D02*
Y1123681D01*
G01X898110Y1108760D02*
G03X897717Y1109154I-394J0D01*
G01Y1110728D02*
G03X898110Y1111122I-1J394D01*
G01Y1113760D02*
G03X897717Y1114154I-394J0D01*
G01Y1115728D02*
G03X898110Y1116122I-1J394D01*
G01Y1118760D02*
G03X897717Y1119154I-394J0D01*
G01Y1120728D02*
G03X898110Y1121122I-1J394D01*
G01X897717Y1105728D02*
G03X898110Y1106122I-1J394D01*
G01X879724Y1126339D02*
X887057D01*
G01X887204D02*
X899213D01*
G01Y1127126D02*
X887204D01*
G01X887057D02*
X879724D01*
G01X890551Y1129154D02*
X897717D01*
G01X879724Y1129488D02*
X887057D01*
G01X887204D02*
X899213D01*
G01Y1130276D02*
X887204D01*
G01X887057D02*
X879724D01*
G01X890551Y1130728D02*
X897717D01*
G01X879724Y1132638D02*
X887057D01*
G01X887204D02*
X899213D01*
G01Y1133425D02*
X887204D01*
G01X887057D02*
X879724D01*
G01X890551Y1134154D02*
X897717D01*
G01X890551Y1135728D02*
X897717D01*
G01X879724Y1135787D02*
X887057D01*
G01X887204D02*
X899213D01*
G01Y1136575D02*
X887204D01*
G01X887057D02*
X879724D01*
G01Y1126339D02*
Y1127126D01*
G01Y1132638D02*
Y1133425D01*
G01Y1129488D02*
Y1130276D01*
G01Y1135787D02*
Y1136575D01*
G01X881498Y1126339D02*
Y1127126D01*
G01Y1132638D02*
Y1133425D01*
G01Y1129488D02*
Y1130276D01*
G01Y1135787D02*
Y1136575D01*
G01X881686D02*
Y1135787D01*
G01Y1133425D02*
Y1132638D01*
G01Y1130276D02*
Y1129488D01*
G01Y1127126D02*
Y1126339D01*
G01X884523Y1136575D02*
Y1135787D01*
G01Y1133425D02*
Y1132638D01*
G01Y1130276D02*
Y1129488D01*
G01Y1127126D02*
Y1126339D01*
G01X885464D02*
Y1127126D01*
G01Y1132638D02*
Y1133425D01*
G01Y1129488D02*
Y1130276D01*
G01Y1135787D02*
Y1136575D01*
G01X887057Y1126339D02*
Y1127126D01*
G01Y1132638D02*
Y1133425D01*
G01Y1129488D02*
Y1130276D01*
G01Y1135787D02*
Y1136575D01*
G01X887204Y1126339D02*
Y1127126D01*
G01Y1132638D02*
Y1133425D01*
G01Y1129488D02*
Y1130276D01*
G01Y1135787D02*
Y1136575D01*
G01X888142Y1138937D02*
Y1136575D01*
G01Y1135787D02*
Y1133425D01*
G01Y1132638D02*
Y1130276D01*
G01Y1129488D02*
Y1127126D01*
G01X889870Y1126339D02*
Y1127126D01*
G01Y1132638D02*
Y1133425D01*
G01Y1129488D02*
Y1130276D01*
G01Y1135787D02*
Y1136575D01*
G01X890551Y1135728D02*
Y1134154D01*
G01Y1130728D02*
Y1129154D01*
G01Y1105728D02*
X897717D01*
G01X879724Y1107441D02*
X887057D01*
G01X887204D02*
X899213D01*
G01Y1108228D02*
X887204D01*
G01X887057D02*
X879724D01*
G01X890551Y1109154D02*
X897717D01*
G01X879724Y1110591D02*
X887057D01*
G01X887204D02*
X899213D01*
G01X890551Y1110728D02*
X897717D01*
G01X899213Y1111378D02*
X887204D01*
G01X887057D02*
X879724D01*
G01Y1113740D02*
X887057D01*
G01X887204D02*
X899213D01*
G01X890551Y1114154D02*
X897717D01*
G01X899213Y1114528D02*
X887204D01*
G01X887057D02*
X879724D01*
G01X890551Y1115728D02*
X897717D01*
G01X879724Y1116890D02*
X887057D01*
G01X887204D02*
X899213D01*
G01Y1117677D02*
X887204D01*
G01X887057D02*
X879724D01*
G01X890551Y1119154D02*
X897717D01*
G01X879724Y1120039D02*
X887057D01*
G01X887204D02*
X899213D01*
G01X890551Y1120728D02*
X897717D01*
G01X899213Y1120827D02*
X887204D01*
G01X887057D02*
X879724D01*
G01Y1123189D02*
X887057D01*
G01X887204D02*
X899213D01*
G01Y1123976D02*
X887204D01*
G01X887057D02*
X879724D01*
G01Y1107441D02*
Y1108228D01*
G01Y1113740D02*
Y1114528D01*
G01Y1110591D02*
Y1111378D01*
G01Y1116890D02*
Y1117677D01*
G01Y1123189D02*
Y1123976D01*
G01Y1120039D02*
Y1120827D01*
G01X881498Y1107441D02*
Y1108228D01*
G01Y1113740D02*
Y1114528D01*
G01Y1110591D02*
Y1111378D01*
G01Y1116890D02*
Y1117677D01*
G01Y1123189D02*
Y1123976D01*
G01Y1120039D02*
Y1120827D01*
G01X881686Y1123976D02*
Y1123189D01*
G01Y1120827D02*
Y1120039D01*
G01Y1117677D02*
Y1116890D01*
G01Y1114528D02*
Y1113740D01*
G01Y1111378D02*
Y1110591D01*
G01Y1108228D02*
Y1107441D01*
G01X884523Y1123976D02*
Y1123189D01*
G01Y1120827D02*
Y1120039D01*
G01Y1117677D02*
Y1116890D01*
G01Y1114528D02*
Y1113740D01*
G01Y1111378D02*
Y1110591D01*
G01Y1108228D02*
Y1107441D01*
G01X885464D02*
Y1108228D01*
G01Y1113740D02*
Y1114528D01*
G01Y1110591D02*
Y1111378D01*
G01Y1116890D02*
Y1117677D01*
G01Y1123189D02*
Y1123976D01*
G01Y1120039D02*
Y1120827D01*
G01X887057Y1107441D02*
Y1108228D01*
G01Y1113740D02*
Y1114528D01*
G01Y1110591D02*
Y1111378D01*
G01Y1116890D02*
Y1117677D01*
G01Y1123189D02*
Y1123976D01*
G01Y1120039D02*
Y1120827D01*
G01X887204Y1107441D02*
Y1108228D01*
G01Y1113740D02*
Y1114528D01*
G01Y1110591D02*
Y1111378D01*
G01Y1116890D02*
Y1117677D01*
G01Y1123189D02*
Y1123976D01*
G01Y1120039D02*
Y1120827D01*
G01X888142Y1126339D02*
Y1123976D01*
G01Y1123189D02*
Y1120827D01*
G01Y1120039D02*
Y1117677D01*
G01Y1116890D02*
Y1114528D01*
G01Y1113740D02*
Y1111378D01*
G01Y1110591D02*
Y1108228D01*
G01X889870Y1107441D02*
Y1108228D01*
G01Y1113740D02*
Y1114528D01*
G01Y1110591D02*
Y1111378D01*
G01Y1116890D02*
Y1117677D01*
G01Y1123189D02*
Y1123976D01*
G01Y1120039D02*
Y1120827D01*
G01X890551Y1120728D02*
Y1119154D01*
G01Y1115728D02*
Y1114154D01*
G01Y1110728D02*
Y1109154D01*
G01X895669Y1138957D02*
X894685D01*
G01X895669Y1140925D02*
X894685D01*
G01X895669Y1141319D02*
X894685D01*
G01X895669Y1141516D02*
X894685D01*
G01X898110Y1142972D02*
X907480D01*
G01X907795Y1143563D02*
X901260D01*
G01X927953Y1143760D02*
X909449D01*
G01X929921Y1144154D02*
X899213D01*
G01X898110Y1144744D02*
X907480D01*
G01X893113Y1146319D02*
X899213D01*
G01X893113Y1146378D02*
X899213D01*
G01X903771Y1151619D02*
X902328D01*
G01X903771Y1155626D02*
X902331D01*
G01X900900D02*
X899441D01*
G01X898010D02*
X896618D01*
G01X931890Y1155846D02*
X905512D01*
G01X893113Y1146319D02*
X892857Y1145925D01*
G01X907795Y1159783D02*
X891417D01*
G01X901772Y1162480D02*
X897441D01*
G01X902397Y1163268D02*
X896815D01*
G01Y1164843D02*
X902397D01*
G01X897441Y1165630D02*
X901772D01*
G01X907795Y1169961D02*
X891417D01*
G01D02*
Y1157028D01*
G01X891522Y1139724D02*
Y1138937D01*
G01X892474Y1145925D02*
Y1148681D01*
G01X893113Y1146378D02*
Y1146319D01*
G01X893506Y1139724D02*
Y1138937D01*
G01X893701Y1140728D02*
Y1139154D01*
G01X895669Y1148681D02*
Y1146378D01*
G01X896618Y1155626D02*
Y1152696D01*
G01X896654Y1140728D02*
Y1139154D01*
G01X896815Y1164843D02*
Y1163268D01*
G01X896850D02*
Y1164843D01*
G01X896868Y1138937D02*
Y1139724D01*
G01X896874Y1163268D02*
Y1164843D01*
G01X897244Y1138937D02*
Y1139724D01*
G01X897270Y1138937D02*
Y1139724D01*
G01X898010Y1155626D02*
Y1153101D01*
G01X898198Y1164843D02*
Y1163268D01*
G01X898567D02*
Y1164843D01*
G01X899441Y1153101D02*
Y1155626D01*
G01X900645Y1164843D02*
Y1163268D01*
G01X900900Y1155626D02*
Y1153101D01*
G01X901015Y1163268D02*
Y1164843D01*
G01X901575Y1155059D02*
Y1151280D01*
G01Y1149311D02*
Y1146909D01*
G01X902328Y1152176D02*
Y1151619D01*
G01X902331Y1153101D02*
Y1155626D01*
G01X902338Y1164843D02*
Y1163268D01*
G01X902362Y1164843D02*
Y1163268D01*
G01X902397D02*
Y1164843D01*
G01X903771Y1155626D02*
Y1151619D01*
G01X892658Y1156142D02*
X892555Y1155773D01*
X892458Y1155443D01*
X892378Y1155181D01*
X892326Y1155015D01*
X892308Y1154961D01*
G01X905512Y1157028D02*
Y1148681D01*
G01X907480Y1144744D02*
Y1142972D01*
G01X907795Y1143563D02*
Y1169961D01*
G01X892308Y1149528D02*
X892326Y1149472D01*
X892379Y1149306D01*
X892457Y1149048D01*
X892553Y1148720D01*
X892658Y1148346D01*
G01D02*
G03Y1156142I-2304J3898D01*
G01X892308Y1149528D02*
G03Y1154961I-1954J2716D01*
G01X892117Y1151972D02*
G03X895163I1523J2362D01*
G01Y1155417D02*
G03X892116Y1155415I-1522J-2362D01*
G01X891596Y1154850D02*
G03Y1152537I2163J-1157D01*
G01X895684Y1152538D02*
G03X895683Y1154852I-2163J1156D01*
G01X894411Y1152832D02*
G03Y1154517I-2236J843D01*
G01X895163Y1151973D02*
G03X895684Y1152538I-830J1288D01*
G01X891596Y1152537D02*
G03X892117Y1151972I1352J724D01*
G01X892116Y1155415D02*
G03X891596Y1154850I832J-1287D01*
G01X895683Y1154852D02*
G03X895162Y1155417I-1351J-723D01*
G01X892938Y1152832D02*
G03X894411I737J277D01*
G01Y1154517D02*
G03X892938I-737J-278D01*
G01X892939D02*
G03Y1152832I2236J-842D01*
G01X897441Y1165630D02*
G03Y1162480I0J-1575D01*
G01X896618Y1152696D02*
G03X896912Y1152026I913J1D01*
G01X897717Y1140728D02*
G03X898110Y1141122I-1J394D01*
G01X899547Y1152170D02*
G03X902328Y1152176I1388J1207D01*
G01X896912Y1152026D02*
G03X899547Y1152170I1248J1351D01*
G01X901772Y1162480D02*
G03Y1165630I0J1575D01*
G01X898010Y1153101D02*
G03X899441I715J0D01*
G01X900900D02*
G03X902331I716J0D01*
G01X879724Y1138937D02*
X887057D01*
G01X887204D02*
X899213D01*
G01X890551Y1139154D02*
X897717D01*
G01X899213Y1139724D02*
X887204D01*
G01X887057D02*
X879724D01*
G01X890551Y1140728D02*
X897717D01*
G01X894094Y1141398D02*
X885110D01*
G01X877953Y1143150D02*
X898110D01*
G01X878745Y1145925D02*
X899213D01*
G01X877953Y1146909D02*
X901575D01*
G01X888050Y1148346D02*
X892658D01*
G01X927953Y1148681D02*
X877953D01*
G01X901575Y1149311D02*
X877953D01*
G01X892308Y1149528D02*
X888400D01*
G01X890819Y1149872D02*
X889358D01*
G01X901575Y1151280D02*
X877953D01*
G01X884013Y1151619D02*
X882396D01*
G01X881101D02*
X879719D01*
G01X887211Y1153201D02*
X885786D01*
G01X887213Y1154026D02*
X884213D01*
G01X885847Y1154470D02*
X884343D01*
G01X888400Y1154961D02*
X892308D01*
G01X901575Y1155059D02*
X877953D01*
G01X890819Y1155626D02*
X889358D01*
G01X884187D02*
X882779D01*
G01X881243D02*
X879693D01*
G01X892658Y1156142D02*
X888050D01*
G01X877953Y1157028D02*
X931890D01*
G01X882779Y1155626D02*
X881988Y1154348D01*
G01X884187Y1155626D02*
X882744Y1153479D01*
G01X881791Y1152605D02*
X881101Y1151619D01*
G01X881014Y1153470D02*
X879719Y1151619D01*
G01X888400Y1149528D02*
X888382Y1149472D01*
X888330Y1149306D01*
X888251Y1149048D01*
X888155Y1148721D01*
X888050Y1148346D01*
G01X877953Y1157028D02*
Y1143150D01*
G01X878270Y1148681D02*
Y1143150D01*
G01X878745Y1145925D02*
Y1143150D01*
G01X879724Y1138937D02*
Y1139724D01*
G01X881498Y1138937D02*
Y1139724D01*
G01X881686D02*
Y1138937D01*
G01X884523Y1139724D02*
Y1138937D01*
G01X884600Y1145925D02*
Y1148681D01*
G01X885464Y1138937D02*
Y1139724D01*
G01X887057Y1138937D02*
Y1139724D01*
G01X887204Y1138937D02*
Y1139724D01*
G01X888142Y1141398D02*
Y1139724D01*
G01X889358Y1155626D02*
Y1149872D01*
G01X889870Y1138937D02*
Y1139724D01*
G01X890551Y1140728D02*
Y1139154D01*
G01X890819Y1155626D02*
Y1149872D01*
G01X882744Y1153479D02*
X884013Y1151619D01*
G01X881791Y1152605D02*
X882396Y1151619D01*
G01X879693Y1155626D02*
X881014Y1153470D01*
G01X881243Y1155626D02*
X881988Y1154348D01*
G01X888400Y1154961D02*
X888382Y1155017D01*
X888330Y1155182D01*
X888251Y1155441D01*
X888155Y1155768D01*
X888050Y1156142D01*
G01X886772Y1155825D02*
G03X885186Y1155539I-265J-3073D01*
G01X885786Y1153201D02*
G03X887211I713J-83D01*
G01X888594Y1152792D02*
G03X888767Y1153453I-4020J1405D01*
G01D02*
G03Y1153950I-3524J249D01*
G01X884213Y1154026D02*
G03X884552Y1152583I3015J-53D01*
G01X888767Y1153948D02*
G03X888506Y1154811I-2971J-428D01*
G01X885786Y1151610D02*
G03X887429Y1151654I756J2475D01*
G01X888507Y1154808D02*
G03X886768Y1155826I-1807J-1093D01*
G01X887429Y1151654D02*
G03X888593Y1152792I-730J1911D01*
G01X884552Y1152583D02*
G03X885786Y1151610I1735J931D01*
G01X885186Y1155539D02*
G03X884343Y1154470I704J-1422D01*
G01X887211Y1154026D02*
G03X886438Y1154835I-792J17D01*
G01D02*
G03X885847Y1154470I-9J-646D01*
G01X888050Y1156142D02*
G03Y1148346I2304J-3898D01*
G01X893858Y1152244D02*
G03I-3504J0D01*
G01X888400Y1154961D02*
G03Y1149528I1954J-2717D01*
G01X892520Y1152244D02*
G03I-2166J0D01*
G01X891522Y1428701D02*
Y1427913D01*
G01X893506Y1428701D02*
Y1427913D01*
G01X893701Y1431240D02*
Y1429665D01*
G01X894685Y1432028D02*
Y1428878D01*
G01X895669Y1432028D02*
Y1428878D01*
G01X896654Y1431240D02*
Y1429665D01*
G01X896868Y1427913D02*
Y1428701D01*
G01X897244Y1427913D02*
Y1428701D01*
G01X897270Y1427913D02*
Y1428701D01*
G01X895669Y1426437D02*
X894685D01*
G01X895669Y1426831D02*
X894685D01*
G01X895669Y1427028D02*
X894685D01*
G01X895669Y1428878D02*
X894685D01*
G01X895669Y1429075D02*
X894685D01*
G01X895669Y1429469D02*
X894685D01*
G01X897717Y1426240D02*
G03X898110Y1426634I-1J394D01*
G01Y1429272D02*
G03X897717Y1429665I-394J-1D01*
G01X879724Y1427913D02*
Y1428701D01*
G01X881498Y1427913D02*
Y1428701D01*
G01X881686D02*
Y1427913D01*
G01X884523Y1428701D02*
Y1427913D01*
G01X885464D02*
Y1428701D01*
G01X887057Y1427913D02*
Y1428701D01*
G01X887204Y1427913D02*
Y1428701D01*
G01X888142Y1431063D02*
Y1428701D01*
G01Y1427913D02*
Y1425551D01*
G01X889870Y1427913D02*
Y1428701D01*
G01X890551Y1431240D02*
Y1429665D01*
G01X899213Y1425551D02*
X887204D01*
G01X887057D02*
X879724D01*
G01X890551Y1426240D02*
X897717D01*
G01X879724Y1427913D02*
X887057D01*
G01X887204D02*
X899213D01*
G01Y1428701D02*
X887204D01*
G01X887057D02*
X879724D01*
G01X890551Y1429665D02*
X897717D01*
G01X901135Y1420853D02*
X900874Y1420768D01*
G01X901658Y1418806D02*
X901397Y1418720D01*
G01X903400Y1418550D02*
X903139Y1418465D01*
G01X892118Y1408195D02*
X892400Y1408372D01*
X892588Y1408638D01*
X892655Y1408940D01*
X892590Y1409240D01*
X892405Y1409507D01*
X892119Y1409688D01*
X891769Y1409754D01*
G01X896307Y1409513D02*
X896594Y1409692D01*
X896948Y1409754D01*
G01X903487Y1418038D02*
X903923Y1418294D01*
G01X900961Y1420256D02*
X901135Y1420341D01*
G01X902878Y1421109D02*
X902529Y1420938D01*
G01X900874Y1420768D02*
X900526Y1420512D01*
G01X892192Y1405403D02*
X892552Y1405639D01*
X892791Y1405989D01*
X892876Y1406393D01*
X892794Y1406794D01*
X892557Y1407147D01*
X892194Y1407387D01*
X891769Y1407472D01*
G01X902704Y1420426D02*
X902965Y1420597D01*
G01X900787Y1420085D02*
X900961Y1420256D01*
G01X902529Y1420938D02*
X902181Y1420597D01*
G01X901832Y1418294D02*
X902181Y1418635D01*
G01X903662Y1418806D02*
X903400Y1418550D01*
G01X897576Y1408380D02*
X896013Y1406853D01*
G01X898147Y1407855D02*
X896519Y1406309D01*
G01X902529Y1420170D02*
X902704Y1420426D01*
G01X901832Y1419061D02*
X901658Y1418806D01*
G01X897576Y1408380D02*
X897759Y1408646D01*
X897822Y1408943D01*
X897757Y1409241D01*
G01X896307Y1409514D02*
X896118Y1409246D01*
G01X898147Y1407855D02*
X898484Y1408317D01*
X898630Y1408835D01*
X898570Y1409353D01*
X898319Y1409837D01*
X897882Y1410231D01*
X897309Y1410455D01*
X896674Y1410474D01*
X896090Y1410288D01*
X895635Y1409935D01*
X895342Y1409463D01*
X895239Y1408942D01*
G01X900526Y1420512D02*
X900264Y1420170D01*
G01X896374Y1377196D02*
X896467Y1377307D01*
G01Y1377180D02*
X896374Y1377068D01*
G01X902181Y1420597D02*
X902006Y1420256D01*
G01X902181Y1418635D02*
X902355Y1418976D01*
G01X903923Y1418294D02*
X904184Y1418720D01*
G01X900700Y1419829D02*
X900787Y1420085D01*
G01X901919Y1419317D02*
X901832Y1419061D01*
G01X895239Y1408942D02*
X895325Y1409419D01*
X895573Y1409861D01*
X895961Y1410213D01*
X896468Y1410433D01*
X897045Y1410489D01*
X897609Y1410367D01*
X898085Y1410084D01*
X898424Y1409680D01*
X898604Y1409223D01*
X898619Y1408743D01*
X898462Y1408272D01*
X898147Y1407855D01*
G01X900264Y1420170D02*
X900177Y1419744D01*
G01X902006Y1420256D02*
X901919Y1419829D01*
G01X904184Y1418720D02*
X904272Y1419147D01*
G01X896118Y1409246D02*
X896050Y1408942D01*
G01X902442Y1419829D02*
X902529Y1420170D01*
G01X902355Y1418976D02*
X902442Y1419317D01*
G01X903749Y1419147D02*
X903662Y1418806D01*
G01X903139Y1417953D02*
X903487Y1418038D01*
G01X891417Y1403366D02*
Y1390433D01*
G01X891522Y1425551D02*
Y1424764D01*
G01Y1422402D02*
Y1421614D01*
G01X892474Y1411713D02*
Y1414469D01*
G01X893113Y1414075D02*
Y1414016D01*
G01X893506Y1425551D02*
Y1424764D01*
G01Y1422402D02*
Y1421614D01*
G01X893640Y1417047D02*
Y1548661D01*
G01X893701Y1426240D02*
Y1424665D01*
G01Y1421240D02*
Y1419665D01*
G01X894094Y1414469D02*
Y1551437D01*
G01X894685Y1427028D02*
Y1423878D01*
G01Y1422028D02*
Y1418878D01*
G01X894882Y1380610D02*
Y1378642D01*
G01Y1376083D02*
Y1378051D01*
G01X894943Y1405030D02*
Y1404587D01*
G01X895239Y1408942D02*
Y1408794D01*
G01X895669Y1427028D02*
Y1423878D01*
G01Y1422028D02*
Y1418878D01*
G01Y1414016D02*
Y1411713D01*
G01X896050Y1408794D02*
Y1408942D01*
G01X896374Y1377068D02*
Y1377196D01*
G01X896457Y1380906D02*
Y1380315D01*
G01Y1379134D02*
Y1377559D01*
G01Y1376378D02*
Y1375787D01*
G01X896467Y1376559D02*
Y1377180D01*
G01X896561Y1377307D02*
Y1376559D01*
G01X896654Y1426240D02*
Y1424665D01*
G01Y1421240D02*
Y1419665D01*
G01X896815Y1397126D02*
Y1395551D01*
G01X896850D02*
Y1397126D01*
G01X896868Y1421614D02*
Y1422402D01*
G01Y1424764D02*
Y1425551D01*
G01X896874Y1395551D02*
Y1397126D01*
G01X897244Y1421614D02*
Y1422402D01*
G01Y1424764D02*
Y1425551D01*
G01X897270Y1421614D02*
Y1422402D01*
G01Y1424764D02*
Y1425551D01*
G01X897441Y1375787D02*
Y1380906D01*
G01X897638D02*
Y1375787D01*
G01X897657Y1419488D02*
Y1421457D01*
G01X898031Y1378051D02*
Y1376083D01*
G01Y1378642D02*
Y1380610D01*
G01X898110Y1414469D02*
Y1551437D01*
G01X898198Y1397126D02*
Y1395551D01*
G01X898567D02*
Y1397126D01*
G01X898856Y1404587D02*
Y1405325D01*
G01X899213Y1551890D02*
Y1414016D01*
G01X900037Y1410492D02*
Y1409754D01*
G01X900177Y1419744D02*
Y1419317D01*
G01Y1422303D02*
Y1422815D01*
G01X900645Y1397126D02*
Y1395551D01*
G01X900700Y1419317D02*
Y1419829D01*
G01X901015Y1395551D02*
Y1397126D01*
G01X901135Y1420341D02*
Y1420853D01*
G01X901181Y1378051D02*
Y1376083D01*
G01Y1378642D02*
Y1380610D01*
G01X901260Y1416831D02*
Y1549075D01*
G01X901575Y1413524D02*
Y1411083D01*
G01Y1409114D02*
Y1405335D01*
G01Y1380906D02*
Y1375787D01*
G01X901772D02*
Y1380906D01*
G01X901919Y1419829D02*
Y1419317D01*
G01X902338Y1397126D02*
Y1395551D01*
G01X902362Y1397126D02*
Y1395551D01*
G01X902397D02*
Y1397126D01*
G01X902442Y1419317D02*
Y1419829D01*
G01X902756Y1375787D02*
Y1376378D01*
G01Y1380315D02*
Y1380906D01*
G01Y1377559D02*
Y1379134D01*
G01X903139Y1418465D02*
Y1417953D01*
G01X903228Y1433248D02*
Y1416831D01*
G01X903749Y1419829D02*
Y1419147D01*
G01X901484Y1418209D02*
X901832Y1418294D01*
G01X896457Y1375787D02*
X902756D01*
G01X898031Y1376083D02*
X894882D01*
G01X901181D02*
X904331D01*
G01X896561Y1376559D02*
X896467D01*
G01Y1377307D02*
X896561D01*
G01X904331Y1378051D02*
X901181D01*
G01X894882D02*
X898031D01*
G01X904331Y1378642D02*
X901181D01*
G01X894882D02*
X898031D01*
G01Y1380610D02*
X894882D01*
G01X901181D02*
X904331D01*
G01X902756Y1380906D02*
X896457D01*
G01X903875Y1409828D02*
Y1410492D01*
G01X904272Y1422815D02*
Y1422303D01*
G01Y1419147D02*
Y1419829D01*
G01X904331Y1380610D02*
Y1378642D01*
G01Y1376083D02*
Y1378051D01*
G01X905512Y1403366D02*
Y1411713D01*
G01X907480Y1417421D02*
Y1415650D01*
G01X907795Y1390433D02*
Y1416831D01*
G01X909449Y1549272D02*
Y1416634D01*
G01X907795Y1390433D02*
X891417D01*
G01X901772Y1394764D02*
X897441D01*
G01X902397Y1395551D02*
X896815D01*
G01Y1397126D02*
X902397D01*
G01X897441Y1397913D02*
X901772D01*
G01X907795Y1400610D02*
X891417D01*
G01X905512Y1404547D02*
X931890D01*
G01X894943Y1404587D02*
X898856D01*
G01X900775D02*
X901661D01*
G01X898856Y1405325D02*
X895977D01*
G01X895239Y1408794D02*
X896050D01*
G01X900037Y1409754D02*
X902989D01*
G01X903875Y1410492D02*
X900037D01*
G01X899213Y1414016D02*
X893113D01*
G01Y1414075D02*
X899213D01*
G01X898110Y1415650D02*
X907480D01*
G01X899213Y1416240D02*
X929921D01*
G01X927953Y1416634D02*
X909449D01*
G01X907795Y1416831D02*
X901260D01*
G01X898110Y1417421D02*
X907480D01*
G01X901135Y1418209D02*
X901484D01*
G01X901397Y1418720D02*
X901222D01*
G01X895669Y1418878D02*
X894685D01*
G01X895669Y1419075D02*
X894685D01*
G01X895669Y1419469D02*
X894685D01*
G01X902965Y1420597D02*
X903226D01*
G01X903313Y1421109D02*
X902878D01*
G01X895669Y1421437D02*
X894685D01*
G01X901484Y1421791D02*
X900787D01*
G01X895669Y1421831D02*
X894685D01*
G01X895669Y1422028D02*
X894685D01*
G01X904272Y1422303D02*
X900874D01*
G01X900177Y1422815D02*
X904272D01*
G01X895669Y1423878D02*
X894685D01*
G01X895669Y1424075D02*
X894685D01*
G01X895669Y1424469D02*
X894685D01*
G01X896949Y1409754D02*
X897296Y1409685D01*
G01X900787Y1418294D02*
X901135Y1418209D01*
G01X901222Y1418720D02*
X900961Y1418806D01*
G01X900264Y1418976D02*
X900438Y1418635D01*
G01X904184Y1420256D02*
X904010Y1420597D01*
G01X900787Y1419061D02*
X900700Y1419317D01*
G01X900177D02*
X900264Y1418976D01*
G01X903662Y1420170D02*
X903749Y1419829D01*
G01X904272D02*
X904184Y1420256D01*
G01X903662Y1420938D02*
X903313Y1421109D01*
G01X892118Y1409689D02*
X892400Y1409511D01*
X892588Y1409246D01*
X892655Y1408944D01*
X892590Y1408644D01*
X892405Y1408377D01*
X892119Y1408195D01*
X891769Y1408130D01*
G01X897296Y1409685D02*
X897576Y1409504D01*
G01X903226Y1420597D02*
X903487Y1420426D01*
G01X892192Y1407387D02*
X892552Y1407152D01*
X892791Y1406802D01*
X892876Y1406398D01*
X892794Y1405996D01*
X892557Y1405643D01*
X892194Y1405404D01*
X891769Y1405319D01*
G01X900787Y1421791D02*
X900177Y1422303D01*
G01X900874D02*
X901484Y1421791D01*
G01X900438Y1418635D02*
X900787Y1418294D01*
G01X904010Y1420597D02*
X903662Y1420938D01*
G01X897575Y1409504D02*
X897758Y1409239D01*
X897822Y1408941D01*
X897757Y1408644D01*
G01X900961Y1418806D02*
X900787Y1419061D01*
G01X903487Y1420426D02*
X903662Y1420170D01*
G01X892857Y1414469D02*
X893113Y1414075D01*
G01X896519Y1406309D02*
G03X895977Y1405325I1276J-1344D01*
G01X897441Y1397913D02*
G03Y1394764I0J-1574D01*
G01X896457Y1379134D02*
G03Y1380315I0J591D01*
G01Y1376378D02*
G03Y1377559I0J590D01*
G01X898110Y1424272D02*
G03X897717Y1424665I-394J-1D01*
G01X898110Y1419272D02*
G03X897717Y1419665I-394J-1D01*
G01Y1421240D02*
G03X898110Y1421634I-1J394D01*
G01X903875Y1409828D02*
G03X901661Y1404587I7143J-6105D01*
G01X902989Y1409754D02*
G03X900775Y1404587I6938J-6031D01*
G01X896013Y1406853D02*
G03X894943Y1405030I2810J-2875D01*
G01X901772Y1394764D02*
G03Y1397913I0J1575D01*
G01X902756Y1380315D02*
G03Y1379134I0J-591D01*
G01Y1377559D02*
G03Y1376378I0J-591D01*
G01X886253Y1409689D02*
X885970Y1409511D01*
X885783Y1409246D01*
X885716Y1408944D01*
X885780Y1408644D01*
X885966Y1408377D01*
X886251Y1408195D01*
X886602Y1408130D01*
G01X886951Y1408195D02*
X887233Y1408372D01*
X887420Y1408638D01*
X887487Y1408940D01*
X887423Y1409240D01*
X887237Y1409507D01*
X886952Y1409688D01*
X886602Y1409754D01*
G01X891420Y1409689D02*
X891137Y1409511D01*
X890950Y1409246D01*
X890883Y1408944D01*
X890948Y1408644D01*
X891133Y1408377D01*
X891419Y1408195D01*
X891769Y1408130D01*
G01X886179Y1407387D02*
X885819Y1407152D01*
X885580Y1406802D01*
X885494Y1406398D01*
X885577Y1405996D01*
X885813Y1405643D01*
X886177Y1405404D01*
X886602Y1405319D01*
G01X887025Y1405403D02*
X887385Y1405639D01*
X887624Y1405989D01*
X887709Y1406393D01*
X887626Y1406794D01*
X887390Y1407147D01*
X887026Y1407387D01*
X886602Y1407472D01*
G01X891346Y1407387D02*
X890986Y1407152D01*
X890747Y1406802D01*
X890662Y1406398D01*
X890744Y1405996D01*
X890981Y1405643D01*
X891344Y1405404D01*
X891769Y1405319D01*
G01X885404Y1407843D02*
X884952Y1407403D01*
X884682Y1406867D01*
X884612Y1406297D01*
X884754Y1405733D01*
X885100Y1405208D01*
X885628Y1404815D01*
X886270Y1404611D01*
X886950Y1404614D01*
X887590Y1404822D01*
X888112Y1405218D01*
X888454Y1405741D01*
X888592Y1406303D01*
X888520Y1406870D01*
X888250Y1407404D01*
G01X890571Y1407843D02*
X890120Y1407403D01*
X889850Y1406867D01*
X889779Y1406297D01*
X889921Y1405733D01*
X890268Y1405208D01*
X890795Y1404815D01*
X891437Y1404611D01*
X892117Y1404614D01*
X892757Y1404822D01*
X893280Y1405218D01*
X893621Y1405741D01*
X893759Y1406303D01*
X893687Y1406870D01*
X893417Y1407404D01*
G01X887800Y1407843D02*
X888122Y1408263D01*
X888285Y1408746D01*
X888263Y1409250D01*
X888060Y1409728D01*
X887693Y1410131D01*
X887187Y1410398D01*
X886596Y1410492D01*
X886007Y1410395D01*
X885504Y1410126D01*
X885140Y1409722D01*
X884939Y1409244D01*
X884920Y1408739D01*
X885083Y1408258D01*
X885404Y1407843D01*
G01X892967D02*
X893289Y1408263D01*
X893452Y1408746D01*
X893430Y1409250D01*
X893227Y1409728D01*
X892861Y1410131D01*
X892354Y1410398D01*
X891763Y1410492D01*
X891174Y1410395D01*
X890672Y1410126D01*
X890307Y1409722D01*
X890106Y1409244D01*
X890087Y1408739D01*
X890251Y1408258D01*
X890571Y1407843D01*
G01X877953Y1417047D02*
Y1403366D01*
G01X878270Y1417047D02*
Y1411713D01*
G01X878745Y1417047D02*
Y1414469D01*
G01X879589Y1410492D02*
Y1409754D01*
G01X879724Y1421614D02*
Y1422402D01*
G01Y1424764D02*
Y1425551D01*
G01X881498Y1421614D02*
Y1422402D01*
G01Y1424764D02*
Y1425551D01*
G01X881686D02*
Y1424764D01*
G01Y1422402D02*
Y1421614D01*
G01X883428Y1409828D02*
Y1410492D01*
G01X884523Y1425551D02*
Y1424764D01*
G01Y1422402D02*
Y1421614D01*
G01X884600Y1411713D02*
Y1414469D01*
G01X885110Y1551437D02*
Y1414469D01*
G01X885464Y1421614D02*
Y1422402D01*
G01Y1424764D02*
Y1425551D01*
G01X887057Y1421614D02*
Y1422402D01*
G01Y1424764D02*
Y1425551D01*
G01X887204Y1421614D02*
Y1422402D01*
G01Y1424764D02*
Y1425551D01*
G01X888142Y1424764D02*
Y1422402D01*
G01Y1421614D02*
Y1419035D01*
G01X889587Y1421457D02*
Y1419488D01*
G01X889870Y1421614D02*
Y1422402D01*
G01Y1424764D02*
Y1425551D01*
G01X890551Y1426240D02*
Y1424665D01*
G01Y1421240D02*
Y1419665D01*
G01X931890Y1403366D02*
X877953D01*
G01X880327Y1404587D02*
X881213D01*
G01X901575Y1405335D02*
X877953D01*
G01X901575Y1409114D02*
X877953D01*
G01X879589Y1409754D02*
X882542D01*
G01X883428Y1410492D02*
X879589D01*
G01X877953Y1411083D02*
X901575D01*
G01X927953Y1411713D02*
X877953D01*
G01X901575Y1413524D02*
X877953D01*
G01X878745Y1414469D02*
X899213D01*
G01X898110Y1417047D02*
X877953D01*
G01X894094Y1419035D02*
X885110D01*
G01X889587Y1419488D02*
X897657D01*
G01X890551Y1419665D02*
X897717D01*
G01X890551Y1421240D02*
X897717D01*
G01X897657Y1421457D02*
X889587D01*
G01X879724Y1421614D02*
X887057D01*
G01X887204D02*
X899213D01*
G01Y1422402D02*
X887204D01*
G01X887057D02*
X879724D01*
G01X890551Y1424665D02*
X897717D01*
G01X879724Y1424764D02*
X887057D01*
G01X887204D02*
X899213D01*
G01X886253Y1408195D02*
X885970Y1408372D01*
X885783Y1408638D01*
X885716Y1408940D01*
X885780Y1409240D01*
X885966Y1409507D01*
X886251Y1409688D01*
X886602Y1409754D01*
G01X886951Y1409689D02*
X887233Y1409511D01*
X887420Y1409246D01*
X887487Y1408944D01*
X887423Y1408644D01*
X887237Y1408377D01*
X886952Y1408195D01*
X886602Y1408130D01*
G01X891420Y1408195D02*
X891137Y1408372D01*
X890950Y1408638D01*
X890883Y1408940D01*
X890948Y1409240D01*
X891133Y1409507D01*
X891419Y1409688D01*
X891769Y1409754D01*
G01X886179Y1405403D02*
X885819Y1405639D01*
X885580Y1405989D01*
X885494Y1406393D01*
X885577Y1406794D01*
X885813Y1407147D01*
X886177Y1407387D01*
X886602Y1407472D01*
G01X887025Y1407387D02*
X887385Y1407152D01*
X887624Y1406802D01*
X887709Y1406398D01*
X887626Y1405996D01*
X887390Y1405643D01*
X887026Y1405404D01*
X886602Y1405319D01*
G01X891346Y1405403D02*
X890986Y1405639D01*
X890747Y1405989D01*
X890662Y1406393D01*
X890744Y1406794D01*
X890981Y1407147D01*
X891344Y1407387D01*
X891769Y1407472D01*
G01X887800Y1407843D02*
X888251Y1407403D01*
X888521Y1406867D01*
X888592Y1406297D01*
X888450Y1405733D01*
X888103Y1405208D01*
X887576Y1404815D01*
X886933Y1404611D01*
X886254Y1404614D01*
X885614Y1404822D01*
X885091Y1405218D01*
X884750Y1405741D01*
X884611Y1406303D01*
X884683Y1406870D01*
X884954Y1407404D01*
G01X892967Y1407843D02*
X893419Y1407403D01*
X893689Y1406867D01*
X893759Y1406297D01*
X893617Y1405733D01*
X893270Y1405208D01*
X892743Y1404815D01*
X892100Y1404611D01*
X891421Y1404614D01*
X890781Y1404822D01*
X890258Y1405218D01*
X889917Y1405741D01*
X889779Y1406303D01*
X889850Y1406870D01*
X890121Y1407404D01*
G01X885404Y1407843D02*
X885081Y1408263D01*
X884919Y1408746D01*
X884941Y1409250D01*
X885143Y1409728D01*
X885510Y1410131D01*
X886017Y1410398D01*
X886607Y1410492D01*
X887197Y1410395D01*
X887699Y1410126D01*
X888063Y1409722D01*
X888265Y1409244D01*
X888284Y1408739D01*
X888120Y1408258D01*
X887800Y1407843D01*
G01X890571D02*
X890249Y1408263D01*
X890086Y1408746D01*
X890108Y1409250D01*
X890311Y1409728D01*
X890678Y1410131D01*
X891184Y1410398D01*
X891775Y1410492D01*
X892364Y1410395D01*
X892867Y1410126D01*
X893231Y1409722D01*
X893432Y1409244D01*
X893451Y1408739D01*
X893287Y1408258D01*
X892967Y1407843D01*
G01X883428Y1409828D02*
G03X881213Y1404587I7141J-6107D01*
G01X882542Y1409754D02*
G03X880327Y1404587I6937J-6032D01*
G01X894882Y1408149D02*
G03I-4528J0D01*
G01X893858D02*
G03I-3504J0D01*
G01X893701D02*
G03I-3347J0D01*
G01X892520D02*
G03I-2166J0D01*
G01X891522Y1463346D02*
Y1462559D01*
G01Y1460197D02*
Y1459409D01*
G01Y1457047D02*
Y1456260D01*
G01Y1453898D02*
Y1453110D01*
G01Y1450748D02*
Y1449961D01*
G01Y1447598D02*
Y1446811D01*
G01Y1444449D02*
Y1443661D01*
G01Y1441299D02*
Y1440512D01*
G01Y1438150D02*
Y1437362D01*
G01Y1435000D02*
Y1434213D01*
G01Y1431850D02*
Y1431063D01*
G01X891678Y1453307D02*
Y1457126D01*
G01Y1459331D02*
Y1466575D01*
G01X892085Y1465118D02*
Y1463937D01*
G01Y1461969D02*
Y1460787D01*
G01Y1458819D02*
Y1457638D01*
G01Y1455669D02*
Y1454488D01*
G01X892104Y1459331D02*
Y1457126D01*
G01X892156Y1453307D02*
Y1472598D01*
G01X893506Y1463346D02*
Y1462559D01*
G01Y1460197D02*
Y1459409D01*
G01Y1457047D02*
Y1456260D01*
G01Y1453898D02*
Y1453110D01*
G01Y1450748D02*
Y1449961D01*
G01Y1447598D02*
Y1446811D01*
G01Y1444449D02*
Y1443661D01*
G01Y1441299D02*
Y1440512D01*
G01Y1438150D02*
Y1437362D01*
G01Y1435000D02*
Y1434213D01*
G01Y1431850D02*
Y1431063D01*
G01X893701Y1451240D02*
Y1449665D01*
G01Y1446240D02*
Y1444665D01*
G01Y1441240D02*
Y1439665D01*
G01Y1436240D02*
Y1434665D01*
G01X894685Y1452028D02*
Y1448878D01*
G01Y1447028D02*
Y1443878D01*
G01Y1442028D02*
Y1438878D01*
G01Y1437028D02*
Y1433878D01*
G01X895235Y1465118D02*
Y1463937D01*
G01Y1461969D02*
Y1460787D01*
G01Y1458819D02*
Y1457638D01*
G01Y1455669D02*
Y1454488D01*
G01X895512Y1453307D02*
Y1472598D01*
G01X895669Y1452028D02*
Y1448878D01*
G01Y1447028D02*
Y1443878D01*
G01Y1442028D02*
Y1438878D01*
G01Y1437028D02*
Y1433878D01*
G01X896219Y1453799D02*
Y1472106D01*
G01X896429Y1472598D02*
Y1453307D01*
G01X896654Y1451240D02*
Y1449665D01*
G01Y1446240D02*
Y1444665D01*
G01Y1441240D02*
Y1439665D01*
G01Y1436240D02*
Y1434665D01*
G01X896868Y1431063D02*
Y1431850D01*
G01Y1434213D02*
Y1435000D01*
G01Y1440512D02*
Y1441299D01*
G01Y1437362D02*
Y1438150D01*
G01Y1443661D02*
Y1444449D01*
G01Y1449961D02*
Y1450748D01*
G01Y1446811D02*
Y1447598D01*
G01Y1453110D02*
Y1453898D01*
G01Y1459409D02*
Y1460197D01*
G01Y1456260D02*
Y1457047D01*
G01Y1462559D02*
Y1463346D01*
G01X896929Y1472598D02*
Y1453307D01*
G01X897203Y1465709D02*
Y1463346D01*
G01Y1462559D02*
Y1460197D01*
G01Y1459409D02*
Y1457047D01*
G01Y1456260D02*
Y1453898D01*
G01X897244Y1431063D02*
Y1431850D01*
G01Y1434213D02*
Y1435000D01*
G01Y1440512D02*
Y1441299D01*
G01Y1437362D02*
Y1438150D01*
G01Y1443661D02*
Y1444449D01*
G01Y1449961D02*
Y1450748D01*
G01Y1446811D02*
Y1447598D01*
G01Y1453110D02*
Y1453898D01*
G01Y1459409D02*
Y1460197D01*
G01Y1456260D02*
Y1457047D01*
G01Y1462559D02*
Y1463346D01*
G01X897270Y1431063D02*
Y1431850D01*
G01Y1434213D02*
Y1435000D01*
G01Y1440512D02*
Y1441299D01*
G01Y1437362D02*
Y1438150D01*
G01Y1443661D02*
Y1444449D01*
G01Y1449961D02*
Y1450748D01*
G01Y1446811D02*
Y1447598D01*
G01Y1453110D02*
Y1453898D01*
G01Y1459409D02*
Y1460197D01*
G01Y1456260D02*
Y1457047D01*
G01Y1462559D02*
Y1463346D01*
G01X897717Y1453307D02*
Y1472598D01*
G01X898031D02*
Y1453307D01*
G01X903228Y1472697D02*
Y1453209D01*
G01Y1450846D02*
Y1435610D01*
G01X895669Y1431437D02*
X894685D01*
G01X895669Y1431831D02*
X894685D01*
G01X895669Y1432028D02*
X894685D01*
G01X927953Y1433248D02*
X901260D01*
G01X895669Y1433878D02*
X894685D01*
G01X895669Y1434075D02*
X894685D01*
G01X895669Y1434469D02*
X894685D01*
G01X927953Y1435610D02*
X901260D01*
G01X895669Y1436437D02*
X894685D01*
G01X895669Y1436831D02*
X894685D01*
G01X895669Y1437028D02*
X894685D01*
G01X895669Y1438878D02*
X894685D01*
G01X895669Y1439075D02*
X894685D01*
G01X895669Y1439469D02*
X894685D01*
G01X895669Y1441437D02*
X894685D01*
G01X895669Y1441831D02*
X894685D01*
G01X895669Y1442028D02*
X894685D01*
G01X895669Y1443878D02*
X894685D01*
G01X895669Y1444075D02*
X894685D01*
G01X895669Y1444469D02*
X894685D01*
G01X895669Y1446437D02*
X894685D01*
G01X895669Y1446831D02*
X894685D01*
G01X928910Y1446850D02*
X909449D01*
G01X895669Y1447028D02*
X894685D01*
G01X895669Y1448878D02*
X894685D01*
G01X895669Y1449075D02*
X894685D01*
G01X895669Y1449469D02*
X894685D01*
G01X927953Y1450846D02*
X901260D01*
G01X895669Y1451437D02*
X894685D01*
G01X895669Y1451831D02*
X894685D01*
G01X895669Y1452028D02*
X894685D01*
G01X927953Y1453189D02*
X909449D01*
G01X899213D02*
X898110D01*
G01X923452Y1453209D02*
X901260D01*
G01X891678Y1453307D02*
X899213D01*
G01X896219Y1453799D02*
X894094D01*
G01X897203Y1454094D02*
X896219D01*
G01X897203Y1454291D02*
X896219D01*
G01X898110Y1454488D02*
X892085D01*
G01X898110Y1455669D02*
X892085D01*
G01X897203Y1455866D02*
X896219D01*
G01X897203Y1456063D02*
X896219D01*
G01X897203Y1457244D02*
X896219D01*
G01X897203Y1457441D02*
X896219D01*
G01X898110Y1457638D02*
X892085D01*
G01X898110Y1458819D02*
X892085D01*
G01X897203Y1459016D02*
X896219D01*
G01X897203Y1459213D02*
X896219D01*
G01X897203Y1460394D02*
X896219D01*
G01X897203Y1460591D02*
X896219D01*
G01X898110Y1460787D02*
X892085D01*
G01X898110Y1461969D02*
X892085D01*
G01X897203Y1462165D02*
X896219D01*
G01X897203Y1462362D02*
X896219D01*
G01X897203Y1463543D02*
X896219D01*
G01X897203Y1463740D02*
X896219D01*
G01X898110Y1463937D02*
X892085D01*
G01X898110Y1465118D02*
X892085D01*
G01X897717Y1431240D02*
G03X898110Y1431634I-1J394D01*
G01Y1434272D02*
G03X897717Y1434665I-394J-1D01*
G01Y1436240D02*
G03X898110Y1436634I-1J394D01*
G01Y1439272D02*
G03X897717Y1439665I-394J-1D01*
G01Y1441240D02*
G03X898110Y1441634I-1J394D01*
G01Y1444272D02*
G03X897717Y1444665I-394J-1D01*
G01Y1446240D02*
G03X898110Y1446634I-1J394D01*
G01Y1449272D02*
G03X897717Y1449665I-394J-1D01*
G01Y1451240D02*
G03X898110Y1451634I-1J394D01*
G01X879724Y1431063D02*
Y1431850D01*
G01Y1434213D02*
Y1435000D01*
G01Y1440512D02*
Y1441299D01*
G01Y1437362D02*
Y1438150D01*
G01Y1443661D02*
Y1444449D01*
G01Y1449961D02*
Y1450748D01*
G01Y1446811D02*
Y1447598D01*
G01Y1453110D02*
Y1453898D01*
G01Y1459409D02*
Y1460197D01*
G01Y1456260D02*
Y1457047D01*
G01Y1462559D02*
Y1463346D01*
G01X881498Y1431063D02*
Y1431850D01*
G01Y1434213D02*
Y1435000D01*
G01Y1440512D02*
Y1441299D01*
G01Y1437362D02*
Y1438150D01*
G01Y1443661D02*
Y1444449D01*
G01Y1449961D02*
Y1450748D01*
G01Y1446811D02*
Y1447598D01*
G01Y1453110D02*
Y1453898D01*
G01Y1459409D02*
Y1460197D01*
G01Y1456260D02*
Y1457047D01*
G01Y1462559D02*
Y1463346D01*
G01X881686D02*
Y1462559D01*
G01Y1460197D02*
Y1459409D01*
G01Y1457047D02*
Y1456260D01*
G01Y1453898D02*
Y1453110D01*
G01Y1450748D02*
Y1449961D01*
G01Y1447598D02*
Y1446811D01*
G01Y1444449D02*
Y1443661D01*
G01Y1441299D02*
Y1440512D01*
G01Y1438150D02*
Y1437362D01*
G01Y1435000D02*
Y1434213D01*
G01Y1431850D02*
Y1431063D01*
G01X884523Y1463346D02*
Y1462559D01*
G01Y1460197D02*
Y1459409D01*
G01Y1457047D02*
Y1456260D01*
G01Y1453898D02*
Y1453110D01*
G01Y1450748D02*
Y1449961D01*
G01Y1447598D02*
Y1446811D01*
G01Y1444449D02*
Y1443661D01*
G01Y1441299D02*
Y1440512D01*
G01Y1438150D02*
Y1437362D01*
G01Y1435000D02*
Y1434213D01*
G01Y1431850D02*
Y1431063D01*
G01X885464D02*
Y1431850D01*
G01Y1434213D02*
Y1435000D01*
G01Y1440512D02*
Y1441299D01*
G01Y1437362D02*
Y1438150D01*
G01Y1443661D02*
Y1444449D01*
G01Y1449961D02*
Y1450748D01*
G01Y1446811D02*
Y1447598D01*
G01Y1453110D02*
Y1453898D01*
G01Y1459409D02*
Y1460197D01*
G01Y1456260D02*
Y1457047D01*
G01Y1462559D02*
Y1463346D01*
G01X887057Y1431063D02*
Y1431850D01*
G01Y1434213D02*
Y1435000D01*
G01Y1440512D02*
Y1441299D01*
G01Y1437362D02*
Y1438150D01*
G01Y1443661D02*
Y1444449D01*
G01Y1449961D02*
Y1450748D01*
G01Y1446811D02*
Y1447598D01*
G01Y1453110D02*
Y1453898D01*
G01Y1459409D02*
Y1460197D01*
G01Y1456260D02*
Y1457047D01*
G01Y1462559D02*
Y1463346D01*
G01X887204Y1431063D02*
Y1431850D01*
G01Y1434213D02*
Y1435000D01*
G01Y1440512D02*
Y1441299D01*
G01Y1437362D02*
Y1438150D01*
G01Y1443661D02*
Y1444449D01*
G01Y1449961D02*
Y1450748D01*
G01Y1446811D02*
Y1447598D01*
G01Y1453110D02*
Y1453898D01*
G01Y1459409D02*
Y1460197D01*
G01Y1456260D02*
Y1457047D01*
G01Y1462559D02*
Y1463346D01*
G01X888142Y1465709D02*
Y1463346D01*
G01Y1462559D02*
Y1460197D01*
G01Y1459409D02*
Y1457047D01*
G01Y1456260D02*
Y1453898D01*
G01Y1453110D02*
Y1450748D01*
G01Y1449961D02*
Y1447598D01*
G01Y1446811D02*
Y1444449D01*
G01Y1443661D02*
Y1441299D01*
G01Y1440512D02*
Y1438150D01*
G01Y1437362D02*
Y1435000D01*
G01Y1434213D02*
Y1431850D01*
G01X889870Y1431063D02*
Y1431850D01*
G01Y1434213D02*
Y1435000D01*
G01Y1440512D02*
Y1441299D01*
G01Y1437362D02*
Y1438150D01*
G01Y1443661D02*
Y1444449D01*
G01Y1449961D02*
Y1450748D01*
G01Y1446811D02*
Y1447598D01*
G01Y1453110D02*
Y1453898D01*
G01Y1459409D02*
Y1460197D01*
G01Y1456260D02*
Y1457047D01*
G01Y1462559D02*
Y1463346D01*
G01X890221Y1457126D02*
Y1459331D01*
G01X890551Y1451240D02*
Y1449665D01*
G01Y1446240D02*
Y1444665D01*
G01Y1441240D02*
Y1439665D01*
G01Y1436240D02*
Y1434665D01*
G01X879724Y1431063D02*
X887057D01*
G01X887204D02*
X899213D01*
G01X890551Y1431240D02*
X897717D01*
G01X899213Y1431850D02*
X887204D01*
G01X887057D02*
X879724D01*
G01Y1434213D02*
X887057D01*
G01X887204D02*
X899213D01*
G01X890551Y1434665D02*
X897717D01*
G01X899213Y1435000D02*
X887204D01*
G01X887057D02*
X879724D01*
G01X890551Y1436240D02*
X897717D01*
G01X879724Y1437362D02*
X887057D01*
G01X887204D02*
X899213D01*
G01Y1438150D02*
X887204D01*
G01X887057D02*
X879724D01*
G01X890551Y1439665D02*
X897717D01*
G01X879724Y1440512D02*
X887057D01*
G01X887204D02*
X899213D01*
G01X890551Y1441240D02*
X897717D01*
G01X899213Y1441299D02*
X887204D01*
G01X887057D02*
X879724D01*
G01Y1443661D02*
X887057D01*
G01X887204D02*
X899213D01*
G01Y1444449D02*
X887204D01*
G01X887057D02*
X879724D01*
G01X890551Y1444665D02*
X897717D01*
G01X890551Y1446240D02*
X897717D01*
G01X879724Y1446811D02*
X887057D01*
G01X887204D02*
X899213D01*
G01Y1447598D02*
X887204D01*
G01X887057D02*
X879724D01*
G01X890551Y1449665D02*
X897717D01*
G01X879724Y1449961D02*
X887057D01*
G01X887204D02*
X899213D01*
G01Y1450748D02*
X887204D01*
G01X887057D02*
X879724D01*
G01X890551Y1451240D02*
X897717D01*
G01X879724Y1453110D02*
X887057D01*
G01X887204D02*
X899213D01*
G01Y1453898D02*
X887204D01*
G01X887057D02*
X879724D01*
G01Y1456260D02*
X887057D01*
G01X887204D02*
X899213D01*
G01Y1457047D02*
X887204D01*
G01X887057D02*
X879724D01*
G01X890221Y1457126D02*
X892104D01*
G01Y1459331D02*
X890221D01*
G01X879724Y1459409D02*
X887057D01*
G01X887204D02*
X899213D01*
G01Y1460197D02*
X887204D01*
G01X887057D02*
X879724D01*
G01Y1462559D02*
X887057D01*
G01X887204D02*
X899213D01*
G01Y1463346D02*
X887204D01*
G01X887057D02*
X879724D01*
G01X891522Y1501142D02*
Y1500354D01*
G01Y1497992D02*
Y1497205D01*
G01Y1494843D02*
Y1494055D01*
G01Y1491693D02*
Y1490906D01*
G01Y1488543D02*
Y1487756D01*
G01X892520Y1491240D02*
Y1489665D01*
G01X893506Y1501142D02*
Y1500354D01*
G01Y1497992D02*
Y1497205D01*
G01Y1494843D02*
Y1494055D01*
G01Y1491693D02*
Y1490906D01*
G01Y1488543D02*
Y1487756D01*
G01X893701Y1501240D02*
Y1499665D01*
G01Y1496240D02*
Y1494665D01*
G01X894685Y1502028D02*
Y1498878D01*
G01Y1497028D02*
Y1493878D01*
G01X895669Y1502028D02*
Y1498878D01*
G01Y1497028D02*
Y1493878D01*
G01Y1491240D02*
Y1489665D01*
G01X896654Y1501240D02*
Y1499665D01*
G01Y1496240D02*
Y1494665D01*
G01Y1492028D02*
Y1488878D01*
G01X896868Y1487756D02*
Y1488543D01*
G01Y1490906D02*
Y1491693D01*
G01Y1497205D02*
Y1497992D01*
G01Y1494055D02*
Y1494843D01*
G01Y1500354D02*
Y1501142D01*
G01X897244Y1487756D02*
Y1488543D01*
G01Y1490906D02*
Y1491693D01*
G01Y1497205D02*
Y1497992D01*
G01Y1494055D02*
Y1494843D01*
G01Y1500354D02*
Y1501142D01*
G01X897270Y1487756D02*
Y1488543D01*
G01Y1490906D02*
Y1491693D01*
G01Y1497205D02*
Y1497992D01*
G01Y1494055D02*
Y1494843D01*
G01Y1500354D02*
Y1501142D01*
G01X897638Y1492028D02*
Y1488878D01*
G01X903228Y1493760D02*
Y1510295D01*
G01X895669Y1486437D02*
X894685D01*
G01X895669Y1486831D02*
X894685D01*
G01X895669Y1487028D02*
X894685D01*
G01X899213Y1488248D02*
X898110D01*
G01X897638Y1488878D02*
X896654D01*
G01X897638Y1489075D02*
X896654D01*
G01X897638Y1489469D02*
X896654D01*
G01X898110Y1489665D02*
X892520D01*
G01X898110Y1491240D02*
X892520D01*
G01X927953Y1491398D02*
X901260D01*
G01X897638Y1491437D02*
X896654D01*
G01X897638Y1491831D02*
X896654D01*
G01X897638Y1492028D02*
X896654D01*
G01X898110Y1492657D02*
X899213D01*
G01X927953Y1493760D02*
X901260D01*
G01X895669Y1493878D02*
X894685D01*
G01X895669Y1494075D02*
X894685D01*
G01X895669Y1494469D02*
X894685D01*
G01X895669Y1496437D02*
X894685D01*
G01X895669Y1496831D02*
X894685D01*
G01X895669Y1497028D02*
X894685D01*
G01X895669Y1498878D02*
X894685D01*
G01X895669Y1499075D02*
X894685D01*
G01X895669Y1499469D02*
X894685D01*
G01X895669Y1501437D02*
X894685D01*
G01X895669Y1501831D02*
X894685D01*
G01X895669Y1502028D02*
X894685D01*
G01X897717Y1486240D02*
G03X898110Y1486634I-1J394D01*
G01Y1499272D02*
G03X897717Y1499665I-394J-1D01*
G01Y1501240D02*
G03X898110Y1501634I-1J394D01*
G01Y1494272D02*
G03X897717Y1494665I-394J-1D01*
G01Y1496240D02*
G03X898110Y1496634I-1J394D01*
G01X891522Y1485394D02*
Y1484606D01*
G01Y1482244D02*
Y1481457D01*
G01Y1479094D02*
Y1478307D01*
G01Y1475945D02*
Y1475157D01*
G01Y1472795D02*
Y1472008D01*
G01Y1469646D02*
Y1468858D01*
G01Y1466496D02*
Y1465709D01*
G01X891678Y1468780D02*
Y1472598D01*
G01X892085Y1471417D02*
Y1470236D01*
G01Y1468268D02*
Y1467087D01*
G01X892104Y1468780D02*
Y1466575D01*
G01X893506Y1485394D02*
Y1484606D01*
G01Y1482244D02*
Y1481457D01*
G01Y1479094D02*
Y1478307D01*
G01Y1475945D02*
Y1475157D01*
G01Y1472795D02*
Y1472008D01*
G01Y1469646D02*
Y1468858D01*
G01Y1466496D02*
Y1465709D01*
G01X893701Y1486240D02*
Y1484665D01*
G01Y1481240D02*
Y1479665D01*
G01Y1476240D02*
Y1474665D01*
G01X894685Y1487028D02*
Y1483878D01*
G01Y1482028D02*
Y1478878D01*
G01Y1477028D02*
Y1473878D01*
G01X895235Y1471417D02*
Y1470236D01*
G01Y1468268D02*
Y1467087D01*
G01X895669Y1487028D02*
Y1483878D01*
G01Y1482028D02*
Y1478878D01*
G01Y1477028D02*
Y1473878D01*
G01X896654Y1486240D02*
Y1484665D01*
G01Y1481240D02*
Y1479665D01*
G01Y1476240D02*
Y1474665D01*
G01X896868Y1468858D02*
Y1469646D01*
G01Y1465709D02*
Y1466496D01*
G01Y1472008D02*
Y1472795D01*
G01Y1478307D02*
Y1479094D01*
G01Y1475157D02*
Y1475945D01*
G01Y1481457D02*
Y1482244D01*
G01Y1484606D02*
Y1485394D01*
G01X897203Y1472008D02*
Y1469646D01*
G01Y1468858D02*
Y1466496D01*
G01X897244Y1468858D02*
Y1469646D01*
G01Y1465709D02*
Y1466496D01*
G01Y1472008D02*
Y1472795D01*
G01Y1478307D02*
Y1479094D01*
G01Y1475157D02*
Y1475945D01*
G01Y1481457D02*
Y1482244D01*
G01Y1484606D02*
Y1485394D01*
G01X897270Y1468858D02*
Y1469646D01*
G01Y1465709D02*
Y1466496D01*
G01Y1472008D02*
Y1472795D01*
G01Y1478307D02*
Y1479094D01*
G01Y1475157D02*
Y1475945D01*
G01Y1481457D02*
Y1482244D01*
G01Y1484606D02*
Y1485394D01*
G01X903228Y1475059D02*
Y1491398D01*
G01X897203Y1465315D02*
X896219D01*
G01X897203Y1465512D02*
X896219D01*
G01X897203Y1466693D02*
X896219D01*
G01X897203Y1466890D02*
X896219D01*
G01X898110Y1467087D02*
X892085D01*
G01X898110Y1468268D02*
X892085D01*
G01X897203Y1468465D02*
X896219D01*
G01X897203Y1468661D02*
X896219D01*
G01X897203Y1469843D02*
X896219D01*
G01X897203Y1470039D02*
X896219D01*
G01X898110Y1470236D02*
X892085D01*
G01X898110Y1471417D02*
X892085D01*
G01X897203Y1471614D02*
X896219D01*
G01X897203Y1471811D02*
X896219D01*
G01Y1472106D02*
X894094D01*
G01X899213Y1472598D02*
X891678D01*
G01X923452Y1472697D02*
X901260D01*
G01X899213Y1472717D02*
X898110D01*
G01X909449D02*
X927953D01*
G01X895669Y1473878D02*
X894685D01*
G01X895669Y1474075D02*
X894685D01*
G01X895669Y1474469D02*
X894685D01*
G01X927953Y1475059D02*
X901260D01*
G01X895669Y1476437D02*
X894685D01*
G01X895669Y1476831D02*
X894685D01*
G01X895669Y1477028D02*
X894685D01*
G01X895669Y1478878D02*
X894685D01*
G01X895669Y1479075D02*
X894685D01*
G01X928910Y1479154D02*
X909449D01*
G01X895669Y1479469D02*
X894685D01*
G01X895669Y1481437D02*
X894685D01*
G01X895669Y1481831D02*
X894685D01*
G01X895669Y1482028D02*
X894685D01*
G01X895669Y1483878D02*
X894685D01*
G01X895669Y1484075D02*
X894685D01*
G01X895669Y1484469D02*
X894685D01*
G01X898110Y1474272D02*
G03X897717Y1474665I-394J-1D01*
G01Y1476240D02*
G03X898110Y1476634I-1J394D01*
G01Y1484272D02*
G03X897717Y1484665I-394J-1D01*
G01X898110Y1479272D02*
G03X897717Y1479665I-394J-1D01*
G01Y1481240D02*
G03X898110Y1481634I-1J394D01*
G01X879724Y1487756D02*
Y1488543D01*
G01Y1490906D02*
Y1491693D01*
G01Y1497205D02*
Y1497992D01*
G01Y1494055D02*
Y1494843D01*
G01Y1500354D02*
Y1501142D01*
G01X881498Y1487756D02*
Y1488543D01*
G01Y1490906D02*
Y1491693D01*
G01Y1497205D02*
Y1497992D01*
G01Y1494055D02*
Y1494843D01*
G01Y1500354D02*
Y1501142D01*
G01X881686D02*
Y1500354D01*
G01Y1497992D02*
Y1497205D01*
G01Y1494843D02*
Y1494055D01*
G01Y1491693D02*
Y1490906D01*
G01Y1488543D02*
Y1487756D01*
G01X884523Y1501142D02*
Y1500354D01*
G01Y1497992D02*
Y1497205D01*
G01Y1494843D02*
Y1494055D01*
G01Y1491693D02*
Y1490906D01*
G01Y1488543D02*
Y1487756D01*
G01X885464D02*
Y1488543D01*
G01Y1490906D02*
Y1491693D01*
G01Y1497205D02*
Y1497992D01*
G01Y1494055D02*
Y1494843D01*
G01Y1500354D02*
Y1501142D01*
G01X887057Y1487756D02*
Y1488543D01*
G01Y1490906D02*
Y1491693D01*
G01Y1497205D02*
Y1497992D01*
G01Y1494055D02*
Y1494843D01*
G01Y1500354D02*
Y1501142D01*
G01X887204Y1487756D02*
Y1488543D01*
G01Y1490906D02*
Y1491693D01*
G01Y1497205D02*
Y1497992D01*
G01Y1494055D02*
Y1494843D01*
G01Y1500354D02*
Y1501142D01*
G01X888142Y1503504D02*
Y1501142D01*
G01Y1500354D02*
Y1497992D01*
G01Y1497205D02*
Y1494843D01*
G01Y1494055D02*
Y1491693D01*
G01Y1490906D02*
Y1488543D01*
G01Y1487756D02*
Y1485394D01*
G01X889870Y1487756D02*
Y1488543D01*
G01Y1490906D02*
Y1491693D01*
G01Y1497205D02*
Y1497992D01*
G01Y1494055D02*
Y1494843D01*
G01Y1500354D02*
Y1501142D01*
G01X890551Y1501240D02*
Y1499665D01*
G01Y1496240D02*
Y1494665D01*
G01X899213Y1485394D02*
X887204D01*
G01X887057D02*
X879724D01*
G01X890551Y1486240D02*
X897717D01*
G01X879724Y1487756D02*
X887057D01*
G01X887204D02*
X899213D01*
G01Y1488543D02*
X887204D01*
G01X887057D02*
X879724D01*
G01Y1490906D02*
X887057D01*
G01X887204D02*
X899213D01*
G01Y1491693D02*
X887204D01*
G01X887057D02*
X879724D01*
G01Y1494055D02*
X887057D01*
G01X887204D02*
X899213D01*
G01X890551Y1494665D02*
X897717D01*
G01X899213Y1494843D02*
X887204D01*
G01X887057D02*
X879724D01*
G01X890551Y1496240D02*
X897717D01*
G01X879724Y1497205D02*
X887057D01*
G01X887204D02*
X899213D01*
G01Y1497992D02*
X887204D01*
G01X887057D02*
X879724D01*
G01X890551Y1499665D02*
X897717D01*
G01X879724Y1500354D02*
X887057D01*
G01X887204D02*
X899213D01*
G01Y1501142D02*
X887204D01*
G01X887057D02*
X879724D01*
G01X890551Y1501240D02*
X897717D01*
G01X879724Y1468858D02*
Y1469646D01*
G01Y1465709D02*
Y1466496D01*
G01Y1472008D02*
Y1472795D01*
G01Y1478307D02*
Y1479094D01*
G01Y1475157D02*
Y1475945D01*
G01Y1481457D02*
Y1482244D01*
G01Y1484606D02*
Y1485394D01*
G01X881498Y1468858D02*
Y1469646D01*
G01Y1465709D02*
Y1466496D01*
G01Y1472008D02*
Y1472795D01*
G01Y1478307D02*
Y1479094D01*
G01Y1475157D02*
Y1475945D01*
G01Y1481457D02*
Y1482244D01*
G01Y1484606D02*
Y1485394D01*
G01X881686D02*
Y1484606D01*
G01Y1482244D02*
Y1481457D01*
G01Y1479094D02*
Y1478307D01*
G01Y1475945D02*
Y1475157D01*
G01Y1472795D02*
Y1472008D01*
G01Y1469646D02*
Y1468858D01*
G01Y1466496D02*
Y1465709D01*
G01X884523Y1485394D02*
Y1484606D01*
G01Y1482244D02*
Y1481457D01*
G01Y1479094D02*
Y1478307D01*
G01Y1475945D02*
Y1475157D01*
G01Y1472795D02*
Y1472008D01*
G01Y1469646D02*
Y1468858D01*
G01Y1466496D02*
Y1465709D01*
G01X885464Y1468858D02*
Y1469646D01*
G01Y1465709D02*
Y1466496D01*
G01Y1472008D02*
Y1472795D01*
G01Y1478307D02*
Y1479094D01*
G01Y1475157D02*
Y1475945D01*
G01Y1481457D02*
Y1482244D01*
G01Y1484606D02*
Y1485394D01*
G01X887057Y1468858D02*
Y1469646D01*
G01Y1465709D02*
Y1466496D01*
G01Y1472008D02*
Y1472795D01*
G01Y1478307D02*
Y1479094D01*
G01Y1475157D02*
Y1475945D01*
G01Y1481457D02*
Y1482244D01*
G01Y1484606D02*
Y1485394D01*
G01X887204Y1468858D02*
Y1469646D01*
G01Y1465709D02*
Y1466496D01*
G01Y1472008D02*
Y1472795D01*
G01Y1478307D02*
Y1479094D01*
G01Y1475157D02*
Y1475945D01*
G01Y1481457D02*
Y1482244D01*
G01Y1484606D02*
Y1485394D01*
G01X888142Y1484606D02*
Y1482244D01*
G01Y1481457D02*
Y1479094D01*
G01Y1478307D02*
Y1475945D01*
G01Y1475157D02*
Y1472795D01*
G01Y1472008D02*
Y1469646D01*
G01Y1468858D02*
Y1466496D01*
G01X889870Y1468858D02*
Y1469646D01*
G01Y1465709D02*
Y1466496D01*
G01Y1472008D02*
Y1472795D01*
G01Y1478307D02*
Y1479094D01*
G01Y1475157D02*
Y1475945D01*
G01Y1481457D02*
Y1482244D01*
G01Y1484606D02*
Y1485394D01*
G01X890221Y1466575D02*
Y1468780D01*
G01X890551Y1486240D02*
Y1484665D01*
G01Y1481240D02*
Y1479665D01*
G01Y1476240D02*
Y1474665D01*
G01X879724Y1465709D02*
X887057D01*
G01X887204D02*
X899213D01*
G01Y1466496D02*
X887204D01*
G01X887057D02*
X879724D01*
G01X890221Y1466575D02*
X892104D01*
G01Y1468780D02*
X890221D01*
G01X879724Y1468858D02*
X887057D01*
G01X887204D02*
X899213D01*
G01Y1469646D02*
X887204D01*
G01X887057D02*
X879724D01*
G01Y1472008D02*
X887057D01*
G01X887204D02*
X899213D01*
G01Y1472795D02*
X887204D01*
G01X887057D02*
X879724D01*
G01X890551Y1474665D02*
X897717D01*
G01X879724Y1475157D02*
X887057D01*
G01X887204D02*
X899213D01*
G01Y1475945D02*
X887204D01*
G01X887057D02*
X879724D01*
G01X890551Y1476240D02*
X897717D01*
G01X879724Y1478307D02*
X887057D01*
G01X887204D02*
X899213D01*
G01Y1479094D02*
X887204D01*
G01X887057D02*
X879724D01*
G01X890551Y1479665D02*
X897717D01*
G01X890551Y1481240D02*
X897717D01*
G01X879724Y1481457D02*
X887057D01*
G01X887204D02*
X899213D01*
G01Y1482244D02*
X887204D01*
G01X887057D02*
X879724D01*
G01Y1484606D02*
X887057D01*
G01X887204D02*
X899213D01*
G01X890551Y1484665D02*
X897717D01*
G01X893113Y1551831D02*
X892857Y1551437D01*
G01X892658Y1561654D02*
X892555Y1561285D01*
X892458Y1560955D01*
X892378Y1560693D01*
X892326Y1560527D01*
X892308Y1560472D01*
G01X891417Y1575472D02*
Y1562539D01*
G01X892474Y1551437D02*
Y1554193D01*
G01X893113Y1551890D02*
Y1551831D01*
G01X895669Y1554193D02*
Y1551890D01*
G01X896618Y1561137D02*
Y1558208D01*
G01X896815Y1570354D02*
Y1568780D01*
G01X896850D02*
Y1570354D01*
G01X896874Y1568780D02*
Y1570354D01*
G01X898010Y1561137D02*
Y1558613D01*
G01X898198Y1570354D02*
Y1568780D01*
G01X898567D02*
Y1570354D01*
G01X899441Y1558613D02*
Y1561137D01*
G01X900645Y1570354D02*
Y1568780D01*
G01X900900Y1561137D02*
Y1558613D01*
G01X901015Y1568780D02*
Y1570354D01*
G01X901575Y1560571D02*
Y1556791D01*
G01Y1554823D02*
Y1552421D01*
G01X902328Y1557687D02*
Y1557131D01*
G01X902331Y1558613D02*
Y1561137D01*
G01X902338Y1570354D02*
Y1568780D01*
G01X902362Y1570354D02*
Y1568780D01*
G01X902397D02*
Y1570354D01*
G01X903771Y1561137D02*
Y1557131D01*
G01X905512Y1562539D02*
Y1554193D01*
G01X907480Y1550256D02*
Y1548484D01*
G01X907795Y1549075D02*
Y1575472D01*
G01X892308Y1555039D02*
X892326Y1554983D01*
X892379Y1554818D01*
X892457Y1554559D01*
X892553Y1554232D01*
X892658Y1553858D01*
G01X895669Y1546437D02*
X894685D01*
G01X895669Y1546831D02*
X894685D01*
G01X895669Y1547028D02*
X894685D01*
G01X898110Y1548484D02*
X907480D01*
G01X907795Y1549075D02*
X901260D01*
G01X927953Y1549272D02*
X909449D01*
G01X929921Y1549665D02*
X899213D01*
G01X898110Y1550256D02*
X907480D01*
G01X893113Y1551831D02*
X899213D01*
G01X893113Y1551890D02*
X899213D01*
G01X903771Y1557131D02*
X902328D01*
G01X903771Y1561137D02*
X902331D01*
G01X900900D02*
X899441D01*
G01X898010D02*
X896618D01*
G01X931890Y1561358D02*
X905512D01*
G01X907795Y1565295D02*
X891417D01*
G01X901772Y1567992D02*
X897441D01*
G01X902397Y1568780D02*
X896815D01*
G01Y1570354D02*
X902397D01*
G01X897441Y1571142D02*
X901772D01*
G01X892658Y1553858D02*
G03Y1561654I-2304J3898D01*
G01X892308Y1555039D02*
G03Y1560472I-1954J2717D01*
G01X894411Y1558344D02*
G03Y1560028I-2236J842D01*
G01X891596Y1558049D02*
G03X892117Y1557484I1351J723D01*
G01X892116Y1560927D02*
G03X891596Y1560361I832J-1287D01*
G01X892117Y1557484D02*
G03X895163I1523J2362D01*
G01Y1560929D02*
G03X892116Y1560927I-1522J-2363D01*
G01X891596Y1560361D02*
G03Y1558049I2163J-1156D01*
G01X895684Y1558050D02*
G03X895683Y1560363I-2163J1156D01*
G01X892939Y1560028D02*
G03Y1558344I2236J-842D01*
G01X897441Y1571142D02*
G03Y1567992I0J-1575D01*
G01X895163Y1557485D02*
G03X895684Y1558050I-830J1288D01*
G01X895683Y1560363D02*
G03X895162Y1560928I-1351J-723D01*
G01X896618Y1558208D02*
G03X896912Y1557537I913J0D01*
G01X892938Y1558344D02*
G03X894411I737J277D01*
G01Y1560028D02*
G03X892938I-737J-277D01*
G01X897717Y1546240D02*
G03X898110Y1546634I-1J394D01*
G01X899547Y1557682D02*
G03X902328Y1557687I1388J1207D01*
G01X896912Y1557537D02*
G03X899547Y1557682I1247J1352D01*
G01X901772Y1567992D02*
G03Y1571142I0J1575D01*
G01X898010Y1558613D02*
G03X899441I715J0D01*
G01X900900D02*
G03X902331I716J0D01*
G01X884187Y1561137D02*
X882744Y1558991D01*
G01X881791Y1558117D02*
X881101Y1557131D01*
G01X881014Y1558982D02*
X879719Y1557131D01*
G01X882779Y1561137D02*
X881988Y1559860D01*
G01X888400Y1555039D02*
X888382Y1554983D01*
X888330Y1554818D01*
X888251Y1554560D01*
X888155Y1554233D01*
X888050Y1553858D01*
G01X877953Y1562539D02*
Y1548661D01*
G01X878270Y1554193D02*
Y1548661D01*
G01X878745Y1551437D02*
Y1548661D01*
G01X884600Y1551437D02*
Y1554193D01*
G01X889358Y1561137D02*
Y1555383D01*
G01X890819Y1561137D02*
Y1555383D01*
G01X888400Y1560472D02*
X888382Y1560528D01*
X888330Y1560694D01*
X888251Y1560952D01*
X888155Y1561280D01*
X888050Y1561654D01*
G01X890551Y1546240D02*
X897717D01*
G01X894094Y1546909D02*
X885110D01*
G01X877953Y1548661D02*
X898110D01*
G01X878745Y1551437D02*
X899213D01*
G01X877953Y1552421D02*
X901575D01*
G01X888050Y1553858D02*
X892658D01*
G01X927953Y1554193D02*
X877953D01*
G01X901575Y1554823D02*
X877953D01*
G01X892308Y1555039D02*
X888400D01*
G01X890819Y1555383D02*
X889358D01*
G01X901575Y1556791D02*
X877953D01*
G01X884013Y1557131D02*
X882396D01*
G01X881101D02*
X879719D01*
G01X887211Y1558713D02*
X885786D01*
G01X887213Y1559538D02*
X884213D01*
G01X885847Y1559981D02*
X884343D01*
G01X888400Y1560472D02*
X892308D01*
G01X901575Y1560571D02*
X877953D01*
G01X890819Y1561137D02*
X889358D01*
G01X884187D02*
X882779D01*
G01X881243D02*
X879693D01*
G01X892658Y1561654D02*
X888050D01*
G01X877953Y1562539D02*
X931890D01*
G01X881791Y1558117D02*
X882396Y1557131D01*
G01X879693Y1561137D02*
X881014Y1558982D01*
G01X881243Y1561137D02*
X881988Y1559860D01*
G01X882744Y1558991D02*
X884013Y1557131D01*
G01X886772Y1561337D02*
G03X885186Y1561051I-265J-3073D01*
G01X885786Y1558713D02*
G03X887211I713J-83D01*
G01X888594Y1558304D02*
G03X888767Y1558965I-4020J1405D01*
G01D02*
G03Y1559462I-3524J249D01*
G01X884213Y1559538D02*
G03X884552Y1558095I3015J-53D01*
G01X888767Y1559460D02*
G03X888506Y1560322I-2971J-429D01*
G01X885786Y1557122D02*
G03X887429Y1557165I757J2475D01*
G01X888507Y1560320D02*
G03X886768Y1561337I-1806J-1094D01*
G01X887429Y1557165D02*
G03X888593Y1558304I-730J1911D01*
G01X884552Y1558095D02*
G03X885786Y1557122I1735J931D01*
G01X885186Y1561051D02*
G03X884343Y1559981I705J-1422D01*
G01X887211Y1559538D02*
G03X886438Y1560346I-791J17D01*
G01D02*
G03X885847Y1559981I-10J-645D01*
G01X888050Y1561654D02*
G03Y1553858I2304J-3898D01*
G01X893858Y1557756D02*
G03I-3504J0D01*
G01X888400Y1560472D02*
G03Y1555039I1954J-2717D01*
G01X892520Y1557756D02*
G03I-2166J0D01*
G01X891522Y1545236D02*
Y1544449D01*
G01Y1542087D02*
Y1541299D01*
G01Y1538937D02*
Y1538150D01*
G01Y1535787D02*
Y1535000D01*
G01Y1532638D02*
Y1531850D01*
G01Y1529488D02*
Y1528701D01*
G01Y1526339D02*
Y1525551D01*
G01Y1523189D02*
Y1522402D01*
G01Y1520039D02*
Y1519252D01*
G01Y1516890D02*
Y1516102D01*
G01Y1513740D02*
Y1512953D01*
G01Y1510591D02*
Y1509803D01*
G01Y1507441D02*
Y1506654D01*
G01Y1504291D02*
Y1503504D01*
G01X892520Y1531240D02*
Y1529665D01*
G01X893506Y1545236D02*
Y1544449D01*
G01Y1542087D02*
Y1541299D01*
G01Y1538937D02*
Y1538150D01*
G01Y1535787D02*
Y1535000D01*
G01Y1532638D02*
Y1531850D01*
G01Y1529488D02*
Y1528701D01*
G01Y1526339D02*
Y1525551D01*
G01Y1523189D02*
Y1522402D01*
G01Y1520039D02*
Y1519252D01*
G01Y1516890D02*
Y1516102D01*
G01Y1513740D02*
Y1512953D01*
G01Y1510591D02*
Y1509803D01*
G01Y1507441D02*
Y1506654D01*
G01Y1504291D02*
Y1503504D01*
G01X893701Y1546240D02*
Y1544665D01*
G01Y1541240D02*
Y1539665D01*
G01Y1536240D02*
Y1534665D01*
G01Y1526240D02*
Y1524665D01*
G01Y1521240D02*
Y1519665D01*
G01Y1516240D02*
Y1514665D01*
G01Y1511240D02*
Y1509665D01*
G01Y1506240D02*
Y1504665D01*
G01X894685Y1547028D02*
Y1543878D01*
G01Y1542028D02*
Y1538878D01*
G01Y1537028D02*
Y1533878D01*
G01Y1527028D02*
Y1523878D01*
G01Y1522028D02*
Y1518878D01*
G01Y1517028D02*
Y1513878D01*
G01Y1512028D02*
Y1508878D01*
G01Y1507028D02*
Y1503878D01*
G01X895669Y1547028D02*
Y1543878D01*
G01Y1542028D02*
Y1538878D01*
G01Y1537028D02*
Y1533878D01*
G01Y1531240D02*
Y1529665D01*
G01Y1527028D02*
Y1523878D01*
G01Y1522028D02*
Y1518878D01*
G01Y1517028D02*
Y1513878D01*
G01Y1512028D02*
Y1508878D01*
G01Y1507028D02*
Y1503878D01*
G01X896654Y1546240D02*
Y1544665D01*
G01Y1541240D02*
Y1539665D01*
G01Y1532028D02*
Y1528878D01*
G01Y1536240D02*
Y1534665D01*
G01Y1526240D02*
Y1524665D01*
G01Y1521240D02*
Y1519665D01*
G01Y1516240D02*
Y1514665D01*
G01Y1511240D02*
Y1509665D01*
G01Y1506240D02*
Y1504665D01*
G01X896868Y1506654D02*
Y1507441D01*
G01Y1503504D02*
Y1504291D01*
G01Y1509803D02*
Y1510591D01*
G01Y1516102D02*
Y1516890D01*
G01Y1512953D02*
Y1513740D01*
G01Y1519252D02*
Y1520039D01*
G01Y1525551D02*
Y1526339D01*
G01Y1522402D02*
Y1523189D01*
G01Y1528701D02*
Y1529488D01*
G01Y1535000D02*
Y1535787D01*
G01Y1531850D02*
Y1532638D01*
G01Y1538150D02*
Y1538937D01*
G01Y1544449D02*
Y1545236D01*
G01Y1541299D02*
Y1542087D01*
G01X897244Y1506654D02*
Y1507441D01*
G01Y1503504D02*
Y1504291D01*
G01Y1509803D02*
Y1510591D01*
G01Y1516102D02*
Y1516890D01*
G01Y1512953D02*
Y1513740D01*
G01Y1519252D02*
Y1520039D01*
G01Y1525551D02*
Y1526339D01*
G01Y1522402D02*
Y1523189D01*
G01Y1528701D02*
Y1529488D01*
G01Y1535000D02*
Y1535787D01*
G01Y1531850D02*
Y1532638D01*
G01Y1538150D02*
Y1538937D01*
G01Y1544449D02*
Y1545236D01*
G01Y1541299D02*
Y1542087D01*
G01X897270Y1506654D02*
Y1507441D01*
G01Y1503504D02*
Y1504291D01*
G01Y1509803D02*
Y1510591D01*
G01Y1516102D02*
Y1516890D01*
G01Y1512953D02*
Y1513740D01*
G01Y1519252D02*
Y1520039D01*
G01Y1525551D02*
Y1526339D01*
G01Y1522402D02*
Y1523189D01*
G01Y1528701D02*
Y1529488D01*
G01Y1535000D02*
Y1535787D01*
G01Y1531850D02*
Y1532638D01*
G01Y1538150D02*
Y1538937D01*
G01Y1544449D02*
Y1545236D01*
G01Y1541299D02*
Y1542087D01*
G01X897638Y1532028D02*
Y1528878D01*
G01X903228Y1512657D02*
Y1529193D01*
G01Y1531555D02*
Y1549075D01*
G01X895669Y1503878D02*
X894685D01*
G01X895669Y1504075D02*
X894685D01*
G01X895669Y1504469D02*
X894685D01*
G01X895669Y1506437D02*
X894685D01*
G01X895669Y1506831D02*
X894685D01*
G01X895669Y1507028D02*
X894685D01*
G01X895669Y1508878D02*
X894685D01*
G01X895669Y1509075D02*
X894685D01*
G01X895669Y1509469D02*
X894685D01*
G01X927953Y1510295D02*
X901260D01*
G01X895669Y1511437D02*
X894685D01*
G01X895669Y1511831D02*
X894685D01*
G01X895669Y1512028D02*
X894685D01*
G01X927953Y1512657D02*
X901260D01*
G01X895669Y1513878D02*
X894685D01*
G01X895669Y1514075D02*
X894685D01*
G01X895669Y1514469D02*
X894685D01*
G01X895669Y1516437D02*
X894685D01*
G01X895669Y1516831D02*
X894685D01*
G01X895669Y1517028D02*
X894685D01*
G01X895669Y1518878D02*
X894685D01*
G01X895669Y1519075D02*
X894685D01*
G01X895669Y1519469D02*
X894685D01*
G01X895669Y1521437D02*
X894685D01*
G01X895669Y1521831D02*
X894685D01*
G01X895669Y1522028D02*
X894685D01*
G01X895669Y1523878D02*
X894685D01*
G01X895669Y1524075D02*
X894685D01*
G01X895669Y1524469D02*
X894685D01*
G01X895669Y1526437D02*
X894685D01*
G01X895669Y1526831D02*
X894685D01*
G01X895669Y1527028D02*
X894685D01*
G01X899213Y1528248D02*
X898110D01*
G01X897638Y1528878D02*
X896654D01*
G01X897638Y1529075D02*
X896654D01*
G01X927953Y1529193D02*
X901260D01*
G01X897638Y1529469D02*
X896654D01*
G01X898110Y1529665D02*
X892520D01*
G01X898110Y1531240D02*
X892520D01*
G01X897638Y1531437D02*
X896654D01*
G01X927953Y1531555D02*
X901260D01*
G01X897638Y1531831D02*
X896654D01*
G01X897638Y1532028D02*
X896654D01*
G01X899213Y1532657D02*
X898110D01*
G01X895669Y1533878D02*
X894685D01*
G01X895669Y1534075D02*
X894685D01*
G01X895669Y1534469D02*
X894685D01*
G01X895669Y1536437D02*
X894685D01*
G01X895669Y1536831D02*
X894685D01*
G01X895669Y1537028D02*
X894685D01*
G01X895669Y1538878D02*
X894685D01*
G01X895669Y1539075D02*
X894685D01*
G01X895669Y1539469D02*
X894685D01*
G01X895669Y1541437D02*
X894685D01*
G01X895669Y1541831D02*
X894685D01*
G01X895669Y1542028D02*
X894685D01*
G01X895669Y1543878D02*
X894685D01*
G01X895669Y1544075D02*
X894685D01*
G01X895669Y1544469D02*
X894685D01*
G01X898110Y1514272D02*
G03X897717Y1514665I-394J-1D01*
G01Y1516240D02*
G03X898110Y1516634I-1J394D01*
G01Y1519272D02*
G03X897717Y1519665I-394J-1D01*
G01Y1521240D02*
G03X898110Y1521634I-1J394D01*
G01Y1524272D02*
G03X897717Y1524665I-394J-1D01*
G01Y1526240D02*
G03X898110Y1526634I-1J394D01*
G01Y1509272D02*
G03X897717Y1509665I-394J-1D01*
G01Y1511240D02*
G03X898110Y1511634I-1J394D01*
G01Y1504272D02*
G03X897717Y1504665I-394J-1D01*
G01Y1506240D02*
G03X898110Y1506634I-1J394D01*
G01Y1539272D02*
G03X897717Y1539665I-394J-1D01*
G01Y1541240D02*
G03X898110Y1541634I-1J394D01*
G01Y1534272D02*
G03X897717Y1534665I-394J-1D01*
G01Y1536240D02*
G03X898110Y1536634I-1J394D01*
G01Y1544272D02*
G03X897717Y1544665I-394J-1D01*
G01X879724Y1506654D02*
Y1507441D01*
G01Y1503504D02*
Y1504291D01*
G01Y1509803D02*
Y1510591D01*
G01Y1516102D02*
Y1516890D01*
G01Y1512953D02*
Y1513740D01*
G01Y1519252D02*
Y1520039D01*
G01Y1525551D02*
Y1526339D01*
G01Y1522402D02*
Y1523189D01*
G01Y1528701D02*
Y1529488D01*
G01Y1535000D02*
Y1535787D01*
G01Y1531850D02*
Y1532638D01*
G01Y1538150D02*
Y1538937D01*
G01Y1544449D02*
Y1545236D01*
G01Y1541299D02*
Y1542087D01*
G01X881498Y1506654D02*
Y1507441D01*
G01Y1503504D02*
Y1504291D01*
G01Y1509803D02*
Y1510591D01*
G01Y1516102D02*
Y1516890D01*
G01Y1512953D02*
Y1513740D01*
G01Y1519252D02*
Y1520039D01*
G01Y1525551D02*
Y1526339D01*
G01Y1522402D02*
Y1523189D01*
G01Y1528701D02*
Y1529488D01*
G01Y1535000D02*
Y1535787D01*
G01Y1531850D02*
Y1532638D01*
G01Y1538150D02*
Y1538937D01*
G01Y1544449D02*
Y1545236D01*
G01Y1541299D02*
Y1542087D01*
G01X881686Y1545236D02*
Y1544449D01*
G01Y1542087D02*
Y1541299D01*
G01Y1538937D02*
Y1538150D01*
G01Y1535787D02*
Y1535000D01*
G01Y1532638D02*
Y1531850D01*
G01Y1529488D02*
Y1528701D01*
G01Y1526339D02*
Y1525551D01*
G01Y1523189D02*
Y1522402D01*
G01Y1520039D02*
Y1519252D01*
G01Y1516890D02*
Y1516102D01*
G01Y1513740D02*
Y1512953D01*
G01Y1510591D02*
Y1509803D01*
G01Y1507441D02*
Y1506654D01*
G01Y1504291D02*
Y1503504D01*
G01X884523Y1545236D02*
Y1544449D01*
G01Y1542087D02*
Y1541299D01*
G01Y1538937D02*
Y1538150D01*
G01Y1535787D02*
Y1535000D01*
G01Y1532638D02*
Y1531850D01*
G01Y1529488D02*
Y1528701D01*
G01Y1526339D02*
Y1525551D01*
G01Y1523189D02*
Y1522402D01*
G01Y1520039D02*
Y1519252D01*
G01Y1516890D02*
Y1516102D01*
G01Y1513740D02*
Y1512953D01*
G01Y1510591D02*
Y1509803D01*
G01Y1507441D02*
Y1506654D01*
G01Y1504291D02*
Y1503504D01*
G01X885464Y1506654D02*
Y1507441D01*
G01Y1503504D02*
Y1504291D01*
G01Y1509803D02*
Y1510591D01*
G01Y1516102D02*
Y1516890D01*
G01Y1512953D02*
Y1513740D01*
G01Y1519252D02*
Y1520039D01*
G01Y1525551D02*
Y1526339D01*
G01Y1522402D02*
Y1523189D01*
G01Y1528701D02*
Y1529488D01*
G01Y1535000D02*
Y1535787D01*
G01Y1531850D02*
Y1532638D01*
G01Y1538150D02*
Y1538937D01*
G01Y1544449D02*
Y1545236D01*
G01Y1541299D02*
Y1542087D01*
G01X887057Y1506654D02*
Y1507441D01*
G01Y1503504D02*
Y1504291D01*
G01Y1509803D02*
Y1510591D01*
G01Y1516102D02*
Y1516890D01*
G01Y1512953D02*
Y1513740D01*
G01Y1519252D02*
Y1520039D01*
G01Y1525551D02*
Y1526339D01*
G01Y1522402D02*
Y1523189D01*
G01Y1528701D02*
Y1529488D01*
G01Y1535000D02*
Y1535787D01*
G01Y1531850D02*
Y1532638D01*
G01Y1538150D02*
Y1538937D01*
G01Y1544449D02*
Y1545236D01*
G01Y1541299D02*
Y1542087D01*
G01X887204Y1506654D02*
Y1507441D01*
G01Y1503504D02*
Y1504291D01*
G01Y1509803D02*
Y1510591D01*
G01Y1516102D02*
Y1516890D01*
G01Y1512953D02*
Y1513740D01*
G01Y1519252D02*
Y1520039D01*
G01Y1525551D02*
Y1526339D01*
G01Y1522402D02*
Y1523189D01*
G01Y1528701D02*
Y1529488D01*
G01Y1535000D02*
Y1535787D01*
G01Y1531850D02*
Y1532638D01*
G01Y1538150D02*
Y1538937D01*
G01Y1544449D02*
Y1545236D01*
G01Y1541299D02*
Y1542087D01*
G01X888142Y1546909D02*
Y1545236D01*
G01Y1544449D02*
Y1542087D01*
G01Y1541299D02*
Y1538937D01*
G01Y1538150D02*
Y1535787D01*
G01Y1535000D02*
Y1532638D01*
G01Y1531850D02*
Y1529488D01*
G01Y1528701D02*
Y1526339D01*
G01Y1525551D02*
Y1523189D01*
G01Y1522402D02*
Y1520039D01*
G01Y1519252D02*
Y1516890D01*
G01Y1516102D02*
Y1513740D01*
G01Y1512953D02*
Y1510591D01*
G01Y1509803D02*
Y1507441D01*
G01Y1506654D02*
Y1504291D01*
G01X889870Y1506654D02*
Y1507441D01*
G01Y1503504D02*
Y1504291D01*
G01Y1509803D02*
Y1510591D01*
G01Y1516102D02*
Y1516890D01*
G01Y1512953D02*
Y1513740D01*
G01Y1519252D02*
Y1520039D01*
G01Y1525551D02*
Y1526339D01*
G01Y1522402D02*
Y1523189D01*
G01Y1528701D02*
Y1529488D01*
G01Y1535000D02*
Y1535787D01*
G01Y1531850D02*
Y1532638D01*
G01Y1538150D02*
Y1538937D01*
G01Y1544449D02*
Y1545236D01*
G01Y1541299D02*
Y1542087D01*
G01X890551Y1546240D02*
Y1544665D01*
G01Y1541240D02*
Y1539665D01*
G01Y1536240D02*
Y1534665D01*
G01Y1526240D02*
Y1524665D01*
G01Y1521240D02*
Y1519665D01*
G01Y1516240D02*
Y1514665D01*
G01Y1511240D02*
Y1509665D01*
G01Y1506240D02*
Y1504665D01*
G01X879724Y1503504D02*
X887057D01*
G01X887204D02*
X899213D01*
G01Y1504291D02*
X887204D01*
G01X887057D02*
X879724D01*
G01X890551Y1504665D02*
X897717D01*
G01X890551Y1506240D02*
X897717D01*
G01X879724Y1506654D02*
X887057D01*
G01X887204D02*
X899213D01*
G01Y1507441D02*
X887204D01*
G01X887057D02*
X879724D01*
G01X890551Y1509665D02*
X897717D01*
G01X879724Y1509803D02*
X887057D01*
G01X887204D02*
X899213D01*
G01Y1510591D02*
X887204D01*
G01X887057D02*
X879724D01*
G01X890551Y1511240D02*
X897717D01*
G01X879724Y1512953D02*
X887057D01*
G01X887204D02*
X899213D01*
G01Y1513740D02*
X887204D01*
G01X887057D02*
X879724D01*
G01X890551Y1514665D02*
X897717D01*
G01X879724Y1516102D02*
X887057D01*
G01X887204D02*
X899213D01*
G01X890551Y1516240D02*
X897717D01*
G01X899213Y1516890D02*
X887204D01*
G01X887057D02*
X879724D01*
G01Y1519252D02*
X887057D01*
G01X887204D02*
X899213D01*
G01X890551Y1519665D02*
X897717D01*
G01X899213Y1520039D02*
X887204D01*
G01X887057D02*
X879724D01*
G01X890551Y1521240D02*
X897717D01*
G01X879724Y1522402D02*
X887057D01*
G01X887204D02*
X899213D01*
G01Y1523189D02*
X887204D01*
G01X887057D02*
X879724D01*
G01X890551Y1524665D02*
X897717D01*
G01X879724Y1525551D02*
X887057D01*
G01X887204D02*
X899213D01*
G01X890551Y1526240D02*
X897717D01*
G01X899213Y1526339D02*
X887204D01*
G01X887057D02*
X879724D01*
G01Y1528701D02*
X887057D01*
G01X887204D02*
X899213D01*
G01Y1529488D02*
X887204D01*
G01X887057D02*
X879724D01*
G01Y1531850D02*
X887057D01*
G01X887204D02*
X899213D01*
G01Y1532638D02*
X887204D01*
G01X887057D02*
X879724D01*
G01X890551Y1534665D02*
X897717D01*
G01X879724Y1535000D02*
X887057D01*
G01X887204D02*
X899213D01*
G01Y1535787D02*
X887204D01*
G01X887057D02*
X879724D01*
G01X890551Y1536240D02*
X897717D01*
G01X879724Y1538150D02*
X887057D01*
G01X887204D02*
X899213D01*
G01Y1538937D02*
X887204D01*
G01X887057D02*
X879724D01*
G01X890551Y1539665D02*
X897717D01*
G01X890551Y1541240D02*
X897717D01*
G01X879724Y1541299D02*
X887057D01*
G01X887204D02*
X899213D01*
G01Y1542087D02*
X887204D01*
G01X887057D02*
X879724D01*
G01Y1544449D02*
X887057D01*
G01X887204D02*
X899213D01*
G01X890551Y1544665D02*
X897717D01*
G01X899213Y1545236D02*
X887204D01*
G01X887057D02*
X879724D01*
G01X907795Y1575472D02*
X891417D01*
G01X896457Y1786417D02*
Y1785827D01*
G01X902756D02*
Y1786417D01*
G01X898031Y1786122D02*
X894882D01*
G01X901181D02*
X904331D01*
G01X902756Y1786417D02*
X896457D01*
G01X896374Y1782707D02*
X896467Y1782819D01*
G01Y1782691D02*
X896374Y1782580D01*
G01X894882Y1786122D02*
Y1784154D01*
G01Y1781594D02*
Y1783563D01*
G01X896374Y1782580D02*
Y1782707D01*
G01X896457Y1784646D02*
Y1783071D01*
G01Y1781890D02*
Y1781299D01*
G01X896467Y1782071D02*
Y1782691D01*
G01X896561Y1782819D02*
Y1782071D01*
G01X897441Y1781299D02*
Y1786417D01*
G01X897638D02*
Y1781299D01*
G01X898031Y1783563D02*
Y1781594D01*
G01Y1784154D02*
Y1786122D01*
G01X901181Y1783563D02*
Y1781594D01*
G01Y1784154D02*
Y1786122D01*
G01X901575Y1786417D02*
Y1781299D01*
G01X901772D02*
Y1786417D01*
G01X902756Y1781299D02*
Y1781890D01*
G01Y1783071D02*
Y1784646D01*
G01X904331Y1786122D02*
Y1784154D01*
G01Y1781594D02*
Y1783563D01*
G01X896457Y1781299D02*
X902756D01*
G01X898031Y1781594D02*
X894882D01*
G01X901181D02*
X904331D01*
G01X896561Y1782071D02*
X896467D01*
G01Y1782819D02*
X896561D01*
G01X904331Y1783563D02*
X901181D01*
G01X894882D02*
X898031D01*
G01X904331Y1784154D02*
X901181D01*
G01X894882D02*
X898031D01*
G01X896457Y1784646D02*
G03Y1785827I0J591D01*
G01Y1781890D02*
G03Y1783071I0J590D01*
G01X902756Y1785827D02*
G03Y1784646I0J-590D01*
G01Y1783071D02*
G03Y1781890I0J-590D01*
G01X901777Y1800271D02*
G03Y1803420I0J1575D01*
G01X896019Y1812360D02*
G03X894949Y1810536I2810J-2874D01*
G01X902995Y1815261D02*
G03X900781Y1810094I6938J-6031D01*
G01X903881Y1815335D02*
G03X901666Y1810094I7142J-6107D01*
G01X897446Y1803420D02*
G03Y1800271I0J-1574D01*
G01X896524Y1811816D02*
G03X895982Y1810832I1276J-1344D01*
G01X892525Y1813657D02*
G03I-2165J0D01*
G01X893706D02*
G03I-3346J0D01*
G01X893864D02*
G03I-3504J0D01*
G01X894887D02*
G03I-4527J0D01*
G01X882547Y1815261D02*
G03X880333Y1810094I6938J-6031D01*
G01X883433Y1815335D02*
G03X881218Y1810094I7142J-6107D01*
G01X892198Y1812895D02*
X892558Y1812659D01*
X892796Y1812308D01*
X892882Y1811905D01*
X892799Y1811503D01*
X892563Y1811150D01*
X892199Y1810910D01*
X891775Y1810826D01*
G01X891352Y1810910D02*
X890991Y1811146D01*
X890753Y1811496D01*
X890667Y1811899D01*
X890750Y1812302D01*
X890986Y1812654D01*
X891350Y1812894D01*
X891775Y1812979D01*
G01X887030Y1812895D02*
X887391Y1812659D01*
X887629Y1812308D01*
X887714Y1811905D01*
X887632Y1811503D01*
X887395Y1811150D01*
X887032Y1810910D01*
X886607Y1810826D01*
G01X886184Y1810910D02*
X885824Y1811146D01*
X885585Y1811496D01*
X885500Y1811899D01*
X885583Y1812302D01*
X885819Y1812654D01*
X886182Y1812894D01*
X886607Y1812979D01*
G01X892123Y1815196D02*
X892406Y1815018D01*
X892593Y1814753D01*
X892660Y1814451D01*
X892596Y1814151D01*
X892410Y1813884D01*
X892125Y1813702D01*
X891775Y1813637D01*
G01X891426Y1813702D02*
X891143Y1813880D01*
X890956Y1814145D01*
X890889Y1814447D01*
X890953Y1814747D01*
X891139Y1815014D01*
X891424Y1815195D01*
X891775Y1815261D01*
G01X886956Y1815196D02*
X887239Y1815018D01*
X887426Y1814753D01*
X887493Y1814451D01*
X887429Y1814151D01*
X887243Y1813884D01*
X886958Y1813702D01*
X886607Y1813637D01*
G01X886258Y1813702D02*
X885976Y1813880D01*
X885789Y1814145D01*
X885722Y1814447D01*
X885786Y1814747D01*
X885971Y1815014D01*
X886257Y1815195D01*
X886607Y1815261D01*
G01X897581Y1815011D02*
X897763Y1814746D01*
X897828Y1814447D01*
X897763Y1814151D01*
G01X890577Y1813350D02*
X890254Y1813769D01*
X890092Y1814253D01*
X890113Y1814758D01*
X890316Y1815234D01*
X890683Y1815638D01*
X891189Y1815905D01*
X891780Y1815999D01*
X892370Y1815902D01*
X892872Y1815633D01*
X893236Y1815229D01*
X893437Y1814751D01*
X893457Y1814246D01*
X893293Y1813765D01*
X892972Y1813350D01*
G01X885409D02*
X885087Y1813769D01*
X884924Y1814253D01*
X884946Y1814758D01*
X885149Y1815234D01*
X885516Y1815638D01*
X886022Y1815905D01*
X886613Y1815999D01*
X887202Y1815902D01*
X887705Y1815633D01*
X888069Y1815229D01*
X888270Y1814751D01*
X888289Y1814246D01*
X888125Y1813765D01*
X887805Y1813350D01*
G01X892972D02*
X893424Y1812910D01*
X893694Y1812374D01*
X893764Y1811804D01*
X893623Y1811240D01*
X893276Y1810715D01*
X892749Y1810322D01*
X892106Y1810118D01*
X891427Y1810121D01*
X890787Y1810329D01*
X890264Y1810725D01*
X889922Y1811249D01*
X889784Y1811810D01*
X889856Y1812377D01*
X890126Y1812911D01*
G01X887805Y1813350D02*
X888257Y1812910D01*
X888527Y1812374D01*
X888597Y1811804D01*
X888455Y1811240D01*
X888109Y1810715D01*
X887581Y1810322D01*
X886939Y1810118D01*
X886259Y1810121D01*
X885619Y1810329D01*
X885097Y1810725D01*
X884755Y1811249D01*
X884617Y1811810D01*
X884689Y1812377D01*
X884959Y1812911D01*
G01X901580Y1814621D02*
X877958D01*
G01X895244Y1814301D02*
X896056D01*
G01X901580Y1810842D02*
X877958D01*
G01X898861Y1810832D02*
X895982D01*
G01X900780Y1810094D02*
X901666D01*
G01X894949D02*
X898861D01*
G01X880333D02*
X881218D01*
G01X905517Y1810054D02*
X931895D01*
G01Y1808873D02*
X877958D01*
G01X907801Y1806117D02*
X891423D01*
G01X897446Y1803420D02*
X901777D01*
G01X896821Y1802633D02*
X902402D01*
G01Y1801058D02*
X896821D01*
G01X901777Y1800271D02*
X897446D01*
G01X907801Y1795940D02*
X891423D01*
G01X907801D02*
Y1822338D01*
G01X905517Y1808873D02*
Y1817220D01*
G01X902402Y1801058D02*
Y1802633D01*
G01X902368D02*
Y1801058D01*
G01X902343Y1802633D02*
Y1801058D01*
G01X901580Y1814621D02*
Y1810842D01*
G01X901020Y1801058D02*
Y1802633D01*
G01X900650D02*
Y1801058D01*
G01X898861Y1810094D02*
Y1810832D01*
G01X898573Y1801058D02*
Y1802633D01*
G01X898203D02*
Y1801058D01*
G01X896880D02*
Y1802633D01*
G01X896856Y1801058D02*
Y1802633D01*
G01X896821D02*
Y1801058D01*
G01X896056Y1814301D02*
Y1814449D01*
G01X895244D02*
Y1814301D01*
G01X894949Y1810536D02*
Y1810094D01*
G01X891423Y1808873D02*
Y1795940D01*
G01X877958Y1822554D02*
Y1808873D01*
G01X896123Y1814753D02*
X896056Y1814449D01*
G01X895244D02*
X895331Y1814926D01*
X895578Y1815368D01*
X895967Y1815720D01*
X896473Y1815940D01*
X897051Y1815996D01*
X897614Y1815874D01*
X898090Y1815591D01*
X898429Y1815187D01*
X898609Y1814730D01*
X898624Y1814250D01*
X898467Y1813779D01*
X898153Y1813362D01*
G01X892972Y1813350D02*
X893295Y1813769D01*
X893458Y1814253D01*
X893436Y1814758D01*
X893233Y1815234D01*
X892866Y1815638D01*
X892360Y1815905D01*
X891769Y1815999D01*
X891180Y1815902D01*
X890677Y1815633D01*
X890313Y1815229D01*
X890112Y1814751D01*
X890093Y1814246D01*
X890256Y1813765D01*
X890577Y1813350D01*
G01X887805D02*
X888128Y1813769D01*
X888290Y1814253D01*
X888269Y1814758D01*
X888066Y1815234D01*
X887699Y1815638D01*
X887193Y1815905D01*
X886601Y1815999D01*
X886012Y1815902D01*
X885510Y1815633D01*
X885146Y1815229D01*
X884944Y1814751D01*
X884925Y1814246D01*
X885089Y1813765D01*
X885409Y1813350D01*
G01X898153Y1813362D02*
X898490Y1813824D01*
X898635Y1814342D01*
X898575Y1814860D01*
X898324Y1815344D01*
X897887Y1815739D01*
X897314Y1815962D01*
X896680Y1815981D01*
X896095Y1815795D01*
X895640Y1815442D01*
X895348Y1814970D01*
X895244Y1814449D01*
G01X896313Y1815021D02*
X896123Y1814753D01*
G01X897581Y1813887D02*
X897764Y1814153D01*
X897828Y1814450D01*
X897763Y1814748D01*
G01X898153Y1813362D02*
X896524Y1811816D01*
G01X890577Y1813350D02*
X890125Y1812910D01*
X889855Y1812374D01*
X889785Y1811804D01*
X889926Y1811240D01*
X890273Y1810715D01*
X890800Y1810322D01*
X891443Y1810118D01*
X892122Y1810121D01*
X892762Y1810329D01*
X893285Y1810725D01*
X893627Y1811249D01*
X893765Y1811810D01*
X893693Y1812377D01*
X893423Y1812911D01*
G01X885409Y1813350D02*
X884958Y1812910D01*
X884688Y1812374D01*
X884617Y1811804D01*
X884759Y1811240D01*
X885106Y1810715D01*
X885633Y1810322D01*
X886276Y1810118D01*
X886955Y1810121D01*
X887595Y1810329D01*
X888118Y1810725D01*
X888459Y1811249D01*
X888597Y1811810D01*
X888526Y1812377D01*
X888255Y1812911D01*
G01X897581Y1813887D02*
X896019Y1812360D01*
G01X892123Y1813702D02*
X892406Y1813880D01*
X892593Y1814145D01*
X892660Y1814447D01*
X892596Y1814747D01*
X892410Y1815014D01*
X892125Y1815195D01*
X891775Y1815261D01*
G01X891426Y1815196D02*
X891143Y1815018D01*
X890956Y1814753D01*
X890889Y1814451D01*
X890953Y1814151D01*
X891139Y1813884D01*
X891424Y1813702D01*
X891775Y1813637D01*
G01X886956Y1813702D02*
X887239Y1813880D01*
X887426Y1814145D01*
X887493Y1814447D01*
X887429Y1814747D01*
X887243Y1815014D01*
X886958Y1815195D01*
X886607Y1815261D01*
G01X886258Y1815196D02*
X885976Y1815018D01*
X885789Y1814753D01*
X885722Y1814451D01*
X885786Y1814151D01*
X885971Y1813884D01*
X886257Y1813702D01*
X886607Y1813637D01*
G01X892198Y1810910D02*
X892558Y1811146D01*
X892796Y1811496D01*
X892882Y1811899D01*
X892799Y1812302D01*
X892563Y1812654D01*
X892199Y1812894D01*
X891775Y1812979D01*
G01X891352Y1812895D02*
X890991Y1812659D01*
X890753Y1812308D01*
X890667Y1811905D01*
X890750Y1811503D01*
X890986Y1811150D01*
X891350Y1810910D01*
X891775Y1810826D01*
G01X887030Y1810910D02*
X887391Y1811146D01*
X887629Y1811496D01*
X887714Y1811899D01*
X887632Y1812302D01*
X887395Y1812654D01*
X887032Y1812894D01*
X886607Y1812979D01*
G01X886184Y1812895D02*
X885824Y1812659D01*
X885585Y1812308D01*
X885500Y1811905D01*
X885583Y1811503D01*
X885819Y1811150D01*
X886182Y1810910D01*
X886607Y1810826D01*
G01X897722Y1826747D02*
G03X898116Y1827141I0J394D01*
G01Y1824779D02*
G03X897722Y1825172I-394J-1D01*
G01Y1856747D02*
G03X898116Y1857141I0J394D01*
G01Y1854779D02*
G03X897722Y1855172I-394J-1D01*
G01Y1851747D02*
G03X898116Y1852141I0J394D01*
G01Y1849779D02*
G03X897722Y1850172I-394J-1D01*
G01Y1846747D02*
G03X898116Y1847141I0J394D01*
G01Y1844779D02*
G03X897722Y1845172I-394J-1D01*
G01Y1836747D02*
G03X898116Y1837141I0J394D01*
G01Y1834779D02*
G03X897722Y1835172I-394J-1D01*
G01Y1841747D02*
G03X898116Y1842141I0J394D01*
G01Y1839779D02*
G03X897722Y1840172I-394J-1D01*
G01Y1831747D02*
G03X898116Y1832141I0J394D01*
G01Y1829779D02*
G03X897722Y1830172I-394J-1D01*
G01X904016Y1826104D02*
X903667Y1826445D01*
G01X900444Y1824142D02*
X900792Y1823801D01*
G01X900879Y1827810D02*
X901489Y1827298D01*
G01X900792D02*
X900183Y1827810D01*
G01X903232Y1826104D02*
X903493Y1825933D01*
G01X897301Y1815192D02*
X897581Y1815011D01*
G01X903667Y1826445D02*
X903319Y1826616D01*
G01X901228Y1824227D02*
X900967Y1824313D01*
G01X900792Y1823801D02*
X901141Y1823716D01*
G01X896954Y1815261D02*
X897302Y1815192D01*
G01X898116Y1866294D02*
X892090D01*
G01X897209Y1866097D02*
X896224D01*
G01X897209Y1865901D02*
X896224D01*
G01X887062Y1865704D02*
X879730D01*
G01X899218D02*
X887209D01*
G01Y1864916D02*
X899218D01*
G01X879730D02*
X887062D01*
G01X892109Y1864838D02*
X890226D01*
G01X897209Y1864720D02*
X896224D01*
G01X897209Y1864523D02*
X896224D01*
G01X898116Y1864326D02*
X892090D01*
G01X898116Y1863145D02*
X892090D01*
G01X897209Y1862948D02*
X896224D01*
G01X897209Y1862751D02*
X896224D01*
G01X890226Y1862633D02*
X892109D01*
G01X887062Y1862554D02*
X879730D01*
G01X899218D02*
X887209D01*
G01Y1861767D02*
X899218D01*
G01X879730D02*
X887062D01*
G01X897209Y1861570D02*
X896224D01*
G01X897209Y1861373D02*
X896224D01*
G01X898116Y1861176D02*
X892090D01*
G01X898116Y1859995D02*
X892090D01*
G01X897209Y1859798D02*
X896224D01*
G01X897209Y1859601D02*
X896224D01*
G01X887062Y1859405D02*
X879730D01*
G01X899218D02*
X887209D01*
G01X896224Y1859306D02*
X894100D01*
G01X891683Y1858814D02*
X899218D01*
G01X923458Y1858716D02*
X901265D01*
G01X899218Y1858696D02*
X898116D01*
G01X927958D02*
X909454D01*
G01X887209Y1858617D02*
X899218D01*
G01X879730D02*
X887062D01*
G01X895675Y1857534D02*
X894690D01*
G01X895675Y1857338D02*
X894690D01*
G01X895675Y1856944D02*
X894690D01*
G01X890557Y1856747D02*
X897722D01*
G01X927958Y1856353D02*
X901265D01*
G01X887062Y1856255D02*
X879730D01*
G01X899218D02*
X887209D01*
G01Y1855468D02*
X899218D01*
G01X879730D02*
X887062D01*
G01X890557Y1855172D02*
X897722D01*
G01X895675Y1854975D02*
X894690D01*
G01X895675Y1854582D02*
X894690D01*
G01X895675Y1854385D02*
X894690D01*
G01X887062Y1853105D02*
X879730D01*
G01X899218D02*
X887209D01*
G01X895675Y1852534D02*
X894690D01*
G01X928915Y1852357D02*
X909454D01*
G01X895675Y1852338D02*
X894690D01*
G01X887209Y1852318D02*
X899218D01*
G01X879730D02*
X887062D01*
G01X895675Y1851944D02*
X894690D01*
G01X890557Y1851747D02*
X897722D01*
G01X890557Y1850172D02*
X897722D01*
G01X895675Y1849975D02*
X894690D01*
G01X887062Y1849956D02*
X879730D01*
G01X899218D02*
X887209D01*
G01X895675Y1849582D02*
X894690D01*
G01X895675Y1849385D02*
X894690D01*
G01X887209Y1849168D02*
X899218D01*
G01X879730D02*
X887062D01*
G01X895675Y1847534D02*
X894690D01*
G01X895675Y1847338D02*
X894690D01*
G01X895675Y1846944D02*
X894690D01*
G01X903493Y1825933D02*
X903667Y1825678D01*
G01X900967Y1824313D02*
X900792Y1824569D01*
G01X887062Y1846806D02*
X879730D01*
G01X899218D02*
X887209D01*
G01X890557Y1846747D02*
X897722D01*
G01X887209Y1846019D02*
X899218D01*
G01X879730D02*
X887062D01*
G01X890557Y1845172D02*
X897722D01*
G01X895675Y1844975D02*
X894690D01*
G01X895675Y1844582D02*
X894690D01*
G01X895675Y1844385D02*
X894690D01*
G01X887062Y1843657D02*
X879730D01*
G01X899218D02*
X887209D01*
G01Y1842869D02*
X899218D01*
G01X879730D02*
X887062D01*
G01X895675Y1842534D02*
X894690D01*
G01X895675Y1842338D02*
X894690D01*
G01X895675Y1841944D02*
X894690D01*
G01X890557Y1841747D02*
X897722D01*
G01X927958Y1841117D02*
X901265D01*
G01X887062Y1840507D02*
X879730D01*
G01X899218D02*
X887209D01*
G01X890557Y1840172D02*
X897722D01*
G01X895675Y1839975D02*
X894690D01*
G01X887209Y1839720D02*
X899218D01*
G01X879730D02*
X887062D01*
G01X895675Y1839582D02*
X894690D01*
G01X895675Y1839385D02*
X894690D01*
G01X927958Y1838755D02*
X901265D01*
G01X895675Y1837534D02*
X894690D01*
G01X887062Y1837357D02*
X879730D01*
G01X899218D02*
X887209D01*
G01X895675Y1837338D02*
X894690D01*
G01X895675Y1836944D02*
X894690D01*
G01X890557Y1836747D02*
X897722D01*
G01X887209Y1836570D02*
X899218D01*
G01X879730D02*
X887062D01*
G01X890557Y1835172D02*
X897722D01*
G01X895675Y1834975D02*
X894690D01*
G01X895675Y1834582D02*
X894690D01*
G01X895675Y1834385D02*
X894690D01*
G01X887062Y1834208D02*
X879730D01*
G01X899218D02*
X887209D01*
G01Y1833420D02*
X899218D01*
G01X879730D02*
X887062D01*
G01X895675Y1832534D02*
X894690D01*
G01X895675Y1832338D02*
X894690D01*
G01X895675Y1831944D02*
X894690D01*
G01X890557Y1831747D02*
X897722D01*
G01X887062Y1831058D02*
X879730D01*
G01X899218D02*
X887209D01*
G01Y1830271D02*
X899218D01*
G01X879730D02*
X887062D01*
G01X890557Y1830172D02*
X897722D01*
G01X895675Y1829975D02*
X894690D01*
G01X895675Y1829582D02*
X894690D01*
G01X895675Y1829385D02*
X894690D01*
G01X900183Y1828322D02*
X904277D01*
G01X887062Y1827908D02*
X879730D01*
G01X899218D02*
X887209D01*
G01X904277Y1827810D02*
X900879D01*
G01X895675Y1827534D02*
X894690D01*
G01X895675Y1827338D02*
X894690D01*
G01X901489Y1827298D02*
X900792D01*
G01X887209Y1827121D02*
X899218D01*
G01X879730D02*
X887062D01*
G01X897663Y1826964D02*
X889592D01*
G01X895675Y1826944D02*
X894690D01*
G01X890557Y1826747D02*
X897722D01*
G01X903319Y1826616D02*
X902883D01*
G01X902970Y1826104D02*
X903232D01*
G01X890557Y1825172D02*
X897722D01*
G01X889592Y1824995D02*
X897663D01*
G01X895675Y1824975D02*
X894690D01*
G01X895675Y1824582D02*
X894690D01*
G01X894100Y1824542D02*
X885115D01*
G01X895675Y1824385D02*
X894690D01*
G01X901402Y1824227D02*
X901228D01*
G01X901141Y1823716D02*
X901489D01*
G01X898116Y1822928D02*
X907486D01*
G01X898116Y1822554D02*
X877958D01*
G01X907801Y1822338D02*
X901265D01*
G01X927958Y1822141D02*
X909454D01*
G01X899218Y1821747D02*
X929927D01*
G01X898116Y1821157D02*
X907486D01*
G01X878751Y1819975D02*
X899218D01*
G01X893118Y1819582D02*
X899218D01*
G01Y1819523D02*
X893118D01*
G01X901580Y1819031D02*
X877958D01*
G01X927958Y1817220D02*
X877958D01*
G01Y1816590D02*
X901580D01*
G01X883433Y1815999D02*
X879594D01*
G01X903881D02*
X900042D01*
G01Y1815261D02*
X902995D01*
G01X879594D02*
X882547D01*
G01X904190Y1825763D02*
X904016Y1826104D01*
G01X900270Y1824483D02*
X900444Y1824142D01*
G01X892863Y1819975D02*
X893118Y1819582D01*
G01X901489Y1823716D02*
X901838Y1823801D01*
G01X903144Y1823460D02*
X903493Y1823545D01*
G01X900792Y1824569D02*
X900705Y1824825D01*
G01X904277Y1825336D02*
X904190Y1825763D01*
G01X903667Y1825678D02*
X903754Y1825336D01*
G01X900183Y1824825D02*
X900270Y1824483D01*
G01X909454Y1954779D02*
Y1822141D01*
G01X907486Y1822928D02*
Y1821157D01*
G01X904277Y1824654D02*
Y1825336D01*
G01Y1828322D02*
Y1827810D01*
G01X903881Y1815335D02*
Y1815999D01*
G01X903754Y1825336D02*
Y1824654D01*
G01X903234Y1838755D02*
Y1822338D01*
G01Y1856353D02*
Y1841117D01*
G01Y1878204D02*
Y1858716D01*
G01X903144Y1823971D02*
Y1823460D01*
G01X902448Y1824825D02*
Y1825336D01*
G01X901925D02*
Y1824825D01*
G01X901580Y1819031D02*
Y1816590D01*
G01X901265Y1822338D02*
Y1954582D01*
G01X901141Y1825848D02*
Y1826360D01*
G01X900705Y1824825D02*
Y1825336D01*
G01X900183Y1827810D02*
Y1828322D01*
G01Y1825251D02*
Y1824825D01*
G01X900042Y1815999D02*
Y1815261D01*
G01X899218Y1957397D02*
Y1819523D01*
G01X898116Y1819975D02*
Y1956944D01*
G01X898037Y1878105D02*
Y1858814D01*
G01X897722D02*
Y1878105D01*
G01X897663Y1824995D02*
Y1826964D01*
G01X897276Y1864916D02*
Y1865704D01*
G01Y1861767D02*
Y1862554D01*
G01Y1855468D02*
Y1856255D01*
G01Y1858617D02*
Y1859405D01*
G01Y1852318D02*
Y1853105D01*
G01Y1846019D02*
Y1846806D01*
G01Y1849168D02*
Y1849956D01*
G01Y1842869D02*
Y1843657D01*
G01Y1836570D02*
Y1837357D01*
G01Y1839720D02*
Y1840507D01*
G01Y1833420D02*
Y1834208D01*
G01Y1827121D02*
Y1827908D01*
G01Y1830271D02*
Y1831058D01*
G01X897249Y1864916D02*
Y1865704D01*
G01Y1861767D02*
Y1862554D01*
G01Y1855468D02*
Y1856255D01*
G01Y1858617D02*
Y1859405D01*
G01Y1852318D02*
Y1853105D01*
G01Y1846019D02*
Y1846806D01*
G01Y1849168D02*
Y1849956D01*
G01Y1842869D02*
Y1843657D01*
G01Y1836570D02*
Y1837357D01*
G01Y1839720D02*
Y1840507D01*
G01Y1833420D02*
Y1834208D01*
G01Y1827121D02*
Y1827908D01*
G01Y1830271D02*
Y1831058D01*
G01X897209Y1861767D02*
Y1859405D01*
G01Y1864916D02*
Y1862554D01*
G01Y1868066D02*
Y1865704D01*
G01X896934Y1878105D02*
Y1858814D01*
G01X896873Y1864916D02*
Y1865704D01*
G01Y1861767D02*
Y1862554D01*
G01Y1855468D02*
Y1856255D01*
G01Y1858617D02*
Y1859405D01*
G01Y1852318D02*
Y1853105D01*
G01Y1846019D02*
Y1846806D01*
G01Y1849168D02*
Y1849956D01*
G01Y1842869D02*
Y1843657D01*
G01Y1836570D02*
Y1837357D01*
G01Y1839720D02*
Y1840507D01*
G01Y1833420D02*
Y1834208D01*
G01Y1827121D02*
Y1827908D01*
G01Y1830271D02*
Y1831058D01*
G01X896659Y1826747D02*
Y1825172D01*
G01Y1831747D02*
Y1830172D01*
G01Y1836747D02*
Y1835172D01*
G01Y1841747D02*
Y1840172D01*
G01Y1846747D02*
Y1845172D01*
G01Y1851747D02*
Y1850172D01*
G01Y1856747D02*
Y1855172D01*
G01X896434Y1878105D02*
Y1858814D01*
G01X896224Y1859306D02*
Y1877613D01*
G01X895675Y1819523D02*
Y1817220D01*
G01Y1827534D02*
Y1824385D01*
G01Y1832534D02*
Y1829385D01*
G01Y1837534D02*
Y1834385D01*
G01Y1842534D02*
Y1839385D01*
G01Y1847534D02*
Y1844385D01*
G01Y1852534D02*
Y1849385D01*
G01Y1857534D02*
Y1854385D01*
G01X895517Y1858814D02*
Y1878105D01*
G01X895240Y1861176D02*
Y1859995D01*
G01Y1864326D02*
Y1863145D01*
G01Y1867475D02*
Y1866294D01*
G01X894690Y1827534D02*
Y1824385D01*
G01Y1832534D02*
Y1829385D01*
G01Y1837534D02*
Y1834385D01*
G01Y1842534D02*
Y1839385D01*
G01Y1847534D02*
Y1844385D01*
G01Y1852534D02*
Y1849385D01*
G01Y1857534D02*
Y1854385D01*
G01X894100Y1819975D02*
Y1956944D01*
G01X893706Y1826747D02*
Y1825172D01*
G01Y1831747D02*
Y1830172D01*
G01Y1836747D02*
Y1835172D01*
G01Y1841747D02*
Y1840172D01*
G01Y1846747D02*
Y1845172D01*
G01Y1851747D02*
Y1850172D01*
G01Y1856747D02*
Y1855172D01*
G01X893645Y1822554D02*
Y1954168D01*
G01X893511Y1827908D02*
Y1827121D01*
G01Y1831058D02*
Y1830271D01*
G01Y1834208D02*
Y1833420D01*
G01Y1837357D02*
Y1836570D01*
G01Y1840507D02*
Y1839720D01*
G01Y1843657D02*
Y1842869D01*
G01Y1846806D02*
Y1846019D01*
G01Y1849956D02*
Y1849168D01*
G01Y1853105D02*
Y1852318D01*
G01Y1856255D02*
Y1855468D01*
G01Y1859405D02*
Y1858617D01*
G01Y1862554D02*
Y1861767D01*
G01Y1865704D02*
Y1864916D01*
G01X893118Y1819582D02*
Y1819523D01*
G01X892479Y1817220D02*
Y1819975D01*
G01X892161Y1858814D02*
Y1878105D01*
G01X892109Y1864838D02*
Y1862633D01*
G01X892090Y1861176D02*
Y1859995D01*
G01Y1864326D02*
Y1863145D01*
G01Y1867475D02*
Y1866294D01*
G01X891683Y1864838D02*
Y1872082D01*
G01Y1858814D02*
Y1862633D01*
G01X891528Y1827908D02*
Y1827121D01*
G01Y1831058D02*
Y1830271D01*
G01Y1834208D02*
Y1833420D01*
G01Y1837357D02*
Y1836570D01*
G01Y1840507D02*
Y1839720D01*
G01Y1843657D02*
Y1842869D01*
G01Y1846806D02*
Y1846019D01*
G01Y1849956D02*
Y1849168D01*
G01Y1853105D02*
Y1852318D01*
G01Y1856255D02*
Y1855468D01*
G01Y1859405D02*
Y1858617D01*
G01Y1862554D02*
Y1861767D01*
G01Y1865704D02*
Y1864916D01*
G01X890557Y1826747D02*
Y1825172D01*
G01Y1831747D02*
Y1830172D01*
G01Y1836747D02*
Y1835172D01*
G01Y1841747D02*
Y1840172D01*
G01Y1846747D02*
Y1845172D01*
G01Y1851747D02*
Y1850172D01*
G01Y1856747D02*
Y1855172D01*
G01X890226Y1862633D02*
Y1864838D01*
G01X889876Y1864916D02*
Y1865704D01*
G01Y1861767D02*
Y1862554D01*
G01Y1855468D02*
Y1856255D01*
G01Y1858617D02*
Y1859405D01*
G01Y1852318D02*
Y1853105D01*
G01Y1846019D02*
Y1846806D01*
G01Y1849168D02*
Y1849956D01*
G01Y1842869D02*
Y1843657D01*
G01Y1836570D02*
Y1837357D01*
G01Y1839720D02*
Y1840507D01*
G01Y1833420D02*
Y1834208D01*
G01Y1827121D02*
Y1827908D01*
G01Y1830271D02*
Y1831058D01*
G01X889592Y1826964D02*
Y1824995D01*
G01X888148Y1830271D02*
Y1827908D01*
G01Y1827121D02*
Y1824542D01*
G01Y1833420D02*
Y1831058D01*
G01Y1836570D02*
Y1834208D01*
G01Y1839720D02*
Y1837357D01*
G01Y1842869D02*
Y1840507D01*
G01Y1846019D02*
Y1843657D01*
G01Y1849168D02*
Y1846806D01*
G01Y1852318D02*
Y1849956D01*
G01Y1855468D02*
Y1853105D01*
G01Y1858617D02*
Y1856255D01*
G01Y1861767D02*
Y1859405D01*
G01Y1864916D02*
Y1862554D01*
G01Y1868066D02*
Y1865704D01*
G01X887209Y1864916D02*
Y1865704D01*
G01Y1861767D02*
Y1862554D01*
G01Y1855468D02*
Y1856255D01*
G01Y1858617D02*
Y1859405D01*
G01Y1852318D02*
Y1853105D01*
G01Y1846019D02*
Y1846806D01*
G01Y1849168D02*
Y1849956D01*
G01Y1842869D02*
Y1843657D01*
G01Y1836570D02*
Y1837357D01*
G01Y1839720D02*
Y1840507D01*
G01Y1833420D02*
Y1834208D01*
G01Y1827121D02*
Y1827908D01*
G01Y1830271D02*
Y1831058D01*
G01X887062Y1864916D02*
Y1865704D01*
G01Y1861767D02*
Y1862554D01*
G01Y1855468D02*
Y1856255D01*
G01Y1858617D02*
Y1859405D01*
G01Y1852318D02*
Y1853105D01*
G01Y1846019D02*
Y1846806D01*
G01Y1849168D02*
Y1849956D01*
G01Y1842869D02*
Y1843657D01*
G01Y1836570D02*
Y1837357D01*
G01Y1839720D02*
Y1840507D01*
G01Y1833420D02*
Y1834208D01*
G01Y1827121D02*
Y1827908D01*
G01Y1830271D02*
Y1831058D01*
G01X885470Y1864916D02*
Y1865704D01*
G01Y1861767D02*
Y1862554D01*
G01Y1855468D02*
Y1856255D01*
G01Y1858617D02*
Y1859405D01*
G01Y1852318D02*
Y1853105D01*
G01Y1846019D02*
Y1846806D01*
G01Y1849168D02*
Y1849956D01*
G01Y1842869D02*
Y1843657D01*
G01Y1836570D02*
Y1837357D01*
G01Y1839720D02*
Y1840507D01*
G01Y1833420D02*
Y1834208D01*
G01Y1827121D02*
Y1827908D01*
G01Y1830271D02*
Y1831058D01*
G01X885115Y1956944D02*
Y1819975D01*
G01X884605Y1817220D02*
Y1819975D01*
G01X884528Y1827908D02*
Y1827121D01*
G01Y1831058D02*
Y1830271D01*
G01Y1834208D02*
Y1833420D01*
G01Y1837357D02*
Y1836570D01*
G01Y1840507D02*
Y1839720D01*
G01Y1843657D02*
Y1842869D01*
G01Y1846806D02*
Y1846019D01*
G01Y1849956D02*
Y1849168D01*
G01Y1853105D02*
Y1852318D01*
G01Y1856255D02*
Y1855468D01*
G01Y1859405D02*
Y1858617D01*
G01Y1862554D02*
Y1861767D01*
G01Y1865704D02*
Y1864916D01*
G01X883433Y1815335D02*
Y1815999D01*
G01X881692Y1827908D02*
Y1827121D01*
G01Y1831058D02*
Y1830271D01*
G01Y1834208D02*
Y1833420D01*
G01Y1837357D02*
Y1836570D01*
G01Y1840507D02*
Y1839720D01*
G01Y1843657D02*
Y1842869D01*
G01Y1846806D02*
Y1846019D01*
G01Y1849956D02*
Y1849168D01*
G01Y1853105D02*
Y1852318D01*
G01Y1856255D02*
Y1855468D01*
G01Y1859405D02*
Y1858617D01*
G01Y1862554D02*
Y1861767D01*
G01Y1865704D02*
Y1864916D01*
G01X881503D02*
Y1865704D01*
G01Y1861767D02*
Y1862554D01*
G01Y1855468D02*
Y1856255D01*
G01Y1858617D02*
Y1859405D01*
G01Y1852318D02*
Y1853105D01*
G01Y1846019D02*
Y1846806D01*
G01Y1849168D02*
Y1849956D01*
G01Y1842869D02*
Y1843657D01*
G01Y1836570D02*
Y1837357D01*
G01Y1839720D02*
Y1840507D01*
G01Y1833420D02*
Y1834208D01*
G01Y1827121D02*
Y1827908D01*
G01Y1830271D02*
Y1831058D01*
G01X879730Y1864916D02*
Y1865704D01*
G01Y1861767D02*
Y1862554D01*
G01Y1855468D02*
Y1856255D01*
G01Y1858617D02*
Y1859405D01*
G01Y1852318D02*
Y1853105D01*
G01Y1846019D02*
Y1846806D01*
G01Y1849168D02*
Y1849956D01*
G01Y1842869D02*
Y1843657D01*
G01Y1836570D02*
Y1837357D01*
G01Y1839720D02*
Y1840507D01*
G01Y1833420D02*
Y1834208D01*
G01Y1827121D02*
Y1827908D01*
G01Y1830271D02*
Y1831058D01*
G01X879594Y1815999D02*
Y1815261D01*
G01X878751Y1822554D02*
Y1819975D01*
G01X878276Y1822554D02*
Y1817220D01*
G01X903754Y1824654D02*
X903667Y1824313D01*
G01X902360Y1824483D02*
X902448Y1824825D01*
G01Y1825336D02*
X902535Y1825678D01*
G01X904190Y1824227D02*
X904277Y1824654D01*
G01X902012Y1825763D02*
X901925Y1825336D01*
G01X900270Y1825678D02*
X900183Y1825251D01*
G01X901925Y1824825D02*
X901838Y1824569D01*
G01X900705Y1825336D02*
X900792Y1825592D01*
G01X902186Y1824142D02*
X902360Y1824483D01*
G01X902186Y1826104D02*
X902012Y1825763D01*
G01X903929Y1823801D02*
X904190Y1824227D01*
G01X900531Y1826019D02*
X900270Y1825678D01*
G01X901838Y1824569D02*
X901664Y1824313D01*
G01X902535Y1825678D02*
X902709Y1825933D01*
G01X903667Y1824313D02*
X903406Y1824057D01*
G01X901838Y1823801D02*
X902186Y1824142D01*
G01X902535Y1826445D02*
X902186Y1826104D01*
G01X900792Y1825592D02*
X900967Y1825763D01*
G01X900879Y1826275D02*
X900531Y1826019D01*
G01X903493Y1823545D02*
X903929Y1823801D01*
G01X896313Y1815020D02*
X896600Y1815199D01*
X896954Y1815261D01*
G01X902709Y1825933D02*
X902970Y1826104D01*
G01X902883Y1826616D02*
X902535Y1826445D01*
G01X900967Y1825763D02*
X901141Y1825848D01*
G01X903406Y1824057D02*
X903144Y1823971D01*
G01X901664Y1824313D02*
X901402Y1824227D01*
G01X901141Y1826360D02*
X900879Y1826275D01*
G01X842028Y1817126D02*
Y1797047D01*
G01X897722Y1886747D02*
G03X898116Y1887141I0J394D01*
G01Y1884779D02*
G03X897722Y1885172I-394J-1D01*
G01Y1881747D02*
G03X898116Y1882141I0J394D01*
G01Y1879779D02*
G03X897722Y1880172I-394J-1D01*
G01X887062Y1887751D02*
X879730D01*
G01X899218D02*
X887209D01*
G01X895675Y1887534D02*
X894690D01*
G01X895675Y1887338D02*
X894690D01*
G01X887209Y1886964D02*
X899218D01*
G01X879730D02*
X887062D01*
G01X895675Y1886944D02*
X894690D01*
G01X890557Y1886747D02*
X897722D01*
G01X890557Y1885172D02*
X897722D01*
G01X895675Y1884975D02*
X894690D01*
G01X928915Y1884660D02*
X909454D01*
G01X887062Y1884601D02*
X879730D01*
G01X899218D02*
X887209D01*
G01X895675Y1884582D02*
X894690D01*
G01X895675Y1884385D02*
X894690D01*
G01X887209Y1883814D02*
X899218D01*
G01X879730D02*
X887062D01*
G01X895675Y1882534D02*
X894690D01*
G01X895675Y1882338D02*
X894690D01*
G01X895675Y1881944D02*
X894690D01*
G01X890557Y1881747D02*
X897722D01*
G01X887062Y1881452D02*
X879730D01*
G01X899218D02*
X887209D01*
G01Y1880664D02*
X899218D01*
G01X879730D02*
X887062D01*
G01X927958Y1880566D02*
X901265D01*
G01X890557Y1880172D02*
X897722D01*
G01X895675Y1879975D02*
X894690D01*
G01X895675Y1879582D02*
X894690D01*
G01X895675Y1879385D02*
X894690D01*
G01X887062Y1878302D02*
X879730D01*
G01X899218D02*
X887209D01*
G01X909454Y1878223D02*
X927958D01*
G01X899218D02*
X898116D01*
G01X923458Y1878204D02*
X901265D01*
G01X899218Y1878105D02*
X891683D01*
G01X896224Y1877613D02*
X894100D01*
G01X887209Y1877515D02*
X899218D01*
G01X879730D02*
X887062D01*
G01X897209Y1877318D02*
X896224D01*
G01X897209Y1877121D02*
X896224D01*
G01X898116Y1876924D02*
X892090D01*
G01X898116Y1875743D02*
X892090D01*
G01X897209Y1875546D02*
X896224D01*
G01X897209Y1875349D02*
X896224D01*
G01X887062Y1875153D02*
X879730D01*
G01X899218D02*
X887209D01*
G01Y1874365D02*
X899218D01*
G01X879730D02*
X887062D01*
G01X892109Y1874286D02*
X890226D01*
G01X897209Y1874168D02*
X896224D01*
G01X897209Y1873971D02*
X896224D01*
G01X898116Y1873775D02*
X892090D01*
G01X898116Y1872594D02*
X892090D01*
G01X897209Y1872397D02*
X896224D01*
G01X897209Y1872200D02*
X896224D01*
G01X890226Y1872082D02*
X892109D01*
G01X887062Y1872003D02*
X879730D01*
G01X899218D02*
X887209D01*
G01Y1871216D02*
X899218D01*
G01X879730D02*
X887062D01*
G01X897209Y1871019D02*
X896224D01*
G01X897209Y1870822D02*
X896224D01*
G01X898116Y1870625D02*
X892090D01*
G01X898116Y1869444D02*
X892090D01*
G01X897209Y1869247D02*
X896224D01*
G01X897209Y1869050D02*
X896224D01*
G01X887062Y1868853D02*
X879730D01*
G01X899218D02*
X887209D01*
G01Y1868066D02*
X899218D01*
G01X879730D02*
X887062D01*
G01X897209Y1867869D02*
X896224D01*
G01X897209Y1867672D02*
X896224D01*
G01X898116Y1867475D02*
X892090D01*
G01X903234Y1880566D02*
Y1896905D01*
G01X897276Y1883814D02*
Y1884601D01*
G01Y1886964D02*
Y1887751D01*
G01Y1880664D02*
Y1881452D01*
G01Y1874365D02*
Y1875153D01*
G01Y1877515D02*
Y1878302D01*
G01Y1871216D02*
Y1872003D01*
G01Y1868066D02*
Y1868853D01*
G01X897249Y1883814D02*
Y1884601D01*
G01Y1886964D02*
Y1887751D01*
G01Y1880664D02*
Y1881452D01*
G01Y1874365D02*
Y1875153D01*
G01Y1877515D02*
Y1878302D01*
G01Y1871216D02*
Y1872003D01*
G01Y1868066D02*
Y1868853D01*
G01X897209Y1871216D02*
Y1868853D01*
G01Y1874365D02*
Y1872003D01*
G01Y1877515D02*
Y1875153D01*
G01X896873Y1883814D02*
Y1884601D01*
G01Y1886964D02*
Y1887751D01*
G01Y1880664D02*
Y1881452D01*
G01Y1874365D02*
Y1875153D01*
G01Y1877515D02*
Y1878302D01*
G01Y1871216D02*
Y1872003D01*
G01Y1868066D02*
Y1868853D01*
G01X896659Y1881747D02*
Y1880172D01*
G01Y1886747D02*
Y1885172D01*
G01X895675Y1882534D02*
Y1879385D01*
G01Y1887534D02*
Y1884385D01*
G01X895240Y1870625D02*
Y1869444D01*
G01Y1873775D02*
Y1872594D01*
G01Y1876924D02*
Y1875743D01*
G01X894690Y1882534D02*
Y1879385D01*
G01Y1887534D02*
Y1884385D01*
G01X893706Y1881747D02*
Y1880172D01*
G01Y1886747D02*
Y1885172D01*
G01X893511Y1868853D02*
Y1868066D01*
G01Y1872003D02*
Y1871216D01*
G01Y1875153D02*
Y1874365D01*
G01Y1878302D02*
Y1877515D01*
G01Y1881452D02*
Y1880664D01*
G01Y1884601D02*
Y1883814D01*
G01Y1887751D02*
Y1886964D01*
G01X892109Y1874286D02*
Y1872082D01*
G01X892090Y1870625D02*
Y1869444D01*
G01Y1873775D02*
Y1872594D01*
G01Y1876924D02*
Y1875743D01*
G01X891683Y1874286D02*
Y1878105D01*
G01X891528Y1868853D02*
Y1868066D01*
G01Y1872003D02*
Y1871216D01*
G01Y1875153D02*
Y1874365D01*
G01Y1878302D02*
Y1877515D01*
G01Y1881452D02*
Y1880664D01*
G01Y1884601D02*
Y1883814D01*
G01Y1887751D02*
Y1886964D01*
G01X890557Y1881747D02*
Y1880172D01*
G01Y1886747D02*
Y1885172D01*
G01X890226Y1872082D02*
Y1874286D01*
G01X889876Y1883814D02*
Y1884601D01*
G01Y1886964D02*
Y1887751D01*
G01Y1880664D02*
Y1881452D01*
G01Y1874365D02*
Y1875153D01*
G01Y1877515D02*
Y1878302D01*
G01Y1871216D02*
Y1872003D01*
G01Y1868066D02*
Y1868853D01*
G01X888148Y1871216D02*
Y1868853D01*
G01Y1874365D02*
Y1872003D01*
G01Y1877515D02*
Y1875153D01*
G01Y1880664D02*
Y1878302D01*
G01Y1883814D02*
Y1881452D01*
G01Y1886964D02*
Y1884601D01*
G01Y1890113D02*
Y1887751D01*
G01X887209Y1883814D02*
Y1884601D01*
G01Y1886964D02*
Y1887751D01*
G01Y1880664D02*
Y1881452D01*
G01Y1874365D02*
Y1875153D01*
G01Y1877515D02*
Y1878302D01*
G01Y1871216D02*
Y1872003D01*
G01Y1868066D02*
Y1868853D01*
G01X887062Y1883814D02*
Y1884601D01*
G01Y1886964D02*
Y1887751D01*
G01Y1880664D02*
Y1881452D01*
G01Y1874365D02*
Y1875153D01*
G01Y1877515D02*
Y1878302D01*
G01Y1871216D02*
Y1872003D01*
G01Y1868066D02*
Y1868853D01*
G01X885470Y1883814D02*
Y1884601D01*
G01Y1886964D02*
Y1887751D01*
G01Y1880664D02*
Y1881452D01*
G01Y1874365D02*
Y1875153D01*
G01Y1877515D02*
Y1878302D01*
G01Y1871216D02*
Y1872003D01*
G01Y1868066D02*
Y1868853D01*
G01X884528D02*
Y1868066D01*
G01Y1872003D02*
Y1871216D01*
G01Y1875153D02*
Y1874365D01*
G01Y1878302D02*
Y1877515D01*
G01Y1881452D02*
Y1880664D01*
G01Y1884601D02*
Y1883814D01*
G01Y1887751D02*
Y1886964D01*
G01X881692Y1868853D02*
Y1868066D01*
G01Y1872003D02*
Y1871216D01*
G01Y1875153D02*
Y1874365D01*
G01Y1878302D02*
Y1877515D01*
G01Y1881452D02*
Y1880664D01*
G01Y1884601D02*
Y1883814D01*
G01Y1887751D02*
Y1886964D01*
G01X881503Y1883814D02*
Y1884601D01*
G01Y1886964D02*
Y1887751D01*
G01Y1880664D02*
Y1881452D01*
G01Y1874365D02*
Y1875153D01*
G01Y1877515D02*
Y1878302D01*
G01Y1871216D02*
Y1872003D01*
G01Y1868066D02*
Y1868853D01*
G01X879730Y1883814D02*
Y1884601D01*
G01Y1886964D02*
Y1887751D01*
G01Y1880664D02*
Y1881452D01*
G01Y1874365D02*
Y1875153D01*
G01Y1877515D02*
Y1878302D01*
G01Y1871216D02*
Y1872003D01*
G01Y1868066D02*
Y1868853D01*
G01X897722Y1931747D02*
G03X898116Y1932141I0J394D01*
G01Y1929779D02*
G03X897722Y1930172I-394J-1D01*
G01Y1901747D02*
G03X898116Y1902141I0J394D01*
G01Y1899779D02*
G03X897722Y1900172I-394J-1D01*
G01Y1891747D02*
G03X898116Y1892141I0J394D01*
G01Y1889779D02*
G03X897722Y1890172I-394J-1D01*
G01Y1911747D02*
G03X898116Y1912141I0J394D01*
G01Y1909779D02*
G03X897722Y1910172I-394J-1D01*
G01Y1916747D02*
G03X898116Y1917141I0J394D01*
G01Y1914779D02*
G03X897722Y1915172I-394J-1D01*
G01Y1926747D02*
G03X898116Y1927141I0J394D01*
G01Y1924779D02*
G03X897722Y1925172I-394J-1D01*
G01Y1921747D02*
G03X898116Y1922141I0J394D01*
G01Y1919779D02*
G03X897722Y1920172I-394J-1D01*
G01Y1906747D02*
G03X898116Y1907141I0J394D01*
G01Y1904779D02*
G03X897722Y1905172I-394J-1D01*
G01X899218Y1938164D02*
X898116D01*
G01X887062Y1938145D02*
X879730D01*
G01X899218D02*
X887209D01*
G01X897643Y1937534D02*
X896659D01*
G01X887209Y1937357D02*
X899218D01*
G01X879730D02*
X887062D01*
G01X897643Y1937338D02*
X896659D01*
G01X927958Y1937062D02*
X901265D01*
G01X897643Y1936944D02*
X896659D01*
G01X898116Y1936747D02*
X892525D01*
G01X898116Y1935172D02*
X892525D01*
G01X887062Y1934995D02*
X879730D01*
G01X899218D02*
X887209D01*
G01X897643Y1934975D02*
X896659D01*
G01X927958Y1934700D02*
X901265D01*
G01X897643Y1934582D02*
X896659D01*
G01X897643Y1934385D02*
X896659D01*
G01X887209Y1934208D02*
X899218D01*
G01X879730D02*
X887062D01*
G01X899218Y1933755D02*
X898116D01*
G01X895675Y1932534D02*
X894690D01*
G01X895675Y1932338D02*
X894690D01*
G01X895675Y1931944D02*
X894690D01*
G01X887062Y1931846D02*
X879730D01*
G01X899218D02*
X887209D01*
G01X890557Y1931747D02*
X897722D01*
G01X887209Y1931058D02*
X899218D01*
G01X879730D02*
X887062D01*
G01X890557Y1930172D02*
X897722D01*
G01X895675Y1929975D02*
X894690D01*
G01X895675Y1929582D02*
X894690D01*
G01X895675Y1929385D02*
X894690D01*
G01X887062Y1928696D02*
X879730D01*
G01X899218D02*
X887209D01*
G01Y1927908D02*
X899218D01*
G01X879730D02*
X887062D01*
G01X895675Y1927534D02*
X894690D01*
G01X895675Y1927338D02*
X894690D01*
G01X895675Y1926944D02*
X894690D01*
G01X890557Y1926747D02*
X897722D01*
G01X887062Y1925546D02*
X879730D01*
G01X899218D02*
X887209D01*
G01X890557Y1925172D02*
X897722D01*
G01X895675Y1924975D02*
X894690D01*
G01X887209Y1924759D02*
X899218D01*
G01X879730D02*
X887062D01*
G01X895675Y1924582D02*
X894690D01*
G01X895675Y1924385D02*
X894690D01*
G01X895675Y1922534D02*
X894690D01*
G01X887062Y1922397D02*
X879730D01*
G01X899218D02*
X887209D01*
G01X895675Y1922338D02*
X894690D01*
G01X895675Y1921944D02*
X894690D01*
G01X890557Y1921747D02*
X897722D01*
G01X887209Y1921609D02*
X899218D01*
G01X879730D02*
X887062D01*
G01X890557Y1920172D02*
X897722D01*
G01X895675Y1919975D02*
X894690D01*
G01X895675Y1919582D02*
X894690D01*
G01X895675Y1919385D02*
X894690D01*
G01X887062Y1919247D02*
X879730D01*
G01X899218D02*
X887209D01*
G01Y1918460D02*
X899218D01*
G01X879730D02*
X887062D01*
G01X927958Y1918164D02*
X901265D01*
G01X895675Y1917534D02*
X894690D01*
G01X895675Y1917338D02*
X894690D01*
G01X895675Y1916944D02*
X894690D01*
G01X890557Y1916747D02*
X897722D01*
G01X887062Y1916097D02*
X879730D01*
G01X899218D02*
X887209D01*
G01X927958Y1915802D02*
X901265D01*
G01X887209Y1915310D02*
X899218D01*
G01X879730D02*
X887062D01*
G01X890557Y1915172D02*
X897722D01*
G01X895675Y1914975D02*
X894690D01*
G01X895675Y1914582D02*
X894690D01*
G01X895675Y1914385D02*
X894690D01*
G01X887062Y1912948D02*
X879730D01*
G01X899218D02*
X887209D01*
G01X895675Y1912534D02*
X894690D01*
G01X895675Y1912338D02*
X894690D01*
G01X887209Y1912160D02*
X899218D01*
G01X879730D02*
X887062D01*
G01X895675Y1911944D02*
X894690D01*
G01X890557Y1911747D02*
X897722D01*
G01X890557Y1910172D02*
X897722D01*
G01X895675Y1909975D02*
X894690D01*
G01X887062Y1909798D02*
X879730D01*
G01X899218D02*
X887209D01*
G01X895675Y1909582D02*
X894690D01*
G01X895675Y1909385D02*
X894690D01*
G01X887209Y1909011D02*
X899218D01*
G01X879730D02*
X887062D01*
G01X895675Y1907534D02*
X894690D01*
G01X895675Y1907338D02*
X894690D01*
G01X895675Y1906944D02*
X894690D01*
G01X890557Y1906747D02*
X897722D01*
G01X887062Y1906649D02*
X879730D01*
G01X899218D02*
X887209D01*
G01Y1905861D02*
X899218D01*
G01X879730D02*
X887062D01*
G01X890557Y1905172D02*
X897722D01*
G01X895675Y1904975D02*
X894690D01*
G01X895675Y1904582D02*
X894690D01*
G01X895675Y1904385D02*
X894690D01*
G01X887062Y1903499D02*
X879730D01*
G01X899218D02*
X887209D01*
G01Y1902712D02*
X899218D01*
G01X879730D02*
X887062D01*
G01X895675Y1902534D02*
X894690D01*
G01X895675Y1902338D02*
X894690D01*
G01X895675Y1901944D02*
X894690D01*
G01X890557Y1901747D02*
X897722D01*
G01X887062Y1900349D02*
X879730D01*
G01X899218D02*
X887209D01*
G01X890557Y1900172D02*
X897722D01*
G01X895675Y1899975D02*
X894690D01*
G01X895675Y1899582D02*
X894690D01*
G01X887209Y1899562D02*
X899218D01*
G01X879730D02*
X887062D01*
G01X895675Y1899385D02*
X894690D01*
G01X927958Y1899267D02*
X901265D01*
G01X898116Y1898164D02*
X899218D01*
G01X897643Y1897534D02*
X896659D01*
G01X897643Y1897338D02*
X896659D01*
G01X887062Y1897200D02*
X879730D01*
G01X899218D02*
X887209D01*
G01X897643Y1896944D02*
X896659D01*
G01X927958Y1896905D02*
X901265D01*
G01X898116Y1896747D02*
X892525D01*
G01X887209Y1896412D02*
X899218D01*
G01X879730D02*
X887062D01*
G01X898116Y1895172D02*
X892525D01*
G01X897643Y1894975D02*
X896659D01*
G01X897643Y1894582D02*
X896659D01*
G01X897643Y1894385D02*
X896659D01*
G01X887062Y1894050D02*
X879730D01*
G01X899218D02*
X887209D01*
G01X899218Y1893755D02*
X898116D01*
G01X887209Y1893263D02*
X899218D01*
G01X879730D02*
X887062D01*
G01X895675Y1892534D02*
X894690D01*
G01X895675Y1892338D02*
X894690D01*
G01X895675Y1891944D02*
X894690D01*
G01X890557Y1891747D02*
X897722D01*
G01X887062Y1890901D02*
X879730D01*
G01X899218D02*
X887209D01*
G01X890557Y1890172D02*
X897722D01*
G01X887209Y1890113D02*
X899218D01*
G01X879730D02*
X887062D01*
G01X895675Y1889975D02*
X894690D01*
G01X895675Y1889582D02*
X894690D01*
G01X895675Y1889385D02*
X894690D01*
G01X903234Y1937062D02*
Y1954582D01*
G01Y1918164D02*
Y1934700D01*
G01Y1899267D02*
Y1915802D01*
G01X897643Y1897534D02*
Y1894385D01*
G01Y1937534D02*
Y1934385D01*
G01X897276Y1934208D02*
Y1934995D01*
G01Y1937357D02*
Y1938145D01*
G01Y1931058D02*
Y1931846D01*
G01Y1924759D02*
Y1925546D01*
G01Y1927908D02*
Y1928696D01*
G01Y1921609D02*
Y1922397D01*
G01Y1915310D02*
Y1916097D01*
G01Y1918460D02*
Y1919247D01*
G01Y1912160D02*
Y1912948D01*
G01Y1905861D02*
Y1906649D01*
G01Y1909011D02*
Y1909798D01*
G01Y1902712D02*
Y1903499D01*
G01Y1899562D02*
Y1900349D01*
G01Y1893263D02*
Y1894050D01*
G01Y1896412D02*
Y1897200D01*
G01Y1890113D02*
Y1890901D01*
G01X897249Y1934208D02*
Y1934995D01*
G01Y1937357D02*
Y1938145D01*
G01Y1931058D02*
Y1931846D01*
G01Y1924759D02*
Y1925546D01*
G01Y1927908D02*
Y1928696D01*
G01Y1921609D02*
Y1922397D01*
G01Y1915310D02*
Y1916097D01*
G01Y1918460D02*
Y1919247D01*
G01Y1912160D02*
Y1912948D01*
G01Y1905861D02*
Y1906649D01*
G01Y1909011D02*
Y1909798D01*
G01Y1902712D02*
Y1903499D01*
G01Y1899562D02*
Y1900349D01*
G01Y1893263D02*
Y1894050D01*
G01Y1896412D02*
Y1897200D01*
G01Y1890113D02*
Y1890901D01*
G01X896873Y1934208D02*
Y1934995D01*
G01Y1937357D02*
Y1938145D01*
G01Y1931058D02*
Y1931846D01*
G01Y1924759D02*
Y1925546D01*
G01Y1927908D02*
Y1928696D01*
G01Y1921609D02*
Y1922397D01*
G01Y1915310D02*
Y1916097D01*
G01Y1918460D02*
Y1919247D01*
G01Y1912160D02*
Y1912948D01*
G01Y1905861D02*
Y1906649D01*
G01Y1909011D02*
Y1909798D01*
G01Y1902712D02*
Y1903499D01*
G01Y1899562D02*
Y1900349D01*
G01Y1893263D02*
Y1894050D01*
G01Y1896412D02*
Y1897200D01*
G01Y1890113D02*
Y1890901D01*
G01X896659Y1891747D02*
Y1890172D01*
G01Y1901747D02*
Y1900172D01*
G01Y1897534D02*
Y1894385D01*
G01Y1906747D02*
Y1905172D01*
G01Y1911747D02*
Y1910172D01*
G01Y1916747D02*
Y1915172D01*
G01Y1921747D02*
Y1920172D01*
G01Y1926747D02*
Y1925172D01*
G01Y1931747D02*
Y1930172D01*
G01Y1937534D02*
Y1934385D01*
G01X895675Y1892534D02*
Y1889385D01*
G01Y1896747D02*
Y1895172D01*
G01Y1902534D02*
Y1899385D01*
G01Y1907534D02*
Y1904385D01*
G01Y1912534D02*
Y1909385D01*
G01Y1917534D02*
Y1914385D01*
G01Y1922534D02*
Y1919385D01*
G01Y1927534D02*
Y1924385D01*
G01Y1932534D02*
Y1929385D01*
G01Y1936747D02*
Y1935172D01*
G01X894690Y1892534D02*
Y1889385D01*
G01Y1902534D02*
Y1899385D01*
G01Y1907534D02*
Y1904385D01*
G01Y1912534D02*
Y1909385D01*
G01Y1917534D02*
Y1914385D01*
G01Y1922534D02*
Y1919385D01*
G01Y1927534D02*
Y1924385D01*
G01Y1932534D02*
Y1929385D01*
G01X893706Y1891747D02*
Y1890172D01*
G01Y1901747D02*
Y1900172D01*
G01Y1906747D02*
Y1905172D01*
G01Y1911747D02*
Y1910172D01*
G01Y1916747D02*
Y1915172D01*
G01Y1921747D02*
Y1920172D01*
G01Y1926747D02*
Y1925172D01*
G01Y1931747D02*
Y1930172D01*
G01X893511Y1890901D02*
Y1890113D01*
G01Y1894050D02*
Y1893263D01*
G01Y1897200D02*
Y1896412D01*
G01Y1900349D02*
Y1899562D01*
G01Y1903499D02*
Y1902712D01*
G01Y1906649D02*
Y1905861D01*
G01Y1909798D02*
Y1909011D01*
G01Y1912948D02*
Y1912160D01*
G01Y1916097D02*
Y1915310D01*
G01Y1919247D02*
Y1918460D01*
G01Y1922397D02*
Y1921609D01*
G01Y1925546D02*
Y1924759D01*
G01Y1928696D02*
Y1927908D01*
G01Y1931846D02*
Y1931058D01*
G01Y1934995D02*
Y1934208D01*
G01Y1938145D02*
Y1937357D01*
G01X892525Y1896747D02*
Y1895172D01*
G01Y1936747D02*
Y1935172D01*
G01X891528Y1890901D02*
Y1890113D01*
G01Y1894050D02*
Y1893263D01*
G01Y1897200D02*
Y1896412D01*
G01Y1900349D02*
Y1899562D01*
G01Y1903499D02*
Y1902712D01*
G01Y1906649D02*
Y1905861D01*
G01Y1909798D02*
Y1909011D01*
G01Y1912948D02*
Y1912160D01*
G01Y1916097D02*
Y1915310D01*
G01Y1919247D02*
Y1918460D01*
G01Y1922397D02*
Y1921609D01*
G01Y1925546D02*
Y1924759D01*
G01Y1928696D02*
Y1927908D01*
G01Y1931846D02*
Y1931058D01*
G01Y1934995D02*
Y1934208D01*
G01Y1938145D02*
Y1937357D01*
G01X890557Y1891747D02*
Y1890172D01*
G01Y1901747D02*
Y1900172D01*
G01Y1906747D02*
Y1905172D01*
G01Y1911747D02*
Y1910172D01*
G01Y1916747D02*
Y1915172D01*
G01Y1921747D02*
Y1920172D01*
G01Y1926747D02*
Y1925172D01*
G01Y1931747D02*
Y1930172D01*
G01X889876Y1934208D02*
Y1934995D01*
G01Y1937357D02*
Y1938145D01*
G01Y1931058D02*
Y1931846D01*
G01Y1924759D02*
Y1925546D01*
G01Y1927908D02*
Y1928696D01*
G01Y1921609D02*
Y1922397D01*
G01Y1915310D02*
Y1916097D01*
G01Y1918460D02*
Y1919247D01*
G01Y1912160D02*
Y1912948D01*
G01Y1905861D02*
Y1906649D01*
G01Y1909011D02*
Y1909798D01*
G01Y1902712D02*
Y1903499D01*
G01Y1899562D02*
Y1900349D01*
G01Y1893263D02*
Y1894050D01*
G01Y1896412D02*
Y1897200D01*
G01Y1890113D02*
Y1890901D01*
G01X888148Y1893263D02*
Y1890901D01*
G01Y1896412D02*
Y1894050D01*
G01Y1899562D02*
Y1897200D01*
G01Y1902712D02*
Y1900349D01*
G01Y1905861D02*
Y1903499D01*
G01Y1909011D02*
Y1906649D01*
G01Y1912160D02*
Y1909798D01*
G01Y1915310D02*
Y1912948D01*
G01Y1918460D02*
Y1916097D01*
G01Y1921609D02*
Y1919247D01*
G01Y1924759D02*
Y1922397D01*
G01Y1927908D02*
Y1925546D01*
G01Y1931058D02*
Y1928696D01*
G01Y1934208D02*
Y1931846D01*
G01Y1937357D02*
Y1934995D01*
G01Y1940507D02*
Y1938145D01*
G01X887209Y1934208D02*
Y1934995D01*
G01Y1937357D02*
Y1938145D01*
G01Y1931058D02*
Y1931846D01*
G01Y1924759D02*
Y1925546D01*
G01Y1927908D02*
Y1928696D01*
G01Y1921609D02*
Y1922397D01*
G01Y1915310D02*
Y1916097D01*
G01Y1918460D02*
Y1919247D01*
G01Y1912160D02*
Y1912948D01*
G01Y1905861D02*
Y1906649D01*
G01Y1909011D02*
Y1909798D01*
G01Y1902712D02*
Y1903499D01*
G01Y1899562D02*
Y1900349D01*
G01Y1893263D02*
Y1894050D01*
G01Y1896412D02*
Y1897200D01*
G01Y1890113D02*
Y1890901D01*
G01X887062Y1934208D02*
Y1934995D01*
G01Y1937357D02*
Y1938145D01*
G01Y1931058D02*
Y1931846D01*
G01Y1924759D02*
Y1925546D01*
G01Y1927908D02*
Y1928696D01*
G01Y1921609D02*
Y1922397D01*
G01Y1915310D02*
Y1916097D01*
G01Y1918460D02*
Y1919247D01*
G01Y1912160D02*
Y1912948D01*
G01Y1905861D02*
Y1906649D01*
G01Y1909011D02*
Y1909798D01*
G01Y1902712D02*
Y1903499D01*
G01Y1899562D02*
Y1900349D01*
G01Y1893263D02*
Y1894050D01*
G01Y1896412D02*
Y1897200D01*
G01Y1890113D02*
Y1890901D01*
G01X885470Y1934208D02*
Y1934995D01*
G01Y1937357D02*
Y1938145D01*
G01Y1931058D02*
Y1931846D01*
G01Y1924759D02*
Y1925546D01*
G01Y1927908D02*
Y1928696D01*
G01Y1921609D02*
Y1922397D01*
G01Y1915310D02*
Y1916097D01*
G01Y1918460D02*
Y1919247D01*
G01Y1912160D02*
Y1912948D01*
G01Y1905861D02*
Y1906649D01*
G01Y1909011D02*
Y1909798D01*
G01Y1902712D02*
Y1903499D01*
G01Y1899562D02*
Y1900349D01*
G01Y1893263D02*
Y1894050D01*
G01Y1896412D02*
Y1897200D01*
G01Y1890113D02*
Y1890901D01*
G01X884528D02*
Y1890113D01*
G01Y1894050D02*
Y1893263D01*
G01Y1897200D02*
Y1896412D01*
G01Y1900349D02*
Y1899562D01*
G01Y1903499D02*
Y1902712D01*
G01Y1906649D02*
Y1905861D01*
G01Y1909798D02*
Y1909011D01*
G01Y1912948D02*
Y1912160D01*
G01Y1916097D02*
Y1915310D01*
G01Y1919247D02*
Y1918460D01*
G01Y1922397D02*
Y1921609D01*
G01Y1925546D02*
Y1924759D01*
G01Y1928696D02*
Y1927908D01*
G01Y1931846D02*
Y1931058D01*
G01Y1934995D02*
Y1934208D01*
G01Y1938145D02*
Y1937357D01*
G01X881692Y1890901D02*
Y1890113D01*
G01Y1894050D02*
Y1893263D01*
G01Y1897200D02*
Y1896412D01*
G01Y1900349D02*
Y1899562D01*
G01Y1903499D02*
Y1902712D01*
G01Y1906649D02*
Y1905861D01*
G01Y1909798D02*
Y1909011D01*
G01Y1912948D02*
Y1912160D01*
G01Y1916097D02*
Y1915310D01*
G01Y1919247D02*
Y1918460D01*
G01Y1922397D02*
Y1921609D01*
G01Y1925546D02*
Y1924759D01*
G01Y1928696D02*
Y1927908D01*
G01Y1931846D02*
Y1931058D01*
G01Y1934995D02*
Y1934208D01*
G01Y1938145D02*
Y1937357D01*
G01X881503Y1934208D02*
Y1934995D01*
G01Y1937357D02*
Y1938145D01*
G01Y1931058D02*
Y1931846D01*
G01Y1924759D02*
Y1925546D01*
G01Y1927908D02*
Y1928696D01*
G01Y1921609D02*
Y1922397D01*
G01Y1915310D02*
Y1916097D01*
G01Y1918460D02*
Y1919247D01*
G01Y1912160D02*
Y1912948D01*
G01Y1905861D02*
Y1906649D01*
G01Y1909011D02*
Y1909798D01*
G01Y1902712D02*
Y1903499D01*
G01Y1899562D02*
Y1900349D01*
G01Y1893263D02*
Y1894050D01*
G01Y1896412D02*
Y1897200D01*
G01Y1890113D02*
Y1890901D01*
G01X879730Y1934208D02*
Y1934995D01*
G01Y1937357D02*
Y1938145D01*
G01Y1931058D02*
Y1931846D01*
G01Y1924759D02*
Y1925546D01*
G01Y1927908D02*
Y1928696D01*
G01Y1921609D02*
Y1922397D01*
G01Y1915310D02*
Y1916097D01*
G01Y1918460D02*
Y1919247D01*
G01Y1912160D02*
Y1912948D01*
G01Y1905861D02*
Y1906649D01*
G01Y1909011D02*
Y1909798D01*
G01Y1902712D02*
Y1903499D01*
G01Y1899562D02*
Y1900349D01*
G01Y1893263D02*
Y1894050D01*
G01Y1896412D02*
Y1897200D01*
G01Y1890113D02*
Y1890901D01*
G01X897722Y1951747D02*
G03X898116Y1952141I0J394D01*
G01Y1949779D02*
G03X897722Y1950172I-394J-1D01*
G01Y1941747D02*
G03X898116Y1942141I0J394D01*
G01Y1939779D02*
G03X897722Y1940172I-394J-1D01*
G01Y1946747D02*
G03X898116Y1947141I0J394D01*
G01Y1944779D02*
G03X897722Y1945172I-394J-1D01*
G01X888405Y1965979D02*
G03Y1960546I1955J-2717D01*
G01X892314D02*
G03Y1965979I-1954J2717D01*
G01X893864Y1963263D02*
G03I-3504J0D01*
G01X892663Y1959365D02*
G03Y1967160I-2304J3898D01*
G01X888056D02*
G03Y1959365I2304J-3897D01*
G01X892314Y1960546D02*
X888405D01*
G01X901580Y1960330D02*
X877958D01*
G01X927958Y1959700D02*
X877958D01*
G01X888056Y1959365D02*
X892663D01*
G01X877958Y1957928D02*
X901580D01*
G01X893118Y1957397D02*
X899218D01*
G01X893118Y1957338D02*
X899218D01*
G01X878751Y1956944D02*
X899218D01*
G01X898116Y1955763D02*
X907486D01*
G01X929927Y1955172D02*
X899218D01*
G01X927958Y1954779D02*
X909454D01*
G01X907801Y1954582D02*
X901265D01*
G01X877958Y1954168D02*
X898116D01*
G01Y1953991D02*
X907486D01*
G01X895675Y1952534D02*
X894690D01*
G01X894100Y1952416D02*
X885115D01*
G01X895675Y1952338D02*
X894690D01*
G01X895675Y1951944D02*
X894690D01*
G01X890557Y1951747D02*
X897722D01*
G01X887062Y1950743D02*
X879730D01*
G01X899218D02*
X887209D01*
G01X890557Y1950172D02*
X897722D01*
G01X895675Y1949975D02*
X894690D01*
G01X887209Y1949956D02*
X899218D01*
G01X879730D02*
X887062D01*
G01X895675Y1949582D02*
X894690D01*
G01X895675Y1949385D02*
X894690D01*
G01X887062Y1947594D02*
X879730D01*
G01X899218D02*
X887209D01*
G01X895675Y1947534D02*
X894690D01*
G01X895675Y1947338D02*
X894690D01*
G01X895675Y1946944D02*
X894690D01*
G01X887209Y1946806D02*
X899218D01*
G01X879730D02*
X887062D01*
G01X890557Y1946747D02*
X897722D01*
G01X890557Y1945172D02*
X897722D01*
G01X895675Y1944975D02*
X894690D01*
G01X895675Y1944582D02*
X894690D01*
G01X887062Y1944444D02*
X879730D01*
G01X899218D02*
X887209D01*
G01X895675Y1944385D02*
X894690D01*
G01X887209Y1943657D02*
X899218D01*
G01X879730D02*
X887062D01*
G01X895675Y1942534D02*
X894690D01*
G01X895675Y1942338D02*
X894690D01*
G01X895675Y1941944D02*
X894690D01*
G01X890557Y1941747D02*
X897722D01*
G01X887062Y1941294D02*
X879730D01*
G01X899218D02*
X887209D01*
G01Y1940507D02*
X899218D01*
G01X879730D02*
X887062D01*
G01X890557Y1940172D02*
X897722D01*
G01X895675Y1939975D02*
X894690D01*
G01X895675Y1939582D02*
X894690D01*
G01X895675Y1939385D02*
X894690D01*
G01X892314Y1960546D02*
X892332Y1960490D01*
X892384Y1960325D01*
X892463Y1960066D01*
X892559Y1959739D01*
X892663Y1959365D01*
G01X907801Y1954582D02*
Y1980979D01*
G01X907486Y1955763D02*
Y1953991D01*
G01X905517Y1968046D02*
Y1959700D01*
G01X901580Y1960330D02*
Y1957928D01*
G01X897276Y1949956D02*
Y1950743D01*
G01Y1943657D02*
Y1944444D01*
G01Y1946806D02*
Y1947594D01*
G01Y1940507D02*
Y1941294D01*
G01X897249Y1949956D02*
Y1950743D01*
G01Y1943657D02*
Y1944444D01*
G01Y1946806D02*
Y1947594D01*
G01Y1940507D02*
Y1941294D01*
G01X896873Y1949956D02*
Y1950743D01*
G01Y1943657D02*
Y1944444D01*
G01Y1946806D02*
Y1947594D01*
G01Y1940507D02*
Y1941294D01*
G01X896659Y1941747D02*
Y1940172D01*
G01Y1946747D02*
Y1945172D01*
G01Y1951747D02*
Y1950172D01*
G01X895675Y1942534D02*
Y1939385D01*
G01Y1947534D02*
Y1944385D01*
G01Y1952534D02*
Y1949385D01*
G01Y1959700D02*
Y1957397D01*
G01X894690Y1942534D02*
Y1939385D01*
G01Y1947534D02*
Y1944385D01*
G01Y1952534D02*
Y1949385D01*
G01X893706Y1941747D02*
Y1940172D01*
G01Y1946747D02*
Y1945172D01*
G01Y1951747D02*
Y1950172D01*
G01X893511Y1941294D02*
Y1940507D01*
G01Y1944444D02*
Y1943657D01*
G01Y1947594D02*
Y1946806D01*
G01Y1950743D02*
Y1949956D01*
G01X893118Y1957397D02*
Y1957338D01*
G01X892479Y1956944D02*
Y1959700D01*
G01X891528Y1941294D02*
Y1940507D01*
G01Y1944444D02*
Y1943657D01*
G01Y1947594D02*
Y1946806D01*
G01Y1950743D02*
Y1949956D01*
G01X890557Y1941747D02*
Y1940172D01*
G01Y1946747D02*
Y1945172D01*
G01Y1951747D02*
Y1950172D01*
G01X889876Y1949956D02*
Y1950743D01*
G01Y1943657D02*
Y1944444D01*
G01Y1946806D02*
Y1947594D01*
G01Y1940507D02*
Y1941294D01*
G01X888148Y1943657D02*
Y1941294D01*
G01Y1946806D02*
Y1944444D01*
G01Y1949956D02*
Y1947594D01*
G01Y1952416D02*
Y1950743D01*
G01X887209Y1949956D02*
Y1950743D01*
G01Y1943657D02*
Y1944444D01*
G01Y1946806D02*
Y1947594D01*
G01Y1940507D02*
Y1941294D01*
G01X887062Y1949956D02*
Y1950743D01*
G01Y1943657D02*
Y1944444D01*
G01Y1946806D02*
Y1947594D01*
G01Y1940507D02*
Y1941294D01*
G01X885470Y1949956D02*
Y1950743D01*
G01Y1943657D02*
Y1944444D01*
G01Y1946806D02*
Y1947594D01*
G01Y1940507D02*
Y1941294D01*
G01X884605Y1956944D02*
Y1959700D01*
G01X884528Y1941294D02*
Y1940507D01*
G01Y1944444D02*
Y1943657D01*
G01Y1947594D02*
Y1946806D01*
G01Y1950743D02*
Y1949956D01*
G01X881692Y1941294D02*
Y1940507D01*
G01Y1944444D02*
Y1943657D01*
G01Y1947594D02*
Y1946806D01*
G01Y1950743D02*
Y1949956D01*
G01X881503D02*
Y1950743D01*
G01Y1943657D02*
Y1944444D01*
G01Y1946806D02*
Y1947594D01*
G01Y1940507D02*
Y1941294D01*
G01X879730Y1949956D02*
Y1950743D01*
G01Y1943657D02*
Y1944444D01*
G01Y1946806D02*
Y1947594D01*
G01Y1940507D02*
Y1941294D01*
G01X878751Y1956944D02*
Y1954168D01*
G01X878276Y1959700D02*
Y1954168D01*
G01X877958Y1968046D02*
Y1954168D01*
G01X888405Y1960546D02*
X888388Y1960490D01*
X888335Y1960325D01*
X888257Y1960067D01*
X888161Y1959740D01*
X888056Y1959365D01*
G01X893118Y1957338D02*
X892863Y1956944D01*
G01X900906Y1964120D02*
G03X902336I715J0D01*
G01X898016D02*
G03X899446I715J0D01*
G01X901777Y1973499D02*
G03Y1976649I0J1575D01*
G01X896917Y1963044D02*
G03X899553Y1963189I1248J1352D01*
G01D02*
G03X902334Y1963194I1388J1207D01*
G01X896623Y1963715D02*
G03X896917Y1963044I914J0D01*
G01X897446Y1976649D02*
G03Y1973499I0J-1575D01*
G01X892944Y1965535D02*
G03Y1963851I2236J-842D01*
G01X894417Y1965536D02*
G03X892944I-737J-278D01*
G01Y1963851D02*
G03X894417I736J277D01*
G01X895689Y1965870D02*
G03X895168Y1966436I-1352J-722D01*
G01X892122Y1966434D02*
G03X891601Y1965869I830J-1288D01*
G01X891602Y1963556D02*
G03X892123Y1962991I1351J723D01*
G01X895169Y1962992D02*
G03X895690Y1963557I-830J1288D01*
G01X894417Y1963851D02*
G03Y1965535I-2237J842D01*
G01X895690Y1963557D02*
G03X895689Y1965870I-2163J1156D01*
G01X891601Y1965869D02*
G03X891602Y1963556I2163J-1156D01*
G01X895168Y1966436D02*
G03X892122Y1966434I-1521J-2363D01*
G01X892123Y1962991D02*
G03X895169I1523J2362D01*
G01X892525Y1963263D02*
G03I-2165J0D01*
G01X886443Y1965853D02*
G03X885853Y1965488I-9J-645D01*
G01X887217Y1965045D02*
G03X886443Y1965853I-791J17D01*
G01X885192Y1966558D02*
G03X884349Y1965489I704J-1422D01*
G01X884557Y1963602D02*
G03X885792Y1962629I1735J931D01*
G01X887434Y1962673D02*
G03X888599Y1963811I-728J1911D01*
G01X888512Y1965827D02*
G03X886774Y1966844I-1806J-1093D01*
G01X885792Y1962629D02*
G03X887434Y1962673I755J2475D01*
G01X888773Y1964967D02*
G03X888511Y1965830I-2971J-431D01*
G01X884218Y1965045D02*
G03X884557Y1963602I3015J-53D01*
G01X888773Y1964472D02*
G03Y1964969I-3524J249D01*
G01X888599Y1963811D02*
G03X888773Y1964472I-4018J1411D01*
G01X885792Y1964220D02*
G03X887217I713J-83D01*
G01X886777Y1966844D02*
G03X885192Y1966558I-264J-3073D01*
G01X907801Y1980979D02*
X891423D01*
G01X897446Y1976649D02*
X901777D01*
G01X896821Y1975861D02*
X902402D01*
G01Y1974286D02*
X896821D01*
G01X901777Y1973499D02*
X897446D01*
G01X907801Y1970802D02*
X891423D01*
G01X877958Y1968046D02*
X931895D01*
G01X892663Y1967160D02*
X888056D01*
G01X931895Y1966865D02*
X905517D01*
G01X881248Y1966645D02*
X879699D01*
G01X884192D02*
X882784D01*
G01X890824D02*
X889364D01*
G01X898016D02*
X896623D01*
G01X900906D02*
X899446D01*
G01X903777D02*
X902336D01*
G01X901580Y1966078D02*
X877958D01*
G01X888405Y1965979D02*
X892314D01*
G01X885852Y1965489D02*
X884349D01*
G01X887218Y1965045D02*
X884218D01*
G01X887217Y1964220D02*
X885792D01*
G01X881107Y1962638D02*
X879725D01*
G01X884018D02*
X882402D01*
G01X903777D02*
X902334D01*
G01X901580Y1962298D02*
X877958D01*
G01X890824Y1960891D02*
X889364D01*
G01X881248Y1966645D02*
X881993Y1965367D01*
G01X879699Y1966645D02*
X881020Y1964489D01*
G01X881796Y1963624D02*
X882402Y1962638D01*
G01X882750Y1964498D02*
X884018Y1962638D01*
G01X888405Y1965979D02*
X888387Y1966035D01*
X888335Y1966201D01*
X888256Y1966459D01*
X888161Y1966787D01*
X888056Y1967160D01*
G01X903777Y1966645D02*
Y1962638D01*
G01X902402Y1974286D02*
Y1975861D01*
G01X902368D02*
Y1974286D01*
G01X902343Y1975861D02*
Y1974286D01*
G01X902336Y1964120D02*
Y1966645D01*
G01X902334Y1963194D02*
Y1962638D01*
G01X901580Y1966078D02*
Y1962298D01*
G01X901020Y1974286D02*
Y1975861D01*
G01X900906Y1966645D02*
Y1964120D01*
G01X900650Y1975861D02*
Y1974286D01*
G01X899446Y1964120D02*
Y1966645D01*
G01X898573Y1974286D02*
Y1975861D01*
G01X898203D02*
Y1974286D01*
G01X898016Y1966645D02*
Y1964120D01*
G01X896880Y1974286D02*
Y1975861D01*
G01X896856Y1974286D02*
Y1975861D01*
G01X896821D02*
Y1974286D01*
G01X896623Y1966645D02*
Y1963715D01*
G01X891423Y1980979D02*
Y1968046D01*
G01X890824Y1966645D02*
Y1960891D01*
G01X889364Y1966645D02*
Y1960891D01*
G01X892663Y1967160D02*
X892560Y1966791D01*
X892464Y1966462D01*
X892384Y1966200D01*
X892331Y1966034D01*
X892314Y1965979D01*
G01X882784Y1966645D02*
X881993Y1965367D01*
G01X881020Y1964489D02*
X879725Y1962638D01*
G01X881796Y1963624D02*
X881107Y1962638D01*
G01X884192Y1966645D02*
X882750Y1964498D01*
G01X982289Y149592D02*
G03X1013785I15748J0D01*
G01X982289D02*
G03X1013785I15748J0D01*
G01X982289D02*
G03X1013785I15748J0D01*
G01X1011816Y163371D02*
G03X984257I-13779J0D01*
G01X1013785D02*
G03X982289I-15748J0D01*
G01X1013785D02*
G03X982289I-15748J0D01*
G01X1013785D02*
G03X982289I-15748J0D01*
G01X984257D02*
Y161009D01*
G01X982289Y149592D02*
Y163371D01*
G01Y149592D02*
Y163371D01*
G01Y149592D02*
Y163371D01*
G01X984257Y161009D02*
X992131D01*
G01X931949Y187553D02*
X931894Y187938D01*
G01X931890Y188012D02*
Y195177D01*
G01X936614Y193209D02*
Y191476D01*
G01X931921Y186862D02*
X931979Y187002D01*
X931984Y187242D01*
G01X931921Y186862D02*
X931978Y186996D01*
X931984Y187232D01*
X931948Y187561D01*
G01X936614Y192580D02*
X931894Y187938D01*
G01X936614Y191476D02*
X931890Y186831D01*
G01X925687Y227126D02*
X925815Y227154D01*
X925904Y227226D01*
X925935Y227323D01*
G01X925687Y230276D02*
X925815Y230303D01*
X925904Y230376D01*
X925935Y230472D01*
G01X925687Y233425D02*
X925815Y233453D01*
X925904Y233526D01*
X925935Y233622D01*
G01X925687Y236575D02*
X925815Y236602D01*
X925904Y236675D01*
X925935Y236772D01*
G01X925687Y239724D02*
X925815Y239752D01*
X925904Y239825D01*
X925935Y239921D01*
G01X925687Y242874D02*
X925815Y242902D01*
X925904Y242974D01*
X925935Y243071D01*
G01X925687Y246024D02*
X925815Y246051D01*
X925904Y246124D01*
X925935Y246220D01*
G01X925687Y249173D02*
X925815Y249201D01*
X925904Y249274D01*
X925935Y249370D01*
G01X925687Y252323D02*
X925815Y252350D01*
X925904Y252423D01*
X925935Y252520D01*
G01X925687Y255472D02*
X925815Y255500D01*
X925904Y255573D01*
X925935Y255669D01*
G01X925687Y258622D02*
X925815Y258650D01*
X925904Y258722D01*
X925935Y258819D01*
G01X925687Y261772D02*
X925815Y261799D01*
X925904Y261872D01*
X925935Y261969D01*
G01X925687Y264921D02*
X925815Y264949D01*
X925904Y265022D01*
X925935Y265118D01*
G01X925697Y237856D02*
X925824Y237884D01*
X925913Y237956D01*
X925944Y238053D01*
G01X925697Y241006D02*
X925824Y241033D01*
X925913Y241106D01*
X925944Y241203D01*
G01X925697Y244156D02*
X925824Y244183D01*
X925913Y244256D01*
X925944Y244352D01*
G01X925697Y247305D02*
X925824Y247333D01*
X925913Y247405D01*
X925944Y247502D01*
G01X925697Y250455D02*
X925824Y250482D01*
X925913Y250555D01*
X925944Y250652D01*
G01X925697Y253604D02*
X925824Y253632D01*
X925913Y253704D01*
X925944Y253801D01*
G01X920639Y227913D02*
X920611Y227909D01*
X920586Y227898D01*
X920562Y227880D01*
X920541Y227856D01*
X920524Y227826D01*
X920511Y227792D01*
X920503Y227756D01*
X920500Y227717D01*
G01X920639Y231063D02*
X920611Y231059D01*
X920586Y231048D01*
X920562Y231030D01*
X920541Y231005D01*
X920524Y230976D01*
X920511Y230942D01*
X920503Y230905D01*
X920500Y230866D01*
G01X920639Y234213D02*
X920611Y234209D01*
X920586Y234198D01*
X920562Y234180D01*
X920541Y234155D01*
X920524Y234125D01*
X920511Y234091D01*
X920503Y234055D01*
X920500Y234016D01*
G01X920639Y237362D02*
X920611Y237358D01*
X920586Y237347D01*
X920562Y237329D01*
X920541Y237304D01*
X920524Y237275D01*
X920511Y237241D01*
X920503Y237204D01*
X920500Y237165D01*
G01X920639Y240512D02*
X920611Y240508D01*
X920586Y240497D01*
X920562Y240479D01*
X920541Y240454D01*
X920524Y240424D01*
X920511Y240391D01*
X920503Y240354D01*
X920500Y240315D01*
G01X920639Y243661D02*
X920611Y243657D01*
X920586Y243646D01*
X920562Y243628D01*
X920541Y243604D01*
X920524Y243574D01*
X920511Y243540D01*
X920503Y243504D01*
X920500Y243465D01*
G01X920639Y246811D02*
X920611Y246807D01*
X920586Y246796D01*
X920562Y246778D01*
X920541Y246753D01*
X920524Y246724D01*
X920511Y246690D01*
X920503Y246653D01*
X920500Y246614D01*
G01X920639Y249961D02*
X920611Y249957D01*
X920586Y249946D01*
X920562Y249928D01*
X920541Y249903D01*
X920524Y249873D01*
X920511Y249839D01*
X920503Y249803D01*
X920500Y249764D01*
G01X920639Y253110D02*
X920611Y253106D01*
X920586Y253095D01*
X920562Y253077D01*
X920541Y253052D01*
X920524Y253023D01*
X920511Y252989D01*
X920503Y252952D01*
X920500Y252913D01*
G01X920639Y256260D02*
X920611Y256256D01*
X920586Y256245D01*
X920562Y256227D01*
X920541Y256202D01*
X920524Y256172D01*
X920511Y256139D01*
X920503Y256102D01*
X920500Y256063D01*
G01X920639Y259409D02*
X920611Y259406D01*
X920586Y259394D01*
X920562Y259376D01*
X920541Y259352D01*
X920524Y259322D01*
X920511Y259288D01*
X920503Y259252D01*
X920500Y259213D01*
G01X920639Y262559D02*
X920611Y262555D01*
X920586Y262544D01*
X920562Y262526D01*
X920541Y262501D01*
X920524Y262472D01*
X920511Y262438D01*
X920503Y262401D01*
X920500Y262362D01*
G01X925687Y227126D02*
X919603D01*
G01X925935Y227323D02*
X919323D01*
G01Y227717D02*
X925935D01*
G01X925687Y227913D02*
X919603D01*
G01X925657Y228130D02*
X919912D01*
G01X919485Y228720D02*
X926071D01*
G01X919485Y229114D02*
X926071D01*
G01X925657Y229705D02*
X919912D01*
G01X925687Y230276D02*
X919603D01*
G01X925935Y230472D02*
X919323D01*
G01Y230866D02*
X925935D01*
G01X925687Y231063D02*
X919603D01*
G01X925757Y233130D02*
X919844D01*
G01X925687Y233425D02*
X919603D01*
G01X925935Y233622D02*
X919323D01*
G01X919420Y233720D02*
X926162D01*
G01X919323Y234016D02*
X925935D01*
G01X919420Y234114D02*
X926162D01*
G01X925687Y234213D02*
X919603D01*
G01X925757Y234705D02*
X919844D01*
G01X929921Y235492D02*
X923452D01*
G01X925687Y236575D02*
X919603D01*
G01X925935Y236772D02*
X919323D01*
G01Y237165D02*
X925935D01*
G01X925687Y237362D02*
X919603D01*
G01X919889Y237856D02*
X925697D01*
G01X919626Y238053D02*
X925944D01*
G01Y239037D02*
X919626D01*
G01X919889Y239234D02*
X925697D01*
G01X925687Y239724D02*
X919603D01*
G01X925935Y239921D02*
X919323D01*
G01Y240315D02*
X925935D01*
G01X925687Y240512D02*
X919603D01*
G01X919889Y241006D02*
X925697D01*
G01X919626Y241203D02*
X925944D01*
G01Y242187D02*
X919626D01*
G01X919889Y242384D02*
X925697D01*
G01X925687Y242874D02*
X919603D01*
G01X925935Y243071D02*
X919323D01*
G01Y243465D02*
X925935D01*
G01X925687Y243661D02*
X919603D01*
G01X919889Y244156D02*
X925697D01*
G01X919626Y244352D02*
X925944D01*
G01Y245337D02*
X919626D01*
G01X919889Y245533D02*
X925697D01*
G01X925687Y246024D02*
X919603D01*
G01X925935Y246220D02*
X919323D01*
G01Y246614D02*
X925935D01*
G01X925687Y246811D02*
X919603D01*
G01X919889Y247305D02*
X925697D01*
G01X919626Y247502D02*
X925944D01*
G01Y248486D02*
X919626D01*
G01X919889Y248683D02*
X925697D01*
G01X925687Y249173D02*
X919603D01*
G01X925935Y249370D02*
X919323D01*
G01Y249764D02*
X925935D01*
G01X925687Y249961D02*
X919603D01*
G01X919889Y250455D02*
X925697D01*
G01X919626Y250652D02*
X925944D01*
G01Y251636D02*
X919626D01*
G01X919889Y251833D02*
X925697D01*
G01X925687Y252323D02*
X919603D01*
G01X925935Y252520D02*
X919323D01*
G01Y252913D02*
X925935D01*
G01X925687Y253110D02*
X919603D01*
G01X919889Y253604D02*
X925697D01*
G01X919626Y253801D02*
X925944D01*
G01Y254785D02*
X919626D01*
G01X919889Y254982D02*
X925697D01*
G01X925687Y255472D02*
X919603D01*
G01X925935Y255669D02*
X919323D01*
G01Y256063D02*
X925935D01*
G01X925687Y256260D02*
X919603D01*
G01X923452Y257343D02*
X929921D01*
G01X925757Y258130D02*
X919844D01*
G01X925687Y258622D02*
X919603D01*
G01X919420Y258720D02*
X926162D01*
G01X925935Y258819D02*
X919323D01*
G01X919420Y259114D02*
X926162D01*
G01X919323Y259213D02*
X925935D01*
G01X925687Y259409D02*
X919603D01*
G01X925757Y259705D02*
X919844D01*
G01X925687Y261772D02*
X919603D01*
G01X925935Y261969D02*
X919323D01*
G01Y262362D02*
X925935D01*
G01X925687Y262559D02*
X919603D01*
G01X925657Y263130D02*
X919912D01*
G01X919485Y263720D02*
X926071D01*
G01X919485Y264114D02*
X926071D01*
G01X925657Y264705D02*
X919912D01*
G01X925687Y264921D02*
X919603D01*
G01X925935Y265118D02*
X919323D01*
G01X920717Y237856D02*
X920688Y237860D01*
X920660Y237871D01*
X920635Y237889D01*
X920612Y237914D01*
X920594Y237944D01*
X920580Y237978D01*
X920572Y238014D01*
X920569Y238053D01*
G01X920717Y241006D02*
X920688Y241010D01*
X920660Y241021D01*
X920635Y241039D01*
X920612Y241064D01*
X920594Y241093D01*
X920580Y241127D01*
X920572Y241164D01*
X920569Y241203D01*
G01X920717Y244156D02*
X920688Y244159D01*
X920660Y244170D01*
X920635Y244189D01*
X920612Y244213D01*
X920594Y244243D01*
X920580Y244277D01*
X920572Y244313D01*
X920569Y244352D01*
G01X920717Y247305D02*
X920688Y247309D01*
X920660Y247320D01*
X920635Y247338D01*
X920612Y247363D01*
X920594Y247393D01*
X920580Y247426D01*
X920572Y247463D01*
X920569Y247502D01*
G01X920717Y250455D02*
X920688Y250459D01*
X920660Y250470D01*
X920635Y250488D01*
X920612Y250513D01*
X920594Y250542D01*
X920580Y250576D01*
X920572Y250613D01*
X920569Y250652D01*
G01X920717Y253604D02*
X920688Y253608D01*
X920660Y253619D01*
X920635Y253637D01*
X920612Y253662D01*
X920594Y253692D01*
X920580Y253726D01*
X920572Y253762D01*
X920569Y253801D01*
G01X921753Y237856D02*
X921747Y237860D01*
X921741Y237871D01*
X921735Y237889D01*
X921730Y237914D01*
X921726Y237944D01*
X921723Y237978D01*
X921721Y238014D01*
X921720Y238053D01*
G01X921753Y241006D02*
X921747Y241010D01*
X921741Y241021D01*
X921735Y241039D01*
X921730Y241064D01*
X921726Y241093D01*
X921723Y241127D01*
X921721Y241164D01*
X921720Y241203D01*
G01X921753Y244156D02*
X921747Y244159D01*
X921741Y244170D01*
X921735Y244189D01*
X921730Y244213D01*
X921726Y244243D01*
X921723Y244277D01*
X921721Y244313D01*
X921720Y244352D01*
G01X921753Y247305D02*
X921747Y247309D01*
X921741Y247320D01*
X921735Y247338D01*
X921730Y247363D01*
X921726Y247393D01*
X921723Y247426D01*
X921721Y247463D01*
X921720Y247502D01*
G01X921753Y250455D02*
X921747Y250459D01*
X921741Y250470D01*
X921735Y250488D01*
X921730Y250513D01*
X921726Y250542D01*
X921723Y250576D01*
X921721Y250613D01*
X921720Y250652D01*
G01X921753Y253604D02*
X921747Y253608D01*
X921741Y253619D01*
X921735Y253637D01*
X921730Y253662D01*
X921726Y253692D01*
X921723Y253726D01*
X921721Y253762D01*
X921720Y253801D01*
G01X921090Y227126D02*
X921051Y227152D01*
X921023Y227224D01*
X921013Y227323D01*
G01X921090Y230276D02*
X921051Y230302D01*
X921023Y230374D01*
X921013Y230472D01*
G01X921090Y233425D02*
X921051Y233452D01*
X921023Y233524D01*
X921013Y233622D01*
G01X921090Y236575D02*
X921051Y236601D01*
X921023Y236673D01*
X921013Y236772D01*
G01X921090Y239724D02*
X921051Y239751D01*
X921023Y239823D01*
X921013Y239921D01*
G01X921090Y242874D02*
X921051Y242900D01*
X921023Y242972D01*
X921013Y243071D01*
G01X921090Y246024D02*
X921051Y246050D01*
X921023Y246122D01*
X921013Y246220D01*
G01X921090Y249173D02*
X921051Y249200D01*
X921023Y249272D01*
X921013Y249370D01*
G01X921090Y252323D02*
X921051Y252349D01*
X921023Y252421D01*
X921013Y252520D01*
G01X921090Y255472D02*
X921051Y255499D01*
X921023Y255571D01*
X921013Y255669D01*
G01X921090Y258622D02*
X921051Y258648D01*
X921023Y258720D01*
X921013Y258819D01*
G01X921090Y261772D02*
X921051Y261798D01*
X921023Y261870D01*
X921013Y261969D01*
G01X921090Y264921D02*
X921051Y264948D01*
X921023Y265020D01*
X921013Y265118D01*
G01X927953Y236654D02*
X929921Y234685D01*
G01X919912Y228130D02*
X919485Y228720D01*
G01X919912Y263130D02*
X919485Y263720D01*
G01X919844Y233130D02*
X919420Y233720D01*
G01X919844Y258130D02*
X919420Y258720D01*
G01X926071Y229114D02*
X925934Y229312D01*
X925796Y229509D01*
X925657Y229705D01*
G01X926071Y264114D02*
X925934Y264312D01*
X925796Y264509D01*
X925657Y264705D01*
G01X926162Y234114D02*
X926028Y234311D01*
X925893Y234508D01*
X925757Y234705D01*
G01X926162Y259114D02*
X926028Y259311D01*
X925893Y259508D01*
X925757Y259705D01*
G01X920602Y228130D02*
X920329Y228720D01*
G01X920602Y233130D02*
X920329Y233720D01*
G01X920602Y258130D02*
X920329Y258720D01*
G01X920602Y263130D02*
X920329Y263720D01*
G01X925944Y239037D02*
X925911Y239137D01*
X925823Y239207D01*
X925697Y239234D01*
G01X925944Y242187D02*
X925911Y242286D01*
X925823Y242357D01*
X925697Y242384D01*
G01X925944Y245337D02*
X925911Y245436D01*
X925823Y245507D01*
X925697Y245533D01*
G01X925944Y248486D02*
X925911Y248585D01*
X925823Y248656D01*
X925697Y248683D01*
G01X925944Y251636D02*
X925911Y251735D01*
X925823Y251806D01*
X925697Y251833D01*
G01X925944Y254785D02*
X925911Y254885D01*
X925823Y254956D01*
X925697Y254982D01*
G01X925935Y227717D02*
X925903Y227813D01*
X925815Y227885D01*
X925687Y227913D01*
G01X925935Y230866D02*
X925903Y230963D01*
X925815Y231035D01*
X925687Y231063D01*
G01X925935Y234016D02*
X925903Y234113D01*
X925815Y234185D01*
X925687Y234213D01*
G01X925935Y237165D02*
X925903Y237262D01*
X925815Y237334D01*
X925687Y237362D01*
G01X925935Y240315D02*
X925903Y240412D01*
X925815Y240484D01*
X925687Y240512D01*
G01X925935Y243465D02*
X925903Y243561D01*
X925815Y243633D01*
X925687Y243661D01*
G01X925935Y246614D02*
X925903Y246711D01*
X925815Y246783D01*
X925687Y246811D01*
G01X925935Y249764D02*
X925903Y249861D01*
X925815Y249933D01*
X925687Y249961D01*
G01X925935Y252913D02*
X925903Y253010D01*
X925815Y253082D01*
X925687Y253110D01*
G01X925935Y256063D02*
X925903Y256160D01*
X925815Y256232D01*
X925687Y256260D01*
G01X925935Y259213D02*
X925903Y259309D01*
X925815Y259381D01*
X925687Y259409D01*
G01X925935Y262362D02*
X925903Y262459D01*
X925815Y262531D01*
X925687Y262559D01*
G01X921454Y228720D02*
X921531Y228130D01*
G01X921454Y233720D02*
X921531Y233130D01*
G01X921454Y258720D02*
X921531Y258130D01*
G01X921454Y263720D02*
X921531Y263130D01*
G01X920500Y227323D02*
X920503Y227285D01*
X920511Y227248D01*
X920523Y227214D01*
X920541Y227183D01*
X920561Y227159D01*
X920585Y227141D01*
X920611Y227130D01*
X920639Y227126D01*
G01X920500Y230472D02*
X920503Y230434D01*
X920511Y230397D01*
X920523Y230363D01*
X920541Y230333D01*
X920561Y230309D01*
X920585Y230291D01*
X920611Y230280D01*
X920639Y230276D01*
G01X920500Y233622D02*
X920503Y233584D01*
X920511Y233547D01*
X920523Y233513D01*
X920541Y233483D01*
X920561Y233458D01*
X920585Y233440D01*
X920611Y233429D01*
X920639Y233425D01*
G01X920500Y236772D02*
X920503Y236733D01*
X920511Y236696D01*
X920523Y236663D01*
X920541Y236632D01*
X920561Y236608D01*
X920585Y236590D01*
X920611Y236579D01*
X920639Y236575D01*
G01X920500Y239921D02*
X920503Y239883D01*
X920511Y239846D01*
X920523Y239812D01*
X920541Y239782D01*
X920561Y239757D01*
X920585Y239739D01*
X920611Y239728D01*
X920639Y239724D01*
G01X920500Y243071D02*
X920503Y243033D01*
X920511Y242996D01*
X920523Y242962D01*
X920541Y242931D01*
X920561Y242907D01*
X920585Y242889D01*
X920611Y242878D01*
X920639Y242874D01*
G01X920500Y246220D02*
X920503Y246182D01*
X920511Y246145D01*
X920523Y246111D01*
X920541Y246081D01*
X920561Y246057D01*
X920585Y246039D01*
X920611Y246028D01*
X920639Y246024D01*
G01X920500Y249370D02*
X920503Y249332D01*
X920511Y249295D01*
X920523Y249261D01*
X920541Y249231D01*
X920561Y249206D01*
X920585Y249188D01*
X920611Y249177D01*
X920639Y249173D01*
G01X920500Y252520D02*
X920503Y252481D01*
X920511Y252444D01*
X920523Y252411D01*
X920541Y252380D01*
X920561Y252356D01*
X920585Y252338D01*
X920611Y252327D01*
X920639Y252323D01*
G01X920500Y255669D02*
X920503Y255631D01*
X920511Y255594D01*
X920523Y255560D01*
X920541Y255530D01*
X920561Y255506D01*
X920585Y255487D01*
X920611Y255476D01*
X920639Y255472D01*
G01X920500Y258819D02*
X920503Y258781D01*
X920511Y258744D01*
X920523Y258710D01*
X920541Y258680D01*
X920561Y258655D01*
X920585Y258637D01*
X920611Y258626D01*
X920639Y258622D01*
G01X920500Y261969D02*
X920503Y261930D01*
X920511Y261893D01*
X920523Y261859D01*
X920541Y261829D01*
X920561Y261805D01*
X920585Y261787D01*
X920611Y261776D01*
X920639Y261772D01*
G01X920500Y265118D02*
X920503Y265080D01*
X920511Y265043D01*
X920523Y265009D01*
X920541Y264979D01*
X920561Y264954D01*
X920585Y264936D01*
X920611Y264925D01*
X920639Y264921D01*
G01X919323Y265512D02*
Y265118D01*
G01Y262362D02*
Y261969D01*
G01Y259213D02*
Y258819D01*
G01Y256063D02*
Y255669D01*
G01Y252913D02*
Y252520D01*
G01Y249764D02*
Y249370D01*
G01Y246614D02*
Y246220D01*
G01Y243465D02*
Y243071D01*
G01Y240315D02*
Y239921D01*
G01Y237165D02*
Y236772D01*
G01Y230866D02*
Y230472D01*
G01Y234016D02*
Y233622D01*
G01Y227717D02*
Y227323D01*
G01X919420Y233720D02*
Y234114D01*
G01Y258720D02*
Y259114D01*
G01X919485Y228720D02*
Y229114D01*
G01Y263720D02*
Y264114D01*
G01X919626Y238053D02*
Y239037D01*
G01Y241203D02*
Y242187D01*
G01Y247502D02*
Y248486D01*
G01Y244352D02*
Y245337D01*
G01Y250652D02*
Y251636D01*
G01Y253801D02*
Y254785D01*
G01X920329Y228720D02*
Y229114D01*
G01Y233720D02*
Y234114D01*
G01Y258720D02*
Y259114D01*
G01Y263720D02*
Y264114D01*
G01X920500Y265512D02*
Y265118D01*
G01Y262362D02*
Y261969D01*
G01Y259213D02*
Y258819D01*
G01Y256063D02*
Y255669D01*
G01Y252913D02*
Y252520D01*
G01Y249764D02*
Y249370D01*
G01Y246614D02*
Y246220D01*
G01Y243465D02*
Y243071D01*
G01Y240315D02*
Y239921D01*
G01Y237165D02*
Y236772D01*
G01Y230866D02*
Y230472D01*
G01Y234016D02*
Y233622D01*
G01Y227717D02*
Y227323D01*
G01X920569Y238053D02*
Y239037D01*
G01Y241203D02*
Y242187D01*
G01Y247502D02*
Y248486D01*
G01Y244352D02*
Y245337D01*
G01Y250652D02*
Y251636D01*
G01Y253801D02*
Y254785D01*
G01X921013Y227323D02*
Y227717D01*
G01Y230472D02*
Y230866D01*
G01Y233622D02*
Y234016D01*
G01Y236772D02*
Y237165D01*
G01Y243071D02*
Y243465D01*
G01Y239921D02*
Y240315D01*
G01Y246220D02*
Y246614D01*
G01Y252520D02*
Y252913D01*
G01Y249370D02*
Y249764D01*
G01Y255669D02*
Y256063D01*
G01Y261969D02*
Y262362D01*
G01Y258819D02*
Y259213D01*
G01Y265118D02*
Y265512D01*
G01X921454Y264114D02*
Y263720D01*
G01Y259114D02*
Y258720D01*
G01Y234114D02*
Y233720D01*
G01Y229114D02*
Y228720D01*
G01X921720Y238053D02*
Y239037D01*
G01Y241203D02*
Y242187D01*
G01Y247502D02*
Y248486D01*
G01Y244352D02*
Y245337D01*
G01Y250652D02*
Y251636D01*
G01Y253801D02*
Y254785D01*
G01X923452Y257343D02*
Y256161D01*
G01Y236673D02*
Y235492D01*
G01X925935Y227323D02*
Y227717D01*
G01Y230472D02*
Y230866D01*
G01Y233622D02*
Y234016D01*
G01Y236772D02*
Y237165D01*
G01Y243071D02*
Y243465D01*
G01Y239921D02*
Y240315D01*
G01Y246220D02*
Y246614D01*
G01Y252520D02*
Y252913D01*
G01Y249370D02*
Y249764D01*
G01Y255669D02*
Y256063D01*
G01Y261969D02*
Y262362D01*
G01Y258819D02*
Y259213D01*
G01Y265118D02*
Y265512D01*
G01X925944Y254785D02*
Y253801D01*
G01Y251636D02*
Y250652D01*
G01Y248486D02*
Y247502D01*
G01Y245337D02*
Y244352D01*
G01Y242187D02*
Y241203D01*
G01Y239037D02*
Y238053D01*
G01X926071Y264114D02*
Y263720D01*
G01Y229114D02*
Y228720D01*
G01X926162Y259114D02*
Y258720D01*
G01Y234114D02*
Y233720D01*
G01X928740Y333524D02*
Y262618D01*
G01Y235492D02*
Y257343D01*
G01X928910Y262618D02*
Y257138D01*
G01Y235696D02*
Y230315D01*
G01X921720Y254785D02*
X921721Y254824D01*
X921723Y254861D01*
X921726Y254894D01*
X921730Y254925D01*
X921735Y254949D01*
X921741Y254967D01*
X921747Y254978D01*
X921753Y254982D01*
G01X921720Y251636D02*
X921721Y251674D01*
X921723Y251711D01*
X921726Y251745D01*
X921730Y251775D01*
X921735Y251800D01*
X921741Y251818D01*
X921747Y251829D01*
X921753Y251833D01*
G01X921720Y248486D02*
X921721Y248524D01*
X921723Y248561D01*
X921726Y248595D01*
X921730Y248626D01*
X921735Y248650D01*
X921741Y248668D01*
X921747Y248679D01*
X921753Y248683D01*
G01X921720Y245337D02*
X921721Y245375D01*
X921723Y245412D01*
X921726Y245446D01*
X921730Y245476D01*
X921735Y245500D01*
X921741Y245519D01*
X921747Y245530D01*
X921753Y245533D01*
G01X921720Y242187D02*
X921721Y242225D01*
X921723Y242262D01*
X921726Y242296D01*
X921730Y242326D01*
X921735Y242351D01*
X921741Y242369D01*
X921747Y242380D01*
X921753Y242384D01*
G01X921720Y239037D02*
X921721Y239076D01*
X921723Y239113D01*
X921726Y239146D01*
X921730Y239177D01*
X921735Y239201D01*
X921741Y239219D01*
X921747Y239230D01*
X921753Y239234D01*
G01X920569Y254785D02*
X920571Y254824D01*
X920580Y254861D01*
X920593Y254894D01*
X920612Y254925D01*
X920634Y254949D01*
X920659Y254967D01*
X920687Y254978D01*
X920717Y254982D01*
G01X920569Y251636D02*
X920571Y251674D01*
X920580Y251711D01*
X920593Y251745D01*
X920612Y251775D01*
X920634Y251800D01*
X920659Y251818D01*
X920687Y251829D01*
X920717Y251833D01*
G01X920569Y248486D02*
X920571Y248524D01*
X920580Y248561D01*
X920593Y248595D01*
X920612Y248626D01*
X920634Y248650D01*
X920659Y248668D01*
X920687Y248679D01*
X920717Y248683D01*
G01X920569Y245337D02*
X920571Y245375D01*
X920580Y245412D01*
X920593Y245446D01*
X920612Y245476D01*
X920634Y245500D01*
X920659Y245519D01*
X920687Y245530D01*
X920717Y245533D01*
G01X920569Y242187D02*
X920571Y242225D01*
X920580Y242262D01*
X920593Y242296D01*
X920612Y242326D01*
X920634Y242351D01*
X920659Y242369D01*
X920687Y242380D01*
X920717Y242384D01*
G01X920569Y239037D02*
X920571Y239076D01*
X920580Y239113D01*
X920593Y239146D01*
X920612Y239177D01*
X920634Y239201D01*
X920659Y239219D01*
X920687Y239230D01*
X920717Y239234D01*
G01X921013Y262362D02*
X921023Y262461D01*
X921051Y262533D01*
X921090Y262559D01*
G01X921013Y259213D02*
X921023Y259311D01*
X921051Y259383D01*
X921090Y259409D01*
G01X921013Y256063D02*
X921023Y256161D01*
X921051Y256233D01*
X921090Y256260D01*
G01X921013Y252913D02*
X921023Y253012D01*
X921051Y253084D01*
X921090Y253110D01*
G01X921013Y246614D02*
X921023Y246713D01*
X921051Y246785D01*
X921090Y246811D01*
G01X921013Y243465D02*
X921023Y243563D01*
X921051Y243635D01*
X921090Y243661D01*
G01X921013Y240315D02*
X921023Y240413D01*
X921051Y240485D01*
X921090Y240512D01*
G01X921013Y237165D02*
X921023Y237264D01*
X921051Y237336D01*
X921090Y237362D01*
G01X921013Y227717D02*
X921023Y227815D01*
X921051Y227887D01*
X921090Y227913D01*
G01X921454Y264114D02*
X921531Y264705D01*
G01X921454Y259114D02*
X921531Y259705D01*
G01X921454Y234114D02*
X921531Y234705D01*
G01X921454Y229114D02*
X921531Y229705D01*
G01X920329Y264114D02*
X920602Y264705D01*
G01X920329Y259114D02*
X920602Y259705D01*
G01X920329Y234114D02*
X920602Y234705D01*
G01X920329Y229114D02*
X920602Y229705D01*
G01X925757Y258130D02*
X925893Y258326D01*
X926028Y258523D01*
X926162Y258720D01*
G01X925757Y233130D02*
X925893Y233326D01*
X926028Y233523D01*
X926162Y233720D01*
G01X925657Y263130D02*
X925796Y263326D01*
X925934Y263523D01*
X926071Y263720D01*
G01X919844Y259705D02*
X919420Y259114D01*
G01X919912Y264705D02*
X919485Y264114D01*
G01X925657Y228130D02*
X925796Y228326D01*
X925934Y228523D01*
X926071Y228720D01*
G01X919844Y234705D02*
X919420Y234114D01*
G01X919912Y229705D02*
X919485Y229114D01*
G01X929921Y258150D02*
X927953Y256181D01*
G01X921090Y249961D02*
X921051Y249934D01*
X921023Y249862D01*
X921013Y249764D01*
G01X921090Y234213D02*
X921051Y234186D01*
X921023Y234114D01*
X921013Y234016D01*
G01X921090Y231063D02*
X921051Y231037D01*
X921023Y230964D01*
X921013Y230866D01*
G01X920639Y265709D02*
X920611Y265705D01*
X920586Y265694D01*
X920562Y265676D01*
X920541Y265651D01*
X920524Y265621D01*
X920511Y265587D01*
X920503Y265551D01*
X920500Y265512D01*
G01X919323D02*
X925935D01*
G01X925687Y265709D02*
X919603D01*
G01X925935Y265512D02*
X925903Y265609D01*
X925815Y265681D01*
X925687Y265709D01*
G01X921013Y265512D02*
X921023Y265610D01*
X921051Y265682D01*
X921090Y265709D01*
G01X925687Y205079D02*
X925815Y205106D01*
X925904Y205179D01*
X925935Y205276D01*
G01X925687Y208228D02*
X925815Y208256D01*
X925904Y208329D01*
X925935Y208425D01*
G01X925687Y211378D02*
X925815Y211406D01*
X925904Y211478D01*
X925935Y211575D01*
G01X925687Y214528D02*
X925815Y214555D01*
X925904Y214628D01*
X925935Y214724D01*
G01X925687Y217677D02*
X925815Y217705D01*
X925904Y217778D01*
X925935Y217874D01*
G01X925687Y220827D02*
X925815Y220854D01*
X925904Y220927D01*
X925935Y221024D01*
G01X925687Y223976D02*
X925815Y224004D01*
X925904Y224077D01*
X925935Y224173D01*
G01X920639Y205866D02*
X920611Y205862D01*
X920586Y205851D01*
X920562Y205833D01*
X920541Y205808D01*
X920524Y205779D01*
X920511Y205745D01*
X920503Y205708D01*
X920500Y205669D01*
G01X920639Y209016D02*
X920611Y209012D01*
X920586Y209001D01*
X920562Y208983D01*
X920541Y208958D01*
X920524Y208928D01*
X920511Y208894D01*
X920503Y208858D01*
X920500Y208819D01*
G01X920639Y212165D02*
X920611Y212161D01*
X920586Y212150D01*
X920562Y212132D01*
X920541Y212107D01*
X920524Y212078D01*
X920511Y212044D01*
X920503Y212007D01*
X920500Y211969D01*
G01X920639Y215315D02*
X920611Y215311D01*
X920586Y215300D01*
X920562Y215282D01*
X920541Y215257D01*
X920524Y215228D01*
X920511Y215194D01*
X920503Y215157D01*
X920500Y215118D01*
G01X920639Y218465D02*
X920611Y218461D01*
X920586Y218450D01*
X920562Y218431D01*
X920541Y218407D01*
X920524Y218377D01*
X920511Y218343D01*
X920503Y218307D01*
X920500Y218268D01*
G01X920639Y221614D02*
X920611Y221610D01*
X920586Y221599D01*
X920562Y221581D01*
X920541Y221556D01*
X920524Y221527D01*
X920511Y221493D01*
X920503Y221456D01*
X920500Y221417D01*
G01X920639Y224764D02*
X920611Y224760D01*
X920586Y224749D01*
X920562Y224731D01*
X920541Y224706D01*
X920524Y224676D01*
X920511Y224643D01*
X920503Y224606D01*
X920500Y224567D01*
G01X933204Y195177D02*
X929921D01*
G01X925657Y203130D02*
X919912D01*
G01X919485Y203720D02*
X926071D01*
G01X919485Y204114D02*
X926071D01*
G01X925657Y204705D02*
X919912D01*
G01X925687Y205079D02*
X919603D01*
G01X925935Y205276D02*
X919323D01*
G01Y205669D02*
X925935D01*
G01X925687Y205866D02*
X919603D01*
G01X925657Y208130D02*
X919912D01*
G01X925687Y208228D02*
X919603D01*
G01X925935Y208425D02*
X919323D01*
G01X919485Y208720D02*
X926071D01*
G01X919323Y208819D02*
X925935D01*
G01X925687Y209016D02*
X919603D01*
G01X919485Y209114D02*
X926071D01*
G01X925657Y209705D02*
X919912D01*
G01X925687Y211378D02*
X919603D01*
G01X925935Y211575D02*
X919323D01*
G01Y211969D02*
X925935D01*
G01X925687Y212165D02*
X919603D01*
G01X925657Y213130D02*
X919912D01*
G01X919485Y213720D02*
X926071D01*
G01X919485Y214114D02*
X926071D01*
G01X925687Y214528D02*
X919603D01*
G01X925657Y214705D02*
X919912D01*
G01X925935Y214724D02*
X919323D01*
G01Y215118D02*
X925935D01*
G01X925687Y215315D02*
X919603D01*
G01X925687Y217677D02*
X919603D01*
G01X925935Y217874D02*
X919323D01*
G01X925657Y218130D02*
X919912D01*
G01X919323Y218268D02*
X925935D01*
G01X925687Y218465D02*
X919603D01*
G01X919485Y218720D02*
X926071D01*
G01X919485Y219114D02*
X926071D01*
G01X925657Y219705D02*
X919912D01*
G01X925687Y220827D02*
X919603D01*
G01X925935Y221024D02*
X919323D01*
G01Y221417D02*
X925935D01*
G01X925687Y221614D02*
X919603D01*
G01X925657Y223130D02*
X919912D01*
G01X919485Y223720D02*
X926071D01*
G01X925687Y223976D02*
X919603D01*
G01X919485Y224114D02*
X926071D01*
G01X925935Y224173D02*
X919323D01*
G01Y224567D02*
X925935D01*
G01X925657Y224705D02*
X919912D01*
G01X925687Y224764D02*
X919603D01*
G01X933204Y195177D02*
X936614Y193209D01*
G01X921090Y205079D02*
X921051Y205105D01*
X921023Y205177D01*
X921013Y205276D01*
G01X921090Y208228D02*
X921051Y208255D01*
X921023Y208327D01*
X921013Y208425D01*
G01X921090Y211378D02*
X921051Y211404D01*
X921023Y211476D01*
X921013Y211575D01*
G01X921090Y214528D02*
X921051Y214554D01*
X921023Y214626D01*
X921013Y214724D01*
G01X921090Y217677D02*
X921051Y217704D01*
X921023Y217776D01*
X921013Y217874D01*
G01X921090Y220827D02*
X921051Y220853D01*
X921023Y220925D01*
X921013Y221024D01*
G01X921090Y223976D02*
X921051Y224003D01*
X921023Y224075D01*
X921013Y224173D01*
G01X929921Y198130D02*
X927953Y200098D01*
G01X919912Y203130D02*
X919485Y203720D01*
G01X919912Y208130D02*
X919485Y208720D01*
G01X919912Y213130D02*
X919485Y213720D01*
G01X919912Y218130D02*
X919485Y218720D01*
G01X919912Y223130D02*
X919485Y223720D01*
G01X926071Y204114D02*
X925934Y204312D01*
X925796Y204509D01*
X925657Y204705D01*
G01X926071Y209114D02*
X925934Y209312D01*
X925796Y209509D01*
X925657Y209705D01*
G01X926071Y214114D02*
X925934Y214312D01*
X925796Y214509D01*
X925657Y214705D01*
G01X926071Y219114D02*
X925934Y219312D01*
X925796Y219509D01*
X925657Y219705D01*
G01X926071Y224114D02*
X925934Y224312D01*
X925796Y224509D01*
X925657Y224705D01*
G01X920602Y203130D02*
X920329Y203720D01*
G01X920602Y208130D02*
X920329Y208720D01*
G01X920602Y213130D02*
X920329Y213720D01*
G01X920602Y218130D02*
X920329Y218720D01*
G01X920602Y223130D02*
X920329Y223720D01*
G01X925935Y205669D02*
X925903Y205766D01*
X925815Y205838D01*
X925687Y205866D01*
G01X925935Y208819D02*
X925903Y208916D01*
X925815Y208988D01*
X925687Y209016D01*
G01X925935Y211969D02*
X925903Y212065D01*
X925815Y212137D01*
X925687Y212165D01*
G01X925935Y215118D02*
X925903Y215215D01*
X925815Y215287D01*
X925687Y215315D01*
G01X925935Y218268D02*
X925903Y218365D01*
X925815Y218437D01*
X925687Y218465D01*
G01X925935Y221417D02*
X925903Y221514D01*
X925815Y221586D01*
X925687Y221614D01*
G01X925935Y224567D02*
X925903Y224664D01*
X925815Y224736D01*
X925687Y224764D01*
G01X921454Y203720D02*
X921531Y203130D01*
G01X921454Y208720D02*
X921531Y208130D01*
G01X921454Y213720D02*
X921531Y213130D01*
G01X921454Y218720D02*
X921531Y218130D01*
G01X921454Y223720D02*
X921531Y223130D01*
G01X920500Y205276D02*
X920503Y205237D01*
X920511Y205200D01*
X920523Y205167D01*
X920541Y205136D01*
X920561Y205112D01*
X920585Y205094D01*
X920611Y205083D01*
X920639Y205079D01*
G01X920500Y208425D02*
X920503Y208387D01*
X920511Y208350D01*
X920523Y208316D01*
X920541Y208286D01*
X920561Y208261D01*
X920585Y208243D01*
X920611Y208232D01*
X920639Y208228D01*
G01X920500Y211575D02*
X920503Y211537D01*
X920511Y211500D01*
X920523Y211466D01*
X920541Y211435D01*
X920561Y211411D01*
X920585Y211393D01*
X920611Y211382D01*
X920639Y211378D01*
G01X920500Y214724D02*
X920503Y214686D01*
X920511Y214649D01*
X920523Y214615D01*
X920541Y214585D01*
X920561Y214561D01*
X920585Y214543D01*
X920611Y214531D01*
X920639Y214528D01*
G01X920500Y217874D02*
X920503Y217836D01*
X920511Y217799D01*
X920523Y217765D01*
X920541Y217735D01*
X920561Y217710D01*
X920585Y217692D01*
X920611Y217681D01*
X920639Y217677D01*
G01X920500Y221024D02*
X920503Y220985D01*
X920511Y220948D01*
X920523Y220915D01*
X920541Y220884D01*
X920561Y220860D01*
X920585Y220842D01*
X920611Y220831D01*
X920639Y220827D01*
G01X920500Y224173D02*
X920503Y224135D01*
X920511Y224098D01*
X920523Y224064D01*
X920541Y224034D01*
X920561Y224009D01*
X920585Y223991D01*
X920611Y223980D01*
X920639Y223976D01*
G01X919323Y221417D02*
Y221024D01*
G01Y224567D02*
Y224173D01*
G01Y218268D02*
Y217874D01*
G01Y211969D02*
Y211575D01*
G01Y215118D02*
Y214724D01*
G01Y208819D02*
Y208425D01*
G01Y205669D02*
Y205276D01*
G01X919485Y203720D02*
Y204114D01*
G01Y208720D02*
Y209114D01*
G01Y213720D02*
Y214114D01*
G01Y218720D02*
Y219114D01*
G01Y223720D02*
Y224114D01*
G01X920329Y203720D02*
Y204114D01*
G01Y208720D02*
Y209114D01*
G01Y213720D02*
Y214114D01*
G01Y218720D02*
Y219114D01*
G01Y223720D02*
Y224114D01*
G01X920500Y221417D02*
Y221024D01*
G01Y224567D02*
Y224173D01*
G01Y218268D02*
Y217874D01*
G01Y211969D02*
Y211575D01*
G01Y215118D02*
Y214724D01*
G01Y208819D02*
Y208425D01*
G01Y205669D02*
Y205276D01*
G01X921013D02*
Y205669D01*
G01Y208425D02*
Y208819D01*
G01Y211575D02*
Y211969D01*
G01Y214724D02*
Y215118D01*
G01Y217874D02*
Y218268D01*
G01Y221024D02*
Y221417D01*
G01Y224173D02*
Y224567D01*
G01X921454Y224114D02*
Y223720D01*
G01Y219114D02*
Y218720D01*
G01Y214114D02*
Y213720D01*
G01Y209114D02*
Y208720D01*
G01Y204114D02*
Y203720D01*
G01X925935Y205276D02*
Y205669D01*
G01Y208425D02*
Y208819D01*
G01Y211575D02*
Y211969D01*
G01Y214724D02*
Y215118D01*
G01Y217874D02*
Y218268D01*
G01Y221024D02*
Y221417D01*
G01Y224173D02*
Y224567D01*
G01X926071Y224114D02*
Y223720D01*
G01Y219114D02*
Y218720D01*
G01Y214114D02*
Y213720D01*
G01Y209114D02*
Y208720D01*
G01Y204114D02*
Y203720D01*
G01X927953Y200098D02*
Y332736D01*
G01X928740Y230315D02*
Y199311D01*
G01X928799Y333130D02*
Y199705D01*
G01X929921Y195177D02*
Y337657D01*
G01X921013Y224567D02*
X921023Y224665D01*
X921051Y224737D01*
X921090Y224764D01*
G01X921013Y211969D02*
X921023Y212067D01*
X921051Y212139D01*
X921090Y212165D01*
G01X921013Y208819D02*
X921023Y208917D01*
X921051Y208989D01*
X921090Y209016D01*
G01X921454Y224114D02*
X921531Y224705D01*
G01X921454Y219114D02*
X921531Y219705D01*
G01X921454Y214114D02*
X921531Y214705D01*
G01X921454Y209114D02*
X921531Y209705D01*
G01X921454Y204114D02*
X921531Y204705D01*
G01X920329Y224114D02*
X920602Y224705D01*
G01X920329Y219114D02*
X920602Y219705D01*
G01X920329Y214114D02*
X920602Y214705D01*
G01X920329Y209114D02*
X920602Y209705D01*
G01X920329Y204114D02*
X920602Y204705D01*
G01X925657Y223130D02*
X925796Y223326D01*
X925934Y223523D01*
X926071Y223720D01*
G01X925657Y218130D02*
X925796Y218326D01*
X925934Y218523D01*
X926071Y218720D01*
G01X925657Y213130D02*
X925796Y213326D01*
X925934Y213523D01*
X926071Y213720D01*
G01X925657Y208130D02*
X925796Y208326D01*
X925934Y208523D01*
X926071Y208720D01*
G01X925657Y203130D02*
X925796Y203326D01*
X925934Y203523D01*
X926071Y203720D01*
G01X919912Y224705D02*
X919485Y224114D01*
G01X919912Y219705D02*
X919485Y219114D01*
G01X919912Y214705D02*
X919485Y214114D01*
G01X919912Y209705D02*
X919485Y209114D01*
G01X919912Y204705D02*
X919485Y204114D01*
G01X929921Y197146D02*
X927953Y195177D01*
G01X921090Y221614D02*
X921051Y221588D01*
X921023Y221515D01*
X921013Y221417D01*
G01X921090Y218465D02*
X921051Y218438D01*
X921023Y218366D01*
X921013Y218268D01*
G01X921090Y215315D02*
X921051Y215289D01*
X921023Y215216D01*
X921013Y215118D01*
G01X921090Y205866D02*
X921051Y205840D01*
X921023Y205767D01*
X921013Y205669D01*
G01X925687Y290118D02*
X925815Y290146D01*
X925904Y290219D01*
X925935Y290315D01*
G01X925687Y293268D02*
X925815Y293295D01*
X925904Y293368D01*
X925935Y293465D01*
G01X925687Y296417D02*
X925815Y296445D01*
X925904Y296518D01*
X925935Y296614D01*
G01X925687Y299567D02*
X925815Y299594D01*
X925904Y299667D01*
X925935Y299764D01*
G01X925687Y302717D02*
X925815Y302744D01*
X925904Y302817D01*
X925935Y302913D01*
G01X925687Y305866D02*
X925815Y305894D01*
X925904Y305967D01*
X925935Y306063D01*
G01X925687Y309016D02*
X925815Y309043D01*
X925904Y309116D01*
X925935Y309213D01*
G01X925687Y312165D02*
X925815Y312193D01*
X925904Y312266D01*
X925935Y312362D01*
G01X920639Y287756D02*
X920611Y287752D01*
X920586Y287741D01*
X920562Y287723D01*
X920541Y287698D01*
X920524Y287669D01*
X920511Y287635D01*
X920503Y287598D01*
X920500Y287559D01*
G01X925687Y318465D02*
X925815Y318492D01*
X925904Y318565D01*
X925935Y318661D01*
G01X925687Y321614D02*
X925815Y321642D01*
X925904Y321715D01*
X925935Y321811D01*
G01X925687Y324764D02*
X925815Y324791D01*
X925904Y324864D01*
X925935Y324961D01*
G01X925687Y327913D02*
X925815Y327941D01*
X925904Y328014D01*
X925935Y328110D01*
G01X920639Y290906D02*
X920611Y290902D01*
X920586Y290891D01*
X920562Y290872D01*
X920541Y290848D01*
X920524Y290818D01*
X920511Y290784D01*
X920503Y290748D01*
X920500Y290709D01*
G01X920639Y294055D02*
X920611Y294051D01*
X920586Y294040D01*
X920562Y294022D01*
X920541Y293997D01*
X920524Y293968D01*
X920511Y293934D01*
X920503Y293897D01*
X920500Y293858D01*
G01X920639Y297205D02*
X920611Y297201D01*
X920586Y297190D01*
X920562Y297172D01*
X920541Y297147D01*
X920524Y297117D01*
X920511Y297083D01*
X920503Y297047D01*
X920500Y297008D01*
G01X920639Y300354D02*
X920611Y300350D01*
X920586Y300339D01*
X920562Y300321D01*
X920541Y300296D01*
X920524Y300267D01*
X920511Y300233D01*
X920503Y300196D01*
X920500Y300157D01*
G01X920639Y303504D02*
X920611Y303500D01*
X920586Y303489D01*
X920562Y303471D01*
X920541Y303446D01*
X920524Y303417D01*
X920511Y303383D01*
X920503Y303346D01*
X920500Y303307D01*
G01X920639Y306654D02*
X920611Y306650D01*
X920586Y306639D01*
X920562Y306620D01*
X920541Y306596D01*
X920524Y306566D01*
X920511Y306532D01*
X920503Y306496D01*
X920500Y306457D01*
G01X920639Y309803D02*
X920611Y309799D01*
X920586Y309788D01*
X920562Y309770D01*
X920541Y309745D01*
X920524Y309716D01*
X920511Y309682D01*
X920503Y309645D01*
X920500Y309606D01*
G01X920639Y312953D02*
X920611Y312949D01*
X920586Y312938D01*
X920562Y312920D01*
X920541Y312895D01*
X920524Y312865D01*
X920511Y312831D01*
X920503Y312795D01*
X920500Y312756D01*
G01X920639Y316102D02*
X920611Y316098D01*
X920586Y316087D01*
X920562Y316069D01*
X920541Y316044D01*
X920524Y316015D01*
X920511Y315981D01*
X920503Y315944D01*
X920500Y315906D01*
G01X920639Y319252D02*
X920611Y319248D01*
X920586Y319237D01*
X920562Y319219D01*
X920541Y319194D01*
X920524Y319165D01*
X920511Y319131D01*
X920503Y319094D01*
X920500Y319055D01*
G01X920639Y322402D02*
X920611Y322398D01*
X920586Y322387D01*
X920562Y322369D01*
X920541Y322344D01*
X920524Y322314D01*
X920511Y322280D01*
X920503Y322244D01*
X920500Y322205D01*
G01X920639Y325551D02*
X920611Y325547D01*
X920586Y325536D01*
X920562Y325518D01*
X920541Y325493D01*
X920524Y325464D01*
X920511Y325430D01*
X920503Y325393D01*
X920500Y325354D01*
G01X920639Y328701D02*
X920611Y328697D01*
X920586Y328686D01*
X920562Y328668D01*
X920541Y328643D01*
X920524Y328613D01*
X920511Y328580D01*
X920503Y328543D01*
X920500Y328504D01*
G01X925687Y286969D02*
X919603D01*
G01X925935Y287165D02*
X919323D01*
G01Y287559D02*
X925935D01*
G01X925687Y287756D02*
X919603D01*
G01X925657Y288130D02*
X919912D01*
G01X919485Y288720D02*
X926071D01*
G01X919485Y289114D02*
X926071D01*
G01X925657Y289705D02*
X919912D01*
G01X925687Y290118D02*
X919603D01*
G01X925935Y290315D02*
X919323D01*
G01Y290709D02*
X925935D01*
G01X925687Y290906D02*
X919603D01*
G01X925657Y293130D02*
X919912D01*
G01X925687Y293268D02*
X919603D01*
G01X925935Y293465D02*
X919323D01*
G01X919485Y293720D02*
X926071D01*
G01X919323Y293858D02*
X925935D01*
G01X925687Y294055D02*
X919603D01*
G01X919485Y294114D02*
X926071D01*
G01X925657Y294705D02*
X919912D01*
G01X925687Y296417D02*
X919603D01*
G01X925935Y296614D02*
X919323D01*
G01Y297008D02*
X925935D01*
G01X925687Y297205D02*
X919603D01*
G01X925657Y298130D02*
X919912D01*
G01X919485Y298720D02*
X926071D01*
G01X919485Y299114D02*
X926071D01*
G01X925687Y299567D02*
X919603D01*
G01X925657Y299705D02*
X919912D01*
G01X925935Y299764D02*
X919323D01*
G01Y300157D02*
X925935D01*
G01X925687Y300354D02*
X919603D01*
G01X925687Y302717D02*
X919603D01*
G01X925935Y302913D02*
X919323D01*
G01X925657Y303130D02*
X919912D01*
G01X919323Y303307D02*
X925935D01*
G01X925687Y303504D02*
X919603D01*
G01X919485Y303720D02*
X926071D01*
G01X919485Y304114D02*
X926071D01*
G01X925657Y304705D02*
X919912D01*
G01X925687Y305866D02*
X919603D01*
G01X925935Y306063D02*
X919323D01*
G01Y306457D02*
X925935D01*
G01X925687Y306654D02*
X919603D01*
G01X925657Y308130D02*
X919912D01*
G01X919485Y308720D02*
X926071D01*
G01X925687Y309016D02*
X919603D01*
G01X919485Y309114D02*
X926071D01*
G01X925935Y309213D02*
X919323D01*
G01Y309606D02*
X925935D01*
G01X925657Y309705D02*
X919912D01*
G01X925687Y309803D02*
X919603D01*
G01X925687Y312165D02*
X919603D01*
G01X925935Y312362D02*
X919323D01*
G01Y312756D02*
X925935D01*
G01X925687Y312953D02*
X919603D01*
G01X927626Y313130D02*
X921880D01*
G01X921454Y313720D02*
X928040D01*
G01X921454Y314114D02*
X928040D01*
G01X927626Y314705D02*
X921880D01*
G01X925687Y315315D02*
X919603D01*
G01X925935Y315512D02*
X919323D01*
G01Y315906D02*
X925935D01*
G01X925687Y316102D02*
X919603D01*
G01X925657Y318130D02*
X919912D01*
G01X925687Y318465D02*
X919603D01*
G01X925935Y318661D02*
X919323D01*
G01X919485Y318720D02*
X926071D01*
G01X919323Y319055D02*
X925935D01*
G01X919485Y319114D02*
X926071D01*
G01X925687Y319252D02*
X919603D01*
G01X925657Y319705D02*
X919912D01*
G01X925687Y321614D02*
X919603D01*
G01X925935Y321811D02*
X919323D01*
G01Y322205D02*
X925935D01*
G01X925687Y322402D02*
X919603D01*
G01X925657Y323130D02*
X919912D01*
G01X919485Y323720D02*
X926071D01*
G01X919485Y324114D02*
X926071D01*
G01X925657Y324705D02*
X919912D01*
G01X925687Y324764D02*
X919603D01*
G01X925935Y324961D02*
X919323D01*
G01Y325354D02*
X925935D01*
G01X925687Y325551D02*
X919603D01*
G01X925687Y327913D02*
X919603D01*
G01X925935Y328110D02*
X919323D01*
G01X925657Y328130D02*
X919912D01*
G01X919323Y328504D02*
X925935D01*
G01X925687Y328701D02*
X919603D01*
G01X919485Y328720D02*
X926071D01*
G01X919485Y329114D02*
X926071D01*
G01X925657Y329705D02*
X919912D01*
G01X933204Y337657D02*
X929921D01*
G01X925687Y287756D02*
X925814Y287728D01*
X925903Y287656D01*
X925935Y287559D01*
G01X925687Y316102D02*
X925814Y316075D01*
X925903Y316002D01*
X925935Y315906D01*
G01X921090Y286969D02*
X921051Y286995D01*
X921023Y287067D01*
X921013Y287165D01*
G01X921090Y290118D02*
X921051Y290144D01*
X921023Y290217D01*
X921013Y290315D01*
G01X921090Y293268D02*
X921051Y293294D01*
X921023Y293366D01*
X921013Y293465D01*
G01X921090Y296417D02*
X921051Y296444D01*
X921023Y296516D01*
X921013Y296614D01*
G01X921090Y299567D02*
X921051Y299593D01*
X921023Y299665D01*
X921013Y299764D01*
G01X921090Y302717D02*
X921051Y302743D01*
X921023Y302815D01*
X921013Y302913D01*
G01X921090Y305866D02*
X921051Y305893D01*
X921023Y305965D01*
X921013Y306063D01*
G01X921090Y309016D02*
X921051Y309042D01*
X921023Y309114D01*
X921013Y309213D01*
G01X921090Y312165D02*
X921051Y312192D01*
X921023Y312264D01*
X921013Y312362D01*
G01X921090Y315315D02*
X921051Y315341D01*
X921023Y315413D01*
X921013Y315512D01*
G01X921090Y318465D02*
X921051Y318491D01*
X921023Y318563D01*
X921013Y318661D01*
G01X921090Y321614D02*
X921051Y321641D01*
X921023Y321713D01*
X921013Y321811D01*
G01X921090Y324764D02*
X921051Y324790D01*
X921023Y324862D01*
X921013Y324961D01*
G01X921090Y327913D02*
X921051Y327940D01*
X921023Y328012D01*
X921013Y328110D01*
G01X929921Y335689D02*
X927953Y337657D01*
G01X919912Y288130D02*
X919485Y288720D01*
G01X919912Y293130D02*
X919485Y293720D01*
G01X919912Y298130D02*
X919485Y298720D01*
G01X919912Y303130D02*
X919485Y303720D01*
G01X919912Y308130D02*
X919485Y308720D01*
G01X921880Y313130D02*
X921454Y313720D01*
G01X919912Y318130D02*
X919485Y318720D01*
G01X919912Y323130D02*
X919485Y323720D01*
G01X919912Y328130D02*
X919485Y328720D01*
G01X926071Y289114D02*
X925934Y289312D01*
X925796Y289509D01*
X925657Y289705D01*
G01X926071Y294114D02*
X925934Y294312D01*
X925796Y294509D01*
X925657Y294705D01*
G01X926071Y299114D02*
X925934Y299312D01*
X925796Y299509D01*
X925657Y299705D01*
G01X926071Y304114D02*
X925934Y304312D01*
X925796Y304509D01*
X925657Y304705D01*
G01X926071Y309114D02*
X925934Y309312D01*
X925796Y309509D01*
X925657Y309705D01*
G01X928040Y314114D02*
X927903Y314312D01*
X927765Y314509D01*
X927626Y314705D01*
G01X926071Y319114D02*
X925934Y319312D01*
X925796Y319509D01*
X925657Y319705D01*
G01X926071Y324114D02*
X925934Y324312D01*
X925796Y324509D01*
X925657Y324705D01*
G01X926071Y329114D02*
X925934Y329312D01*
X925796Y329509D01*
X925657Y329705D01*
G01X920602Y288130D02*
X920329Y288720D01*
G01X920602Y293130D02*
X920329Y293720D01*
G01X920602Y298130D02*
X920329Y298720D01*
G01X920602Y303130D02*
X920329Y303720D01*
G01X920602Y308130D02*
X920329Y308720D01*
G01X922570Y313130D02*
X922298Y313720D01*
G01X920602Y318130D02*
X920329Y318720D01*
G01X920602Y323130D02*
X920329Y323720D01*
G01X920602Y328130D02*
X920329Y328720D01*
G01X925935Y290709D02*
X925903Y290806D01*
X925815Y290878D01*
X925687Y290906D01*
G01X925935Y293858D02*
X925903Y293955D01*
X925815Y294027D01*
X925687Y294055D01*
G01X925935Y297008D02*
X925903Y297105D01*
X925815Y297177D01*
X925687Y297205D01*
G01X925935Y300157D02*
X925903Y300254D01*
X925815Y300326D01*
X925687Y300354D01*
G01X925935Y303307D02*
X925903Y303404D01*
X925815Y303476D01*
X925687Y303504D01*
G01X925935Y306457D02*
X925903Y306554D01*
X925815Y306626D01*
X925687Y306654D01*
G01X925935Y309606D02*
X925903Y309703D01*
X925815Y309775D01*
X925687Y309803D01*
G01X925935Y312756D02*
X925903Y312853D01*
X925815Y312925D01*
X925687Y312953D01*
G01X925935Y319055D02*
X925903Y319152D01*
X925815Y319224D01*
X925687Y319252D01*
G01X925935Y322205D02*
X925903Y322302D01*
X925815Y322374D01*
X925687Y322402D01*
G01X925935Y325354D02*
X925903Y325451D01*
X925815Y325523D01*
X925687Y325551D01*
G01X925935Y328504D02*
X925903Y328601D01*
X925815Y328673D01*
X925687Y328701D01*
G01X921454Y288720D02*
X921531Y288130D01*
G01X921454Y293720D02*
X921531Y293130D01*
G01X921454Y298720D02*
X921531Y298130D01*
G01X920500Y287165D02*
X920503Y287127D01*
X920511Y287090D01*
X920523Y287056D01*
X920541Y287026D01*
X920561Y287002D01*
X920585Y286983D01*
X920611Y286972D01*
X920639Y286969D01*
G01X920500Y290315D02*
X920503Y290277D01*
X920511Y290240D01*
X920523Y290206D01*
X920541Y290176D01*
X920561Y290151D01*
X920585Y290133D01*
X920611Y290122D01*
X920639Y290118D01*
G01X920500Y293465D02*
X920503Y293426D01*
X920511Y293389D01*
X920523Y293356D01*
X920541Y293325D01*
X920561Y293301D01*
X920585Y293283D01*
X920611Y293272D01*
X920639Y293268D01*
G01X920500Y296614D02*
X920503Y296576D01*
X920511Y296539D01*
X920523Y296505D01*
X920541Y296475D01*
X920561Y296450D01*
X920585Y296432D01*
X920611Y296421D01*
X920639Y296417D01*
G01X920500Y299764D02*
X920503Y299726D01*
X920511Y299689D01*
X920523Y299655D01*
X920541Y299624D01*
X920561Y299600D01*
X920585Y299582D01*
X920611Y299571D01*
X920639Y299567D01*
G01X920500Y302913D02*
X920503Y302875D01*
X920511Y302838D01*
X920523Y302804D01*
X920541Y302774D01*
X920561Y302750D01*
X920585Y302731D01*
X920611Y302720D01*
X920639Y302717D01*
G01X920500Y306063D02*
X920503Y306025D01*
X920511Y305988D01*
X920523Y305954D01*
X920541Y305924D01*
X920561Y305899D01*
X920585Y305881D01*
X920611Y305870D01*
X920639Y305866D01*
G01X920500Y309213D02*
X920503Y309174D01*
X920511Y309137D01*
X920523Y309104D01*
X920541Y309073D01*
X920561Y309049D01*
X920585Y309031D01*
X920611Y309020D01*
X920639Y309016D01*
G01X920500Y312362D02*
X920503Y312324D01*
X920511Y312287D01*
X920523Y312253D01*
X920541Y312223D01*
X920561Y312198D01*
X920585Y312180D01*
X920611Y312169D01*
X920639Y312165D01*
G01X920500Y315512D02*
X920503Y315474D01*
X920511Y315437D01*
X920523Y315403D01*
X920541Y315372D01*
X920561Y315348D01*
X920585Y315330D01*
X920611Y315319D01*
X920639Y315315D01*
G01X920500Y318661D02*
X920503Y318623D01*
X920511Y318586D01*
X920523Y318552D01*
X920541Y318522D01*
X920561Y318498D01*
X920585Y318480D01*
X920611Y318469D01*
X920639Y318465D01*
G01X920500Y321811D02*
X920503Y321773D01*
X920511Y321736D01*
X920523Y321702D01*
X920541Y321672D01*
X920561Y321647D01*
X920585Y321629D01*
X920611Y321618D01*
X920639Y321614D01*
G01X920500Y324961D02*
X920503Y324922D01*
X920511Y324885D01*
X920523Y324852D01*
X920541Y324821D01*
X920561Y324797D01*
X920585Y324779D01*
X920611Y324768D01*
X920639Y324764D01*
G01X920500Y328110D02*
X920503Y328072D01*
X920511Y328035D01*
X920523Y328001D01*
X920541Y327971D01*
X920561Y327946D01*
X920585Y327928D01*
X920611Y327917D01*
X920639Y327913D01*
G01X921454Y303720D02*
X921531Y303130D01*
G01X921454Y308720D02*
X921531Y308130D01*
G01X921454Y318720D02*
X921531Y318130D01*
G01Y323130D02*
X921454Y323720D01*
G01X923422Y313720D02*
X923500Y313130D01*
G01X921454Y328720D02*
X921531Y328130D01*
G01X919323Y328504D02*
Y328110D01*
G01Y325354D02*
Y324961D01*
G01Y322205D02*
Y321811D01*
G01Y315906D02*
Y315512D01*
G01Y319055D02*
Y318661D01*
G01Y312756D02*
Y312362D01*
G01Y306457D02*
Y306063D01*
G01Y309606D02*
Y309213D01*
G01Y303307D02*
Y302913D01*
G01Y297008D02*
Y296614D01*
G01Y300157D02*
Y299764D01*
G01Y293858D02*
Y293465D01*
G01Y290709D02*
Y290315D01*
G01Y287559D02*
Y287165D01*
G01X919485Y288720D02*
Y289114D01*
G01Y293720D02*
Y294114D01*
G01Y298720D02*
Y299114D01*
G01Y303720D02*
Y304114D01*
G01Y308720D02*
Y309114D01*
G01Y318720D02*
Y319114D01*
G01Y323720D02*
Y324114D01*
G01Y328720D02*
Y329114D01*
G01X920329Y288720D02*
Y289114D01*
G01Y293720D02*
Y294114D01*
G01Y298720D02*
Y299114D01*
G01Y303720D02*
Y304114D01*
G01Y308720D02*
Y309114D01*
G01Y318720D02*
Y319114D01*
G01Y323720D02*
Y324114D01*
G01Y328720D02*
Y329114D01*
G01X920500Y328504D02*
Y328110D01*
G01Y325354D02*
Y324961D01*
G01Y322205D02*
Y321811D01*
G01Y315906D02*
Y315512D01*
G01Y319055D02*
Y318661D01*
G01Y312756D02*
Y312362D01*
G01Y306457D02*
Y306063D01*
G01Y309606D02*
Y309213D01*
G01Y303307D02*
Y302913D01*
G01Y297008D02*
Y296614D01*
G01Y300157D02*
Y299764D01*
G01Y293858D02*
Y293465D01*
G01Y290709D02*
Y290315D01*
G01Y287559D02*
Y287165D01*
G01X921013Y290315D02*
Y290709D01*
G01Y287165D02*
Y287559D01*
G01Y293465D02*
Y293858D01*
G01Y296614D02*
Y297008D01*
G01Y299764D02*
Y300157D01*
G01Y302913D02*
Y303307D01*
G01Y306063D02*
Y306457D01*
G01Y309213D02*
Y309606D01*
G01Y312362D02*
Y312756D01*
G01Y315512D02*
Y315906D01*
G01Y318661D02*
Y319055D01*
G01Y321811D02*
Y322205D01*
G01Y328110D02*
Y328504D01*
G01Y324961D02*
Y325354D01*
G01X921454Y329114D02*
Y328720D01*
G01Y319114D02*
Y318720D01*
G01Y309114D02*
Y308720D01*
G01Y304114D02*
Y303720D01*
G01Y299114D02*
Y298720D01*
G01Y294114D02*
Y293720D01*
G01Y289114D02*
Y288720D01*
G01Y323720D02*
Y324114D01*
G01Y313720D02*
Y314114D01*
G01X922298Y313720D02*
Y314114D01*
G01X923422D02*
Y313720D01*
G01X925935Y290315D02*
Y290709D01*
G01Y287165D02*
Y287559D01*
G01Y293465D02*
Y293858D01*
G01Y296614D02*
Y297008D01*
G01Y299764D02*
Y300157D01*
G01Y302913D02*
Y303307D01*
G01Y306063D02*
Y306457D01*
G01Y309213D02*
Y309606D01*
G01Y312362D02*
Y312756D01*
G01Y315512D02*
Y315906D01*
G01Y318661D02*
Y319055D01*
G01Y321811D02*
Y322205D01*
G01Y328110D02*
Y328504D01*
G01Y324961D02*
Y325354D01*
G01X926071Y329114D02*
Y328720D01*
G01Y324114D02*
Y323720D01*
G01Y319114D02*
Y318720D01*
G01Y309114D02*
Y308720D01*
G01Y304114D02*
Y303720D01*
G01Y299114D02*
Y298720D01*
G01Y294114D02*
Y293720D01*
G01Y289114D02*
Y288720D01*
G01X928040Y314114D02*
Y313720D01*
G01X931890Y337657D02*
Y344823D01*
G01X921013Y328504D02*
X921023Y328602D01*
X921051Y328674D01*
X921090Y328701D01*
G01X921013Y325354D02*
X921023Y325453D01*
X921051Y325525D01*
X921090Y325551D01*
G01X921013Y322205D02*
X921023Y322303D01*
X921051Y322375D01*
X921090Y322402D01*
G01X921013Y319055D02*
X921023Y319154D01*
X921051Y319226D01*
X921090Y319252D01*
G01X921013Y315906D02*
X921023Y316004D01*
X921051Y316076D01*
X921090Y316102D01*
G01X921013Y312756D02*
X921023Y312854D01*
X921051Y312926D01*
X921090Y312953D01*
G01X921013Y309606D02*
X921023Y309705D01*
X921051Y309777D01*
X921090Y309803D01*
G01X921013Y306457D02*
X921023Y306555D01*
X921051Y306627D01*
X921090Y306654D01*
G01X921013Y303307D02*
X921023Y303406D01*
X921051Y303478D01*
X921090Y303504D01*
G01X921013Y300157D02*
X921023Y300256D01*
X921051Y300328D01*
X921090Y300354D01*
G01X921013Y297008D02*
X921023Y297106D01*
X921051Y297178D01*
X921090Y297205D01*
G01X921013Y293858D02*
X921023Y293957D01*
X921051Y294029D01*
X921090Y294055D01*
G01X921013Y290709D02*
X921023Y290807D01*
X921051Y290879D01*
X921090Y290906D01*
G01X921013Y287559D02*
X921023Y287657D01*
X921051Y287730D01*
X921090Y287756D01*
G01X921454Y329114D02*
X921531Y329705D01*
G01Y324705D02*
X921454Y324114D01*
G01Y319114D02*
X921531Y319705D01*
G01X921454Y309114D02*
X921531Y309705D01*
G01X921454Y304114D02*
X921531Y304705D01*
G01X923422Y314114D02*
X923500Y314705D01*
G01X921454Y299114D02*
X921531Y299705D01*
G01X921454Y294114D02*
X921531Y294705D01*
G01X921454Y289114D02*
X921531Y289705D01*
G01X925935Y315512D02*
X925901Y315413D01*
X925813Y315342D01*
X925687Y315315D01*
G01X925935Y287165D02*
X925901Y287066D01*
X925813Y286995D01*
X925687Y286969D01*
G01X920329Y329114D02*
X920602Y329705D01*
G01X920329Y324114D02*
X920602Y324705D01*
G01X920329Y319114D02*
X920602Y319705D01*
G01X922298Y314114D02*
X922570Y314705D01*
G01X920329Y309114D02*
X920602Y309705D01*
G01X920329Y304114D02*
X920602Y304705D01*
G01X920329Y299114D02*
X920602Y299705D01*
G01X920329Y294114D02*
X920602Y294705D01*
G01X920329Y289114D02*
X920602Y289705D01*
G01X925657Y328130D02*
X925796Y328326D01*
X925934Y328523D01*
X926071Y328720D01*
G01X925657Y323130D02*
X925796Y323326D01*
X925934Y323523D01*
X926071Y323720D01*
G01X925657Y318130D02*
X925796Y318326D01*
X925934Y318523D01*
X926071Y318720D01*
G01X927626Y313130D02*
X927765Y313326D01*
X927903Y313523D01*
X928040Y313720D01*
G01X925657Y308130D02*
X925796Y308326D01*
X925934Y308523D01*
X926071Y308720D01*
G01X925657Y303130D02*
X925796Y303326D01*
X925934Y303523D01*
X926071Y303720D01*
G01X925657Y298130D02*
X925796Y298326D01*
X925934Y298523D01*
X926071Y298720D01*
G01X925657Y293130D02*
X925796Y293326D01*
X925934Y293523D01*
X926071Y293720D01*
G01X925657Y288130D02*
X925796Y288326D01*
X925934Y288523D01*
X926071Y288720D01*
G01X919912Y329705D02*
X919485Y329114D01*
G01X919912Y324705D02*
X919485Y324114D01*
G01X919912Y319705D02*
X919485Y319114D01*
G01X921880Y314705D02*
X921454Y314114D01*
G01X919912Y309705D02*
X919485Y309114D01*
G01X919912Y304705D02*
X919485Y304114D01*
G01X919912Y299705D02*
X919485Y299114D01*
G01X919912Y294705D02*
X919485Y294114D01*
G01X919912Y289705D02*
X919485Y289114D01*
G01X927953Y332736D02*
X929921Y334705D01*
G01X933204Y337657D02*
X936614Y339626D01*
G01X925687Y268071D02*
X925815Y268098D01*
X925904Y268171D01*
X925935Y268268D01*
G01X925687Y271220D02*
X925815Y271248D01*
X925904Y271321D01*
X925935Y271417D01*
G01X925687Y274370D02*
X925815Y274398D01*
X925904Y274470D01*
X925935Y274567D01*
G01X925687Y277520D02*
X925815Y277547D01*
X925904Y277620D01*
X925935Y277717D01*
G01X925687Y280669D02*
X925815Y280697D01*
X925904Y280770D01*
X925935Y280866D01*
G01X925687Y283819D02*
X925815Y283846D01*
X925904Y283919D01*
X925935Y284016D01*
G01X920639Y268858D02*
X920611Y268854D01*
X920586Y268843D01*
X920562Y268825D01*
X920541Y268800D01*
X920524Y268771D01*
X920511Y268737D01*
X920503Y268700D01*
X920500Y268661D01*
G01X920639Y272008D02*
X920611Y272004D01*
X920586Y271993D01*
X920562Y271975D01*
X920541Y271950D01*
X920524Y271920D01*
X920511Y271887D01*
X920503Y271850D01*
X920500Y271811D01*
G01X920639Y275157D02*
X920611Y275154D01*
X920586Y275143D01*
X920562Y275124D01*
X920541Y275100D01*
X920524Y275070D01*
X920511Y275036D01*
X920503Y275000D01*
X920500Y274961D01*
G01X920639Y278307D02*
X920611Y278303D01*
X920586Y278292D01*
X920562Y278274D01*
X920541Y278249D01*
X920524Y278220D01*
X920511Y278186D01*
X920503Y278149D01*
X920500Y278110D01*
G01X920639Y281457D02*
X920611Y281453D01*
X920586Y281442D01*
X920562Y281424D01*
X920541Y281399D01*
X920524Y281369D01*
X920511Y281335D01*
X920503Y281299D01*
X920500Y281260D01*
G01X920639Y284606D02*
X920611Y284602D01*
X920586Y284591D01*
X920562Y284573D01*
X920541Y284548D01*
X920524Y284519D01*
X920511Y284485D01*
X920503Y284448D01*
X920500Y284409D01*
G01X925687Y268071D02*
X919603D01*
G01X925657Y268130D02*
X919912D01*
G01X925935Y268268D02*
X919323D01*
G01Y268661D02*
X925935D01*
G01X919485Y268720D02*
X926071D01*
G01X925687Y268858D02*
X919603D01*
G01X919485Y269114D02*
X926071D01*
G01X925657Y269705D02*
X919912D01*
G01X925687Y271220D02*
X919603D01*
G01X925935Y271417D02*
X919323D01*
G01Y271811D02*
X925935D01*
G01X925687Y272008D02*
X919603D01*
G01X927626Y273130D02*
X921880D01*
G01X921454Y273720D02*
X928040D01*
G01X921454Y274114D02*
X928040D01*
G01X925687Y274370D02*
X919603D01*
G01X925935Y274567D02*
X919323D01*
G01X927626Y274705D02*
X921880D01*
G01X919323Y274961D02*
X925935D01*
G01X925687Y275157D02*
X919603D01*
G01X925687Y277520D02*
X919603D01*
G01X925935Y277717D02*
X919323D01*
G01Y278110D02*
X925935D01*
G01X925657Y278130D02*
X919912D01*
G01X925687Y278307D02*
X919603D01*
G01X919485Y278720D02*
X926071D01*
G01X919485Y279114D02*
X926071D01*
G01X925657Y279705D02*
X919912D01*
G01X925687Y280669D02*
X919603D01*
G01X925935Y280866D02*
X919323D01*
G01Y281260D02*
X925935D01*
G01X925687Y281457D02*
X919603D01*
G01X925657Y283130D02*
X919912D01*
G01X919485Y283720D02*
X926071D01*
G01X925687Y283819D02*
X919603D01*
G01X925935Y284016D02*
X919323D01*
G01X919485Y284114D02*
X926071D01*
G01X919323Y284409D02*
X925935D01*
G01X925687Y284606D02*
X919603D01*
G01X925657Y284705D02*
X919912D01*
G01X921090Y268071D02*
X921051Y268097D01*
X921023Y268169D01*
X921013Y268268D01*
G01X921090Y271220D02*
X921051Y271247D01*
X921023Y271319D01*
X921013Y271417D01*
G01X921090Y274370D02*
X921051Y274396D01*
X921023Y274469D01*
X921013Y274567D01*
G01X921090Y277520D02*
X921051Y277546D01*
X921023Y277618D01*
X921013Y277717D01*
G01X921090Y280669D02*
X921051Y280696D01*
X921023Y280768D01*
X921013Y280866D01*
G01X921090Y283819D02*
X921051Y283845D01*
X921023Y283917D01*
X921013Y284016D01*
G01X919912Y268130D02*
X919485Y268720D01*
G01X921880Y273130D02*
X921454Y273720D01*
G01X919912Y278130D02*
X919485Y278720D01*
G01X919912Y283130D02*
X919485Y283720D01*
G01X926071Y269114D02*
X925934Y269312D01*
X925796Y269509D01*
X925657Y269705D01*
G01X928040Y274114D02*
X927903Y274312D01*
X927765Y274509D01*
X927626Y274705D01*
G01X926071Y279114D02*
X925934Y279312D01*
X925796Y279509D01*
X925657Y279705D01*
G01X926071Y284114D02*
X925934Y284312D01*
X925796Y284509D01*
X925657Y284705D01*
G01X920602Y268130D02*
X920329Y268720D01*
G01X922570Y273130D02*
X922298Y273720D01*
G01X920602Y278130D02*
X920329Y278720D01*
G01X920602Y283130D02*
X920329Y283720D01*
G01X925935Y268661D02*
X925903Y268758D01*
X925815Y268830D01*
X925687Y268858D01*
G01X925935Y271811D02*
X925903Y271908D01*
X925815Y271980D01*
X925687Y272008D01*
G01X925935Y274961D02*
X925903Y275057D01*
X925815Y275130D01*
X925687Y275157D01*
G01X925935Y278110D02*
X925903Y278207D01*
X925815Y278279D01*
X925687Y278307D01*
G01X925935Y281260D02*
X925903Y281357D01*
X925815Y281429D01*
X925687Y281457D01*
G01X925935Y284409D02*
X925903Y284506D01*
X925815Y284578D01*
X925687Y284606D01*
G01X921454Y268720D02*
X921531Y268130D01*
G01X921454Y278720D02*
X921531Y278130D01*
G01X921454Y283720D02*
X921531Y283130D01*
G01X923422Y273720D02*
X923500Y273130D01*
G01X920500Y268268D02*
X920503Y268230D01*
X920511Y268193D01*
X920523Y268159D01*
X920541Y268128D01*
X920561Y268104D01*
X920585Y268086D01*
X920611Y268075D01*
X920639Y268071D01*
G01X920500Y271417D02*
X920503Y271379D01*
X920511Y271342D01*
X920523Y271308D01*
X920541Y271278D01*
X920561Y271254D01*
X920585Y271235D01*
X920611Y271224D01*
X920639Y271220D01*
G01X920500Y274567D02*
X920503Y274529D01*
X920511Y274492D01*
X920523Y274458D01*
X920541Y274428D01*
X920561Y274403D01*
X920585Y274385D01*
X920611Y274374D01*
X920639Y274370D01*
G01X920500Y277717D02*
X920503Y277678D01*
X920511Y277641D01*
X920523Y277607D01*
X920541Y277577D01*
X920561Y277553D01*
X920585Y277535D01*
X920611Y277524D01*
X920639Y277520D01*
G01X920500Y280866D02*
X920503Y280828D01*
X920511Y280791D01*
X920523Y280757D01*
X920541Y280727D01*
X920561Y280702D01*
X920585Y280684D01*
X920611Y280673D01*
X920639Y280669D01*
G01X920500Y284016D02*
X920503Y283978D01*
X920511Y283941D01*
X920523Y283907D01*
X920541Y283876D01*
X920561Y283852D01*
X920585Y283834D01*
X920611Y283823D01*
X920639Y283819D01*
G01X919323Y284409D02*
Y284016D01*
G01Y281260D02*
Y280866D01*
G01Y278110D02*
Y277717D01*
G01Y274961D02*
Y274567D01*
G01Y271811D02*
Y271417D01*
G01Y268661D02*
Y268268D01*
G01X919485Y268720D02*
Y269114D01*
G01Y278720D02*
Y279114D01*
G01Y283720D02*
Y284114D01*
G01X920329Y268720D02*
Y269114D01*
G01Y278720D02*
Y279114D01*
G01Y283720D02*
Y284114D01*
G01X920500Y284409D02*
Y284016D01*
G01Y281260D02*
Y280866D01*
G01Y278110D02*
Y277717D01*
G01Y274961D02*
Y274567D01*
G01Y271811D02*
Y271417D01*
G01Y268661D02*
Y268268D01*
G01X921013Y271417D02*
Y271811D01*
G01Y268268D02*
Y268661D01*
G01Y274567D02*
Y274961D01*
G01Y280866D02*
Y281260D01*
G01Y277717D02*
Y278110D01*
G01Y284016D02*
Y284409D01*
G01X921454Y284114D02*
Y283720D01*
G01Y279114D02*
Y278720D01*
G01Y269114D02*
Y268720D01*
G01Y273720D02*
Y274114D01*
G01X922298Y273720D02*
Y274114D01*
G01X923422D02*
Y273720D01*
G01X925935Y271417D02*
Y271811D01*
G01Y268268D02*
Y268661D01*
G01Y274567D02*
Y274961D01*
G01Y280866D02*
Y281260D01*
G01Y277717D02*
Y278110D01*
G01Y284016D02*
Y284409D01*
G01X926071Y284114D02*
Y283720D01*
G01Y279114D02*
Y278720D01*
G01Y269114D02*
Y268720D01*
G01X928040Y274114D02*
Y273720D01*
G01X921013Y284409D02*
X921023Y284508D01*
X921051Y284580D01*
X921090Y284606D01*
G01X921013Y281260D02*
X921023Y281358D01*
X921051Y281430D01*
X921090Y281457D01*
G01X921013Y278110D02*
X921023Y278209D01*
X921051Y278281D01*
X921090Y278307D01*
G01X921013Y274961D02*
X921023Y275059D01*
X921051Y275131D01*
X921090Y275157D01*
G01X921013Y271811D02*
X921023Y271909D01*
X921051Y271981D01*
X921090Y272008D01*
G01X921013Y268661D02*
X921023Y268760D01*
X921051Y268832D01*
X921090Y268858D01*
G01X921454Y284114D02*
X921531Y284705D01*
G01X921454Y279114D02*
X921531Y279705D01*
G01X921454Y269114D02*
X921531Y269705D01*
G01X923422Y274114D02*
X923500Y274705D01*
G01X920329Y284114D02*
X920602Y284705D01*
G01X920329Y279114D02*
X920602Y279705D01*
G01X922298Y274114D02*
X922570Y274705D01*
G01X920329Y269114D02*
X920602Y269705D01*
G01X925657Y283130D02*
X925796Y283326D01*
X925934Y283523D01*
X926071Y283720D01*
G01X925657Y278130D02*
X925796Y278326D01*
X925934Y278523D01*
X926071Y278720D01*
G01X927626Y273130D02*
X927765Y273326D01*
X927903Y273523D01*
X928040Y273720D01*
G01X925657Y268130D02*
X925796Y268326D01*
X925934Y268523D01*
X926071Y268720D01*
G01X919912Y284705D02*
X919485Y284114D01*
G01X919912Y279705D02*
X919485Y279114D01*
G01X921880Y274705D02*
X921454Y274114D01*
G01X919912Y269705D02*
X919485Y269114D01*
G01X931921Y345973D02*
X931979Y345833D01*
X931984Y345593D01*
G01X931947Y345272D02*
X931984Y345596D01*
X931978Y345837D01*
X931921Y345973D01*
G01X936614Y340255D02*
X931894Y344896D01*
G01X936614Y341358D02*
X931890Y346004D01*
G01X936614Y339626D02*
Y341358D01*
G01X931948Y345274D02*
X931894Y344896D01*
G01X925687Y610591D02*
X925815Y610618D01*
X925904Y610691D01*
X925935Y610787D01*
G01X925687Y613740D02*
X925815Y613768D01*
X925904Y613841D01*
X925935Y613937D01*
G01X925687Y616890D02*
X925815Y616917D01*
X925904Y616990D01*
X925935Y617087D01*
G01X925687Y620039D02*
X925815Y620067D01*
X925904Y620140D01*
X925935Y620236D01*
G01X925687Y623189D02*
X925815Y623217D01*
X925904Y623289D01*
X925935Y623386D01*
G01X920639Y611378D02*
X920611Y611374D01*
X920586Y611363D01*
X920562Y611345D01*
X920541Y611320D01*
X920524Y611291D01*
X920511Y611257D01*
X920503Y611220D01*
X920500Y611181D01*
G01X920639Y614528D02*
X920611Y614524D01*
X920586Y614513D01*
X920562Y614494D01*
X920541Y614470D01*
X920524Y614440D01*
X920511Y614406D01*
X920503Y614370D01*
X920500Y614331D01*
G01X920639Y617677D02*
X920611Y617673D01*
X920586Y617662D01*
X920562Y617644D01*
X920541Y617619D01*
X920524Y617590D01*
X920511Y617556D01*
X920503Y617519D01*
X920500Y617480D01*
G01X920639Y620827D02*
X920611Y620823D01*
X920586Y620812D01*
X920562Y620794D01*
X920541Y620769D01*
X920524Y620739D01*
X920511Y620706D01*
X920503Y620669D01*
X920500Y620630D01*
G01X920639Y623976D02*
X920611Y623972D01*
X920586Y623961D01*
X920562Y623943D01*
X920541Y623919D01*
X920524Y623889D01*
X920511Y623855D01*
X920503Y623819D01*
X920500Y623780D01*
G01X933204Y600689D02*
X929921D01*
G01X925657Y608642D02*
X919912D01*
G01X919485Y609232D02*
X926071D01*
G01X919485Y609626D02*
X926071D01*
G01X925657Y610217D02*
X919912D01*
G01X925687Y610591D02*
X919603D01*
G01X925935Y610787D02*
X919323D01*
G01Y611181D02*
X925935D01*
G01X925687Y611378D02*
X919603D01*
G01X925657Y613642D02*
X919912D01*
G01X925687Y613740D02*
X919603D01*
G01X925935Y613937D02*
X919323D01*
G01X919485Y614232D02*
X926071D01*
G01X919323Y614331D02*
X925935D01*
G01X925687Y614528D02*
X919603D01*
G01X919485Y614626D02*
X926071D01*
G01X925657Y615217D02*
X919912D01*
G01X925687Y616890D02*
X919603D01*
G01X925935Y617087D02*
X919323D01*
G01Y617480D02*
X925935D01*
G01X925687Y617677D02*
X919603D01*
G01X925657Y618642D02*
X919912D01*
G01X919485Y619232D02*
X926071D01*
G01X919485Y619626D02*
X926071D01*
G01X925687Y620039D02*
X919603D01*
G01X925657Y620217D02*
X919912D01*
G01X925935Y620236D02*
X919323D01*
G01Y620630D02*
X925935D01*
G01X925687Y620827D02*
X919603D01*
G01X925687Y623189D02*
X919603D01*
G01X925935Y623386D02*
X919323D01*
G01X925657Y623642D02*
X919912D01*
G01X919323Y623780D02*
X925935D01*
G01X925687Y623976D02*
X919603D01*
G01X919485Y624232D02*
X926071D01*
G01X919485Y624626D02*
X926071D01*
G01X925657Y625217D02*
X919912D01*
G01X933204Y600689D02*
X936614Y598720D01*
G01X921090Y610591D02*
X921051Y610617D01*
X921023Y610689D01*
X921013Y610787D01*
G01X921090Y613740D02*
X921051Y613767D01*
X921023Y613839D01*
X921013Y613937D01*
G01X921090Y616890D02*
X921051Y616916D01*
X921023Y616988D01*
X921013Y617087D01*
G01X921090Y620039D02*
X921051Y620066D01*
X921023Y620138D01*
X921013Y620236D01*
G01X921090Y623189D02*
X921051Y623215D01*
X921023Y623287D01*
X921013Y623386D01*
G01X929921Y603642D02*
X927953Y605610D01*
G01X919912Y608642D02*
X919485Y609232D01*
G01X919912Y613642D02*
X919485Y614232D01*
G01X919912Y618642D02*
X919485Y619232D01*
G01X919912Y623642D02*
X919485Y624232D01*
G01X926071Y609626D02*
X925934Y609824D01*
X925796Y610020D01*
X925657Y610217D01*
G01X926071Y614626D02*
X925934Y614824D01*
X925796Y615020D01*
X925657Y615217D01*
G01X926071Y619626D02*
X925934Y619824D01*
X925796Y620020D01*
X925657Y620217D01*
G01X926071Y624626D02*
X925934Y624824D01*
X925796Y625020D01*
X925657Y625217D01*
G01X920602Y608642D02*
X920329Y609232D01*
G01X920602Y613642D02*
X920329Y614232D01*
G01X920602Y618642D02*
X920329Y619232D01*
G01X920602Y623642D02*
X920329Y624232D01*
G01X925935Y611181D02*
X925903Y611278D01*
X925815Y611350D01*
X925687Y611378D01*
G01X925935Y614331D02*
X925903Y614428D01*
X925815Y614500D01*
X925687Y614528D01*
G01X925935Y617480D02*
X925903Y617577D01*
X925815Y617649D01*
X925687Y617677D01*
G01X925935Y620630D02*
X925903Y620727D01*
X925815Y620799D01*
X925687Y620827D01*
G01X925935Y623780D02*
X925903Y623876D01*
X925815Y623948D01*
X925687Y623976D01*
G01X920500Y610787D02*
X920503Y610749D01*
X920511Y610712D01*
X920523Y610678D01*
X920541Y610648D01*
X920561Y610624D01*
X920585Y610606D01*
X920611Y610594D01*
X920639Y610591D01*
G01X920500Y613937D02*
X920503Y613899D01*
X920511Y613862D01*
X920523Y613828D01*
X920541Y613798D01*
X920561Y613773D01*
X920585Y613755D01*
X920611Y613744D01*
X920639Y613740D01*
G01X920500Y617087D02*
X920503Y617048D01*
X920511Y617011D01*
X920523Y616978D01*
X920541Y616947D01*
X920561Y616923D01*
X920585Y616905D01*
X920611Y616894D01*
X920639Y616890D01*
G01X920500Y620236D02*
X920503Y620198D01*
X920511Y620161D01*
X920523Y620127D01*
X920541Y620097D01*
X920561Y620072D01*
X920585Y620054D01*
X920611Y620043D01*
X920639Y620039D01*
G01X920500Y623386D02*
X920503Y623348D01*
X920511Y623311D01*
X920523Y623277D01*
X920541Y623246D01*
X920561Y623222D01*
X920585Y623204D01*
X920611Y623193D01*
X920639Y623189D01*
G01X931949Y593065D02*
X931894Y593450D01*
G01X921454Y609232D02*
X921531Y608642D01*
G01X921454Y614232D02*
X921531Y613642D01*
G01X921454Y619232D02*
X921531Y618642D01*
G01X921454Y624232D02*
X921531Y623642D01*
G01X919323Y623780D02*
Y623386D01*
G01Y620630D02*
Y620236D01*
G01Y617480D02*
Y617087D01*
G01Y614331D02*
Y613937D01*
G01Y611181D02*
Y610787D01*
G01X919485Y609232D02*
Y609626D01*
G01Y614232D02*
Y614626D01*
G01Y619232D02*
Y619626D01*
G01Y624232D02*
Y624626D01*
G01X920329Y609232D02*
Y609626D01*
G01Y614232D02*
Y614626D01*
G01Y619232D02*
Y619626D01*
G01Y624232D02*
Y624626D01*
G01X920500Y623780D02*
Y623386D01*
G01Y620630D02*
Y620236D01*
G01Y617480D02*
Y617087D01*
G01Y614331D02*
Y613937D01*
G01Y611181D02*
Y610787D01*
G01X921013D02*
Y611181D01*
G01Y617087D02*
Y617480D01*
G01Y613937D02*
Y614331D01*
G01Y620236D02*
Y620630D01*
G01Y623386D02*
Y623780D01*
G01X921454Y624626D02*
Y624232D01*
G01Y619626D02*
Y619232D01*
G01Y614626D02*
Y614232D01*
G01Y609626D02*
Y609232D01*
G01X925935Y610787D02*
Y611181D01*
G01Y617087D02*
Y617480D01*
G01Y613937D02*
Y614331D01*
G01Y620236D02*
Y620630D01*
G01Y623386D02*
Y623780D01*
G01X926071Y624626D02*
Y624232D01*
G01Y619626D02*
Y619232D01*
G01Y614626D02*
Y614232D01*
G01Y609626D02*
Y609232D01*
G01X927953Y605610D02*
Y738248D01*
G01X928740Y635827D02*
Y604823D01*
G01X928799Y738642D02*
Y605217D01*
G01X929921Y600689D02*
Y743169D01*
G01X931890Y593524D02*
Y600689D01*
G01X936614Y598720D02*
Y596988D01*
G01X921013Y617480D02*
X921023Y617579D01*
X921051Y617651D01*
X921090Y617677D01*
G01X921013Y614331D02*
X921023Y614429D01*
X921051Y614501D01*
X921090Y614528D01*
G01X921454Y624626D02*
X921531Y625217D01*
G01X921454Y619626D02*
X921531Y620217D01*
G01X921454Y614626D02*
X921531Y615217D01*
G01X921454Y609626D02*
X921531Y610217D01*
G01X931921Y592374D02*
X931979Y592513D01*
X931984Y592754D01*
G01X931921Y592374D02*
X931978Y592508D01*
X931984Y592744D01*
X931948Y593072D01*
G01X920329Y624626D02*
X920602Y625217D01*
G01X920329Y619626D02*
X920602Y620217D01*
G01X920329Y614626D02*
X920602Y615217D01*
G01X920329Y609626D02*
X920602Y610217D01*
G01X921090Y623976D02*
X921051Y623950D01*
X921023Y623878D01*
X921013Y623780D01*
G01X921090Y620827D02*
X921051Y620800D01*
X921023Y620728D01*
X921013Y620630D01*
G01X925657Y623642D02*
X925796Y623838D01*
X925934Y624035D01*
X926071Y624232D01*
G01X925657Y618642D02*
X925796Y618838D01*
X925934Y619035D01*
X926071Y619232D01*
G01X925657Y613642D02*
X925796Y613838D01*
X925934Y614035D01*
X926071Y614232D01*
G01X925657Y608642D02*
X925796Y608838D01*
X925934Y609035D01*
X926071Y609232D01*
G01X919912Y625217D02*
X919485Y624626D01*
G01X919912Y620217D02*
X919485Y619626D01*
G01X919912Y615217D02*
X919485Y614626D01*
G01X919912Y610217D02*
X919485Y609626D01*
G01X929921Y602657D02*
X927953Y600689D01*
G01X936614Y598091D02*
X931894Y593450D01*
G01X936614Y596988D02*
X931890Y592343D01*
G01X921090Y611378D02*
X921051Y611352D01*
X921023Y611279D01*
X921013Y611181D01*
G01X925687Y626339D02*
X925815Y626366D01*
X925904Y626439D01*
X925935Y626535D01*
G01X925687Y629488D02*
X925815Y629516D01*
X925904Y629589D01*
X925935Y629685D01*
G01X920639Y627126D02*
X920611Y627122D01*
X920586Y627111D01*
X920562Y627093D01*
X920541Y627068D01*
X920524Y627039D01*
X920511Y627005D01*
X920503Y626968D01*
X920500Y626929D01*
G01X925687Y626339D02*
X919603D01*
G01X925935Y626535D02*
X919323D01*
G01Y626929D02*
X925935D01*
G01X925687Y627126D02*
X919603D01*
G01X925657Y628642D02*
X919912D01*
G01X919485Y629232D02*
X926071D01*
G01X925687Y629488D02*
X919603D01*
G01X921090Y626339D02*
X921051Y626365D01*
X921023Y626437D01*
X921013Y626535D01*
G01X921090Y629488D02*
X921051Y629515D01*
X921023Y629587D01*
X921013Y629685D01*
G01X919912Y628642D02*
X919485Y629232D01*
G01X926071Y629626D02*
X925934Y629824D01*
X925796Y630020D01*
X925657Y630217D01*
G01X920602Y628642D02*
X920329Y629232D01*
G01X925935Y626929D02*
X925903Y627026D01*
X925815Y627098D01*
X925687Y627126D01*
G01X920500Y626535D02*
X920503Y626497D01*
X920511Y626460D01*
X920523Y626426D01*
X920541Y626396D01*
X920561Y626372D01*
X920585Y626354D01*
X920611Y626343D01*
X920639Y626339D01*
G01X920500Y629685D02*
X920503Y629647D01*
X920511Y629610D01*
X920523Y629576D01*
X920541Y629546D01*
X920561Y629521D01*
X920585Y629503D01*
X920611Y629492D01*
X920639Y629488D01*
G01X921454Y629232D02*
X921531Y628642D01*
G01X919323Y626929D02*
Y626535D01*
G01X919485Y629232D02*
Y629626D01*
G01X920329Y629232D02*
Y629626D01*
G01X920500Y626929D02*
Y626535D01*
G01X921013D02*
Y626929D01*
G01X921454Y629626D02*
Y629232D01*
G01X925935Y626535D02*
Y626929D01*
G01X926071Y629626D02*
Y629232D01*
G01X921454Y629626D02*
X921531Y630217D01*
G01X920329Y629626D02*
X920602Y630217D01*
G01X919912D02*
X919485Y629626D01*
G01X921090Y627126D02*
X921051Y627100D01*
X921023Y627027D01*
X921013Y626929D01*
G01X925657Y628642D02*
X925796Y628838D01*
X925934Y629035D01*
X926071Y629232D01*
G01X1011816Y686993D02*
G03X984257I-13779J0D01*
G01X1013785D02*
G03X982289I-15748J0D01*
G01X1013785D02*
G03X982289I-15748J0D01*
G01X1013785D02*
G03X982289I-15748J0D01*
G01Y673214D02*
G03X1013785I15748J0D01*
G01X982289D02*
G03X1013785I15748J0D01*
G01X982289D02*
G03X1013785I15748J0D01*
G01X984257Y686993D02*
Y684631D01*
G01X982289Y673214D02*
Y686993D01*
G01Y673214D02*
Y686993D01*
G01Y673214D02*
Y686993D01*
G01X984257Y684631D02*
X992131D01*
G01X925687Y648386D02*
X925815Y648413D01*
X925904Y648486D01*
X925935Y648583D01*
G01X925687Y651535D02*
X925815Y651563D01*
X925904Y651636D01*
X925935Y651732D01*
G01X925687Y654685D02*
X925815Y654713D01*
X925904Y654785D01*
X925935Y654882D01*
G01X925687Y657835D02*
X925815Y657862D01*
X925904Y657935D01*
X925935Y658031D01*
G01X925687Y660984D02*
X925815Y661012D01*
X925904Y661085D01*
X925935Y661181D01*
G01X925687Y664134D02*
X925815Y664161D01*
X925904Y664234D01*
X925935Y664331D01*
G01X925687Y667283D02*
X925815Y667311D01*
X925904Y667384D01*
X925935Y667480D01*
G01X925687Y670433D02*
X925815Y670461D01*
X925904Y670533D01*
X925935Y670630D01*
G01X925687Y673583D02*
X925815Y673610D01*
X925904Y673683D01*
X925935Y673780D01*
G01X925687Y676732D02*
X925815Y676760D01*
X925904Y676833D01*
X925935Y676929D01*
G01X925687Y679882D02*
X925815Y679909D01*
X925904Y679982D01*
X925935Y680079D01*
G01X925687Y683031D02*
X925815Y683059D01*
X925904Y683132D01*
X925935Y683228D01*
G01X925687Y686181D02*
X925815Y686209D01*
X925904Y686281D01*
X925935Y686378D01*
G01X925687Y689331D02*
X925815Y689358D01*
X925904Y689431D01*
X925935Y689528D01*
G01X925687Y695630D02*
X925815Y695657D01*
X925904Y695730D01*
X925935Y695827D01*
G01X925687Y698780D02*
X925815Y698807D01*
X925904Y698880D01*
X925935Y698976D01*
G01X925687Y701929D02*
X925815Y701957D01*
X925904Y702030D01*
X925935Y702126D01*
G01X925697Y646518D02*
X925824Y646545D01*
X925913Y646618D01*
X925944Y646715D01*
G01X925697Y649667D02*
X925824Y649695D01*
X925913Y649767D01*
X925944Y649864D01*
G01X925697Y652817D02*
X925824Y652844D01*
X925913Y652917D01*
X925944Y653014D01*
G01X925697Y655967D02*
X925824Y655994D01*
X925913Y656067D01*
X925944Y656163D01*
G01X925697Y659116D02*
X925824Y659144D01*
X925913Y659216D01*
X925944Y659313D01*
G01X920639Y646024D02*
X920611Y646020D01*
X920586Y646009D01*
X920562Y645991D01*
X920541Y645966D01*
X920524Y645936D01*
X920511Y645902D01*
X920503Y645866D01*
X920500Y645827D01*
G01X920639Y649173D02*
X920611Y649169D01*
X920586Y649158D01*
X920562Y649140D01*
X920541Y649115D01*
X920524Y649086D01*
X920511Y649052D01*
X920503Y649015D01*
X920500Y648976D01*
G01X920639Y652323D02*
X920611Y652319D01*
X920586Y652308D01*
X920562Y652290D01*
X920541Y652265D01*
X920524Y652235D01*
X920511Y652202D01*
X920503Y652165D01*
X920500Y652126D01*
G01X920639Y655472D02*
X920611Y655469D01*
X920586Y655457D01*
X920562Y655439D01*
X920541Y655415D01*
X920524Y655385D01*
X920511Y655351D01*
X920503Y655315D01*
X920500Y655276D01*
G01X920639Y658622D02*
X920611Y658618D01*
X920586Y658607D01*
X920562Y658589D01*
X920541Y658564D01*
X920524Y658535D01*
X920511Y658501D01*
X920503Y658464D01*
X920500Y658425D01*
G01X920639Y661772D02*
X920611Y661768D01*
X920586Y661757D01*
X920562Y661739D01*
X920541Y661714D01*
X920524Y661684D01*
X920511Y661650D01*
X920503Y661614D01*
X920500Y661575D01*
G01X920639Y664921D02*
X920611Y664917D01*
X920586Y664906D01*
X920562Y664888D01*
X920541Y664863D01*
X920524Y664834D01*
X920511Y664800D01*
X920503Y664763D01*
X920500Y664724D01*
G01X920639Y668071D02*
X920611Y668067D01*
X920586Y668056D01*
X920562Y668038D01*
X920541Y668013D01*
X920524Y667983D01*
X920511Y667950D01*
X920503Y667913D01*
X920500Y667874D01*
G01X920639Y671220D02*
X920611Y671217D01*
X920586Y671206D01*
X920562Y671187D01*
X920541Y671163D01*
X920524Y671133D01*
X920511Y671099D01*
X920503Y671063D01*
X920500Y671024D01*
G01X920639Y674370D02*
X920611Y674366D01*
X920586Y674355D01*
X920562Y674337D01*
X920541Y674312D01*
X920524Y674283D01*
X920511Y674249D01*
X920503Y674212D01*
X920500Y674173D01*
G01X920639Y677520D02*
X920611Y677516D01*
X920586Y677505D01*
X920562Y677487D01*
X920541Y677462D01*
X920524Y677432D01*
X920511Y677398D01*
X920503Y677362D01*
X920500Y677323D01*
G01X920639Y680669D02*
X920611Y680665D01*
X920586Y680654D01*
X920562Y680636D01*
X920541Y680611D01*
X920524Y680582D01*
X920511Y680548D01*
X920503Y680511D01*
X920500Y680472D01*
G01X920639Y683819D02*
X920611Y683815D01*
X920586Y683804D01*
X920562Y683786D01*
X920541Y683761D01*
X920524Y683731D01*
X920511Y683698D01*
X920503Y683661D01*
X920500Y683622D01*
G01X920639Y686969D02*
X920611Y686965D01*
X920586Y686954D01*
X920562Y686935D01*
X920541Y686911D01*
X920524Y686881D01*
X920511Y686847D01*
X920503Y686811D01*
X920500Y686772D01*
G01X920639Y690118D02*
X920611Y690114D01*
X920586Y690103D01*
X920562Y690085D01*
X920541Y690060D01*
X920524Y690031D01*
X920511Y689997D01*
X920503Y689960D01*
X920500Y689921D01*
G01X920639Y693268D02*
X920611Y693264D01*
X920586Y693253D01*
X920562Y693235D01*
X920541Y693210D01*
X920524Y693180D01*
X920511Y693146D01*
X920503Y693110D01*
X920500Y693071D01*
G01X920639Y696417D02*
X920611Y696413D01*
X920586Y696402D01*
X920562Y696384D01*
X920541Y696359D01*
X920524Y696330D01*
X920511Y696296D01*
X920503Y696259D01*
X920500Y696220D01*
G01X920639Y699567D02*
X920611Y699563D01*
X920586Y699552D01*
X920562Y699534D01*
X920541Y699509D01*
X920524Y699480D01*
X920511Y699446D01*
X920503Y699409D01*
X920500Y699370D01*
G01X925935Y645433D02*
X919323D01*
G01Y645827D02*
X925935D01*
G01X925687Y646024D02*
X919603D01*
G01X919889Y646518D02*
X925697D01*
G01X919626Y646715D02*
X925944D01*
G01Y647699D02*
X919626D01*
G01X919889Y647896D02*
X925697D01*
G01X925687Y648386D02*
X919603D01*
G01X925935Y648583D02*
X919323D01*
G01Y648976D02*
X925935D01*
G01X925687Y649173D02*
X919603D01*
G01X919889Y649667D02*
X925697D01*
G01X919626Y649864D02*
X925944D01*
G01Y650848D02*
X919626D01*
G01X919889Y651045D02*
X925697D01*
G01X925687Y651535D02*
X919603D01*
G01X925935Y651732D02*
X919323D01*
G01Y652126D02*
X925935D01*
G01X925687Y652323D02*
X919603D01*
G01X919889Y652817D02*
X925697D01*
G01X919626Y653014D02*
X925944D01*
G01Y653998D02*
X919626D01*
G01X919889Y654195D02*
X925697D01*
G01X925687Y654685D02*
X919603D01*
G01X925935Y654882D02*
X919323D01*
G01Y655276D02*
X925935D01*
G01X925687Y655472D02*
X919603D01*
G01X919889Y655967D02*
X925697D01*
G01X919626Y656163D02*
X925944D01*
G01Y657148D02*
X919626D01*
G01X919889Y657344D02*
X925697D01*
G01X925687Y657835D02*
X919603D01*
G01X925935Y658031D02*
X919323D01*
G01Y658425D02*
X925935D01*
G01X925687Y658622D02*
X919603D01*
G01X919889Y659116D02*
X925697D01*
G01X919626Y659313D02*
X925944D01*
G01Y660297D02*
X919626D01*
G01X919889Y660494D02*
X925697D01*
G01X925687Y660984D02*
X919603D01*
G01X925935Y661181D02*
X919323D01*
G01Y661575D02*
X925935D01*
G01X925687Y661772D02*
X919603D01*
G01X923452Y662854D02*
X929921D01*
G01X925757Y663642D02*
X919844D01*
G01X925687Y664134D02*
X919603D01*
G01X919420Y664232D02*
X926162D01*
G01X925935Y664331D02*
X919323D01*
G01X919420Y664626D02*
X926162D01*
G01X919323Y664724D02*
X925935D01*
G01X925687Y664921D02*
X919603D01*
G01X925757Y665217D02*
X919844D01*
G01X925687Y667283D02*
X919603D01*
G01X925935Y667480D02*
X919323D01*
G01Y667874D02*
X925935D01*
G01X925687Y668071D02*
X919603D01*
G01X925657Y668642D02*
X919912D01*
G01X919485Y669232D02*
X926071D01*
G01X919485Y669626D02*
X926071D01*
G01X925657Y670217D02*
X919912D01*
G01X925687Y670433D02*
X919603D01*
G01X925935Y670630D02*
X919323D01*
G01Y671024D02*
X925935D01*
G01X925687Y671220D02*
X919603D01*
G01X925687Y673583D02*
X919603D01*
G01X925657Y673642D02*
X919912D01*
G01X925935Y673780D02*
X919323D01*
G01Y674173D02*
X925935D01*
G01X919485Y674232D02*
X926071D01*
G01X925687Y674370D02*
X919603D01*
G01X919485Y674626D02*
X926071D01*
G01X925657Y675217D02*
X919912D01*
G01X925687Y676732D02*
X919603D01*
G01X925935Y676929D02*
X919323D01*
G01Y677323D02*
X925935D01*
G01X925687Y677520D02*
X919603D01*
G01X927626Y678642D02*
X921880D01*
G01X921454Y679232D02*
X928040D01*
G01X921454Y679626D02*
X928040D01*
G01X925687Y679882D02*
X919603D01*
G01X925935Y680079D02*
X919323D01*
G01X927626Y680217D02*
X921880D01*
G01X919323Y680472D02*
X925935D01*
G01X925687Y680669D02*
X919603D01*
G01X925687Y683031D02*
X919603D01*
G01X925935Y683228D02*
X919323D01*
G01Y683622D02*
X925935D01*
G01X925657Y683642D02*
X919912D01*
G01X925687Y683819D02*
X919603D01*
G01X919485Y684232D02*
X926071D01*
G01X919485Y684626D02*
X926071D01*
G01X925657Y685217D02*
X919912D01*
G01X925687Y686181D02*
X919603D01*
G01X925935Y686378D02*
X919323D01*
G01Y686772D02*
X925935D01*
G01X925687Y686969D02*
X919603D01*
G01X925657Y688642D02*
X919912D01*
G01X919485Y689232D02*
X926071D01*
G01X925687Y689331D02*
X919603D01*
G01X925935Y689528D02*
X919323D01*
G01X919485Y689626D02*
X926071D01*
G01X919323Y689921D02*
X925935D01*
G01X925687Y690118D02*
X919603D01*
G01X925657Y690217D02*
X919912D01*
G01X925687Y692480D02*
X919603D01*
G01X925935Y692677D02*
X919323D01*
G01Y693071D02*
X925935D01*
G01X925687Y693268D02*
X919603D01*
G01X925657Y693642D02*
X919912D01*
G01X919485Y694232D02*
X926071D01*
G01X919485Y694626D02*
X926071D01*
G01X925657Y695217D02*
X919912D01*
G01X925687Y695630D02*
X919603D01*
G01X925935Y695827D02*
X919323D01*
G01Y696220D02*
X925935D01*
G01X925687Y696417D02*
X919603D01*
G01X925657Y698642D02*
X919912D01*
G01X925687Y698780D02*
X919603D01*
G01X925935Y698976D02*
X919323D01*
G01X919485Y699232D02*
X926071D01*
G01X919323Y699370D02*
X925935D01*
G01X925687Y699567D02*
X919603D01*
G01X919485Y699626D02*
X926071D01*
G01X925657Y700217D02*
X919912D01*
G01X925687Y701929D02*
X919603D01*
G01X925935Y702126D02*
X919323D01*
G01X920717Y646518D02*
X920688Y646522D01*
X920660Y646533D01*
X920635Y646551D01*
X920612Y646576D01*
X920594Y646605D01*
X920580Y646639D01*
X920572Y646676D01*
X920569Y646715D01*
G01X920717Y649667D02*
X920688Y649671D01*
X920660Y649682D01*
X920635Y649700D01*
X920612Y649725D01*
X920594Y649755D01*
X920580Y649789D01*
X920572Y649825D01*
X920569Y649864D01*
G01X920717Y652817D02*
X920688Y652821D01*
X920660Y652832D01*
X920635Y652850D01*
X920612Y652875D01*
X920594Y652904D01*
X920580Y652938D01*
X920572Y652975D01*
X920569Y653014D01*
G01X920717Y655967D02*
X920688Y655970D01*
X920660Y655981D01*
X920635Y656000D01*
X920612Y656024D01*
X920594Y656054D01*
X920580Y656088D01*
X920572Y656124D01*
X920569Y656163D01*
G01X920717Y659116D02*
X920688Y659120D01*
X920660Y659131D01*
X920635Y659149D01*
X920612Y659174D01*
X920594Y659204D01*
X920580Y659237D01*
X920572Y659274D01*
X920569Y659313D01*
G01X925687Y693268D02*
X925814Y693240D01*
X925903Y693167D01*
X925935Y693071D01*
G01X921753Y646518D02*
X921747Y646522D01*
X921741Y646533D01*
X921735Y646551D01*
X921730Y646576D01*
X921726Y646605D01*
X921723Y646639D01*
X921721Y646676D01*
X921720Y646715D01*
G01X921753Y649667D02*
X921747Y649671D01*
X921741Y649682D01*
X921735Y649700D01*
X921730Y649725D01*
X921726Y649755D01*
X921723Y649789D01*
X921721Y649825D01*
X921720Y649864D01*
G01X921753Y652817D02*
X921747Y652821D01*
X921741Y652832D01*
X921735Y652850D01*
X921730Y652875D01*
X921726Y652904D01*
X921723Y652938D01*
X921721Y652975D01*
X921720Y653014D01*
G01X921753Y655967D02*
X921747Y655970D01*
X921741Y655981D01*
X921735Y656000D01*
X921730Y656024D01*
X921726Y656054D01*
X921723Y656088D01*
X921721Y656124D01*
X921720Y656163D01*
G01X921753Y659116D02*
X921747Y659120D01*
X921741Y659131D01*
X921735Y659149D01*
X921730Y659174D01*
X921726Y659204D01*
X921723Y659237D01*
X921721Y659274D01*
X921720Y659313D01*
G01X921090Y648386D02*
X921051Y648412D01*
X921023Y648484D01*
X921013Y648583D01*
G01X921090Y651535D02*
X921051Y651562D01*
X921023Y651634D01*
X921013Y651732D01*
G01X921090Y654685D02*
X921051Y654711D01*
X921023Y654783D01*
X921013Y654882D01*
G01X921090Y657835D02*
X921051Y657861D01*
X921023Y657933D01*
X921013Y658031D01*
G01X921090Y660984D02*
X921051Y661011D01*
X921023Y661083D01*
X921013Y661181D01*
G01X921090Y664134D02*
X921051Y664160D01*
X921023Y664232D01*
X921013Y664331D01*
G01X921090Y667283D02*
X921051Y667310D01*
X921023Y667382D01*
X921013Y667480D01*
G01X921090Y670433D02*
X921051Y670459D01*
X921023Y670531D01*
X921013Y670630D01*
G01X921090Y673583D02*
X921051Y673609D01*
X921023Y673681D01*
X921013Y673780D01*
G01X921090Y676732D02*
X921051Y676759D01*
X921023Y676831D01*
X921013Y676929D01*
G01X921090Y679882D02*
X921051Y679908D01*
X921023Y679980D01*
X921013Y680079D01*
G01X921090Y683031D02*
X921051Y683058D01*
X921023Y683130D01*
X921013Y683228D01*
G01X921090Y686181D02*
X921051Y686207D01*
X921023Y686280D01*
X921013Y686378D01*
G01X921090Y689331D02*
X921051Y689357D01*
X921023Y689429D01*
X921013Y689528D01*
G01X921090Y692480D02*
X921051Y692507D01*
X921023Y692579D01*
X921013Y692677D01*
G01X921090Y695630D02*
X921051Y695656D01*
X921023Y695728D01*
X921013Y695827D01*
G01X921090Y698780D02*
X921051Y698806D01*
X921023Y698878D01*
X921013Y698976D01*
G01X921090Y701929D02*
X921051Y701956D01*
X921023Y702028D01*
X921013Y702126D01*
G01X919912Y668642D02*
X919485Y669232D01*
G01X919912Y673642D02*
X919485Y674232D01*
G01X921880Y678642D02*
X921454Y679232D01*
G01X919912Y683642D02*
X919485Y684232D01*
G01X919912Y688642D02*
X919485Y689232D01*
G01X919912Y693642D02*
X919485Y694232D01*
G01X919912Y698642D02*
X919485Y699232D01*
G01X919844Y663642D02*
X919420Y664232D01*
G01X926071Y669626D02*
X925934Y669824D01*
X925796Y670020D01*
X925657Y670217D01*
G01X926071Y674626D02*
X925934Y674824D01*
X925796Y675020D01*
X925657Y675217D01*
G01X928040Y679626D02*
X927903Y679824D01*
X927765Y680020D01*
X927626Y680217D01*
G01X926162Y664626D02*
X926028Y664823D01*
X925893Y665020D01*
X925757Y665217D01*
G01X926071Y684626D02*
X925934Y684824D01*
X925796Y685020D01*
X925657Y685217D01*
G01X926071Y689626D02*
X925934Y689824D01*
X925796Y690020D01*
X925657Y690217D01*
G01X926071Y694626D02*
X925934Y694824D01*
X925796Y695020D01*
X925657Y695217D01*
G01X926071Y699626D02*
X925934Y699824D01*
X925796Y700020D01*
X925657Y700217D01*
G01X920602Y663642D02*
X920329Y664232D01*
G01X920602Y668642D02*
X920329Y669232D01*
G01X920602Y673642D02*
X920329Y674232D01*
G01X922570Y678642D02*
X922298Y679232D01*
G01X920602Y683642D02*
X920329Y684232D01*
G01X920602Y688642D02*
X920329Y689232D01*
G01X920602Y693642D02*
X920329Y694232D01*
G01X920602Y698642D02*
X920329Y699232D01*
G01X925944Y647699D02*
X925911Y647798D01*
X925823Y647869D01*
X925697Y647896D01*
G01X925944Y650848D02*
X925911Y650948D01*
X925823Y651019D01*
X925697Y651045D01*
G01X925944Y653998D02*
X925911Y654097D01*
X925823Y654168D01*
X925697Y654195D01*
G01X925944Y657148D02*
X925911Y657247D01*
X925823Y657318D01*
X925697Y657344D01*
G01X925944Y660297D02*
X925911Y660396D01*
X925823Y660467D01*
X925697Y660494D01*
G01X925935Y645827D02*
X925903Y645924D01*
X925815Y645996D01*
X925687Y646024D01*
G01X925935Y648976D02*
X925903Y649073D01*
X925815Y649145D01*
X925687Y649173D01*
G01X925935Y652126D02*
X925903Y652223D01*
X925815Y652295D01*
X925687Y652323D01*
G01X925935Y655276D02*
X925903Y655372D01*
X925815Y655444D01*
X925687Y655472D01*
G01X925935Y658425D02*
X925903Y658522D01*
X925815Y658594D01*
X925687Y658622D01*
G01X925935Y661575D02*
X925903Y661672D01*
X925815Y661744D01*
X925687Y661772D01*
G01X925935Y664724D02*
X925903Y664821D01*
X925815Y664893D01*
X925687Y664921D01*
G01X925935Y667874D02*
X925903Y667971D01*
X925815Y668043D01*
X925687Y668071D01*
G01X925935Y671024D02*
X925903Y671120D01*
X925815Y671193D01*
X925687Y671220D01*
G01X925935Y674173D02*
X925903Y674270D01*
X925815Y674342D01*
X925687Y674370D01*
G01X925935Y677323D02*
X925903Y677420D01*
X925815Y677492D01*
X925687Y677520D01*
G01X925935Y680472D02*
X925903Y680569D01*
X925815Y680641D01*
X925687Y680669D01*
G01X925935Y683622D02*
X925903Y683719D01*
X925815Y683791D01*
X925687Y683819D01*
G01X925935Y686772D02*
X925903Y686869D01*
X925815Y686941D01*
X925687Y686969D01*
G01X925935Y689921D02*
X925903Y690018D01*
X925815Y690090D01*
X925687Y690118D01*
G01X925935Y696220D02*
X925903Y696317D01*
X925815Y696389D01*
X925687Y696417D01*
G01X925935Y699370D02*
X925903Y699467D01*
X925815Y699539D01*
X925687Y699567D01*
G01X920500Y648583D02*
X920503Y648544D01*
X920511Y648507D01*
X920523Y648474D01*
X920541Y648443D01*
X920561Y648419D01*
X920585Y648401D01*
X920611Y648390D01*
X920639Y648386D01*
G01X920500Y651732D02*
X920503Y651694D01*
X920511Y651657D01*
X920523Y651623D01*
X920541Y651593D01*
X920561Y651569D01*
X920585Y651550D01*
X920611Y651539D01*
X920639Y651535D01*
G01X920500Y654882D02*
X920503Y654844D01*
X920511Y654807D01*
X920523Y654773D01*
X920541Y654743D01*
X920561Y654718D01*
X920585Y654700D01*
X920611Y654689D01*
X920639Y654685D01*
G01X920500Y658031D02*
X920503Y657993D01*
X920511Y657956D01*
X920523Y657922D01*
X920541Y657892D01*
X920561Y657868D01*
X920585Y657850D01*
X920611Y657839D01*
X920639Y657835D01*
G01X920500Y661181D02*
X920503Y661143D01*
X920511Y661106D01*
X920523Y661072D01*
X920541Y661042D01*
X920561Y661017D01*
X920585Y660999D01*
X920611Y660988D01*
X920639Y660984D01*
G01X920500Y664331D02*
X920503Y664293D01*
X920511Y664256D01*
X920523Y664222D01*
X920541Y664191D01*
X920561Y664167D01*
X920585Y664149D01*
X920611Y664138D01*
X920639Y664134D01*
G01X920500Y667480D02*
X920503Y667442D01*
X920511Y667405D01*
X920523Y667371D01*
X920541Y667341D01*
X920561Y667317D01*
X920585Y667298D01*
X920611Y667287D01*
X920639Y667283D01*
G01X920500Y670630D02*
X920503Y670592D01*
X920511Y670555D01*
X920523Y670521D01*
X920541Y670491D01*
X920561Y670466D01*
X920585Y670448D01*
X920611Y670437D01*
X920639Y670433D01*
G01X920500Y673780D02*
X920503Y673741D01*
X920511Y673704D01*
X920523Y673670D01*
X920541Y673640D01*
X920561Y673616D01*
X920585Y673598D01*
X920611Y673587D01*
X920639Y673583D01*
G01X920500Y676929D02*
X920503Y676891D01*
X920511Y676854D01*
X920523Y676820D01*
X920541Y676790D01*
X920561Y676765D01*
X920585Y676747D01*
X920611Y676736D01*
X920639Y676732D01*
G01X920500Y680079D02*
X920503Y680041D01*
X920511Y680004D01*
X920523Y679970D01*
X920541Y679939D01*
X920561Y679915D01*
X920585Y679897D01*
X920611Y679886D01*
X920639Y679882D01*
G01X920500Y683228D02*
X920503Y683190D01*
X920511Y683153D01*
X920523Y683119D01*
X920541Y683089D01*
X920561Y683065D01*
X920585Y683046D01*
X920611Y683035D01*
X920639Y683031D01*
G01X920500Y686378D02*
X920503Y686340D01*
X920511Y686303D01*
X920523Y686269D01*
X920541Y686239D01*
X920561Y686214D01*
X920585Y686196D01*
X920611Y686185D01*
X920639Y686181D01*
G01X920500Y689528D02*
X920503Y689489D01*
X920511Y689452D01*
X920523Y689419D01*
X920541Y689388D01*
X920561Y689364D01*
X920585Y689346D01*
X920611Y689335D01*
X920639Y689331D01*
G01X920500Y692677D02*
X920503Y692639D01*
X920511Y692602D01*
X920523Y692568D01*
X920541Y692538D01*
X920561Y692513D01*
X920585Y692495D01*
X920611Y692484D01*
X920639Y692480D01*
G01X920500Y695827D02*
X920503Y695789D01*
X920511Y695752D01*
X920523Y695718D01*
X920541Y695687D01*
X920561Y695663D01*
X920585Y695645D01*
X920611Y695634D01*
X920639Y695630D01*
G01X920500Y698976D02*
X920503Y698938D01*
X920511Y698901D01*
X920523Y698867D01*
X920541Y698837D01*
X920561Y698813D01*
X920585Y698794D01*
X920611Y698783D01*
X920639Y698780D01*
G01X920500Y702126D02*
X920503Y702088D01*
X920511Y702051D01*
X920523Y702017D01*
X920541Y701987D01*
X920561Y701962D01*
X920585Y701944D01*
X920611Y701933D01*
X920639Y701929D01*
G01X921454Y664232D02*
X921531Y663642D01*
G01X921454Y669232D02*
X921531Y668642D01*
G01X921454Y674232D02*
X921531Y673642D01*
G01X921454Y684232D02*
X921531Y683642D01*
G01X921454Y689232D02*
X921531Y688642D01*
G01X923422Y679232D02*
X923500Y678642D01*
G01X921454Y694232D02*
X921531Y693642D01*
G01X921454Y699232D02*
X921531Y698642D01*
G01X919323Y699370D02*
Y698976D01*
G01Y702520D02*
Y702126D01*
G01Y696220D02*
Y695827D01*
G01Y689921D02*
Y689528D01*
G01Y693071D02*
Y692677D01*
G01Y686772D02*
Y686378D01*
G01Y680472D02*
Y680079D01*
G01Y683622D02*
Y683228D01*
G01Y677323D02*
Y676929D01*
G01Y674173D02*
Y673780D01*
G01Y671024D02*
Y670630D01*
G01Y667874D02*
Y667480D01*
G01Y664724D02*
Y664331D01*
G01Y661575D02*
Y661181D01*
G01Y658425D02*
Y658031D01*
G01Y652126D02*
Y651732D01*
G01Y655276D02*
Y654882D01*
G01Y648976D02*
Y648583D01*
G01Y645827D02*
Y645433D01*
G01X919420Y664232D02*
Y664626D01*
G01X919485Y669232D02*
Y669626D01*
G01Y674232D02*
Y674626D01*
G01Y684232D02*
Y684626D01*
G01Y689232D02*
Y689626D01*
G01Y694232D02*
Y694626D01*
G01Y699232D02*
Y699626D01*
G01X919626Y646715D02*
Y647699D01*
G01Y649864D02*
Y650848D01*
G01Y653014D02*
Y653998D01*
G01Y659313D02*
Y660297D01*
G01Y656163D02*
Y657148D01*
G01X920329Y664232D02*
Y664626D01*
G01Y669232D02*
Y669626D01*
G01Y674232D02*
Y674626D01*
G01Y684232D02*
Y684626D01*
G01Y689232D02*
Y689626D01*
G01Y694232D02*
Y694626D01*
G01Y699232D02*
Y699626D01*
G01X920500Y699370D02*
Y698976D01*
G01Y702520D02*
Y702126D01*
G01Y696220D02*
Y695827D01*
G01Y689921D02*
Y689528D01*
G01Y693071D02*
Y692677D01*
G01Y686772D02*
Y686378D01*
G01Y680472D02*
Y680079D01*
G01Y683622D02*
Y683228D01*
G01Y677323D02*
Y676929D01*
G01Y674173D02*
Y673780D01*
G01Y671024D02*
Y670630D01*
G01Y667874D02*
Y667480D01*
G01Y664724D02*
Y664331D01*
G01Y661575D02*
Y661181D01*
G01Y658425D02*
Y658031D01*
G01Y652126D02*
Y651732D01*
G01Y655276D02*
Y654882D01*
G01Y648976D02*
Y648583D01*
G01Y645827D02*
Y645433D01*
G01X920569Y646715D02*
Y647699D01*
G01Y649864D02*
Y650848D01*
G01Y653014D02*
Y653998D01*
G01Y659313D02*
Y660297D01*
G01Y656163D02*
Y657148D01*
G01X921013Y645433D02*
Y645827D01*
G01Y648583D02*
Y648976D01*
G01Y651732D02*
Y652126D01*
G01Y654882D02*
Y655276D01*
G01Y658031D02*
Y658425D01*
G01Y664331D02*
Y664724D01*
G01Y661181D02*
Y661575D01*
G01Y667480D02*
Y667874D01*
G01Y673780D02*
Y674173D01*
G01Y670630D02*
Y671024D01*
G01Y676929D02*
Y677323D01*
G01Y680079D02*
Y680472D01*
G01Y683228D02*
Y683622D01*
G01Y686378D02*
Y686772D01*
G01Y689528D02*
Y689921D01*
G01Y692677D02*
Y693071D01*
G01Y695827D02*
Y696220D01*
G01Y698976D02*
Y699370D01*
G01Y702126D02*
Y702520D01*
G01X921454Y699626D02*
Y699232D01*
G01Y694626D02*
Y694232D01*
G01Y689626D02*
Y689232D01*
G01Y684626D02*
Y684232D01*
G01Y674626D02*
Y674232D01*
G01Y669626D02*
Y669232D01*
G01Y664626D02*
Y664232D01*
G01Y679232D02*
Y679626D01*
G01X921720Y646715D02*
Y647699D01*
G01Y649864D02*
Y650848D01*
G01Y653014D02*
Y653998D01*
G01Y659313D02*
Y660297D01*
G01Y656163D02*
Y657148D01*
G01X922298Y679232D02*
Y679626D01*
G01X923422D02*
Y679232D01*
G01X923452Y662854D02*
Y661673D01*
G01X925935Y645433D02*
Y645827D01*
G01Y648583D02*
Y648976D01*
G01Y651732D02*
Y652126D01*
G01Y654882D02*
Y655276D01*
G01Y658031D02*
Y658425D01*
G01Y664331D02*
Y664724D01*
G01Y661181D02*
Y661575D01*
G01Y667480D02*
Y667874D01*
G01Y673780D02*
Y674173D01*
G01Y670630D02*
Y671024D01*
G01Y676929D02*
Y677323D01*
G01Y680079D02*
Y680472D01*
G01Y683228D02*
Y683622D01*
G01Y686378D02*
Y686772D01*
G01Y689528D02*
Y689921D01*
G01Y692677D02*
Y693071D01*
G01Y695827D02*
Y696220D01*
G01Y698976D02*
Y699370D01*
G01Y702126D02*
Y702520D01*
G01X925944Y660297D02*
Y659313D01*
G01Y657148D02*
Y656163D01*
G01Y653998D02*
Y653014D01*
G01Y647699D02*
Y646715D01*
G01Y650848D02*
Y649864D01*
G01X926071Y699626D02*
Y699232D01*
G01Y694626D02*
Y694232D01*
G01Y689626D02*
Y689232D01*
G01Y684626D02*
Y684232D01*
G01Y674626D02*
Y674232D01*
G01Y669626D02*
Y669232D01*
G01X926162Y664626D02*
Y664232D01*
G01X928040Y679626D02*
Y679232D01*
G01X928740Y739035D02*
Y668130D01*
G01X928910D02*
Y662650D01*
G01X921720Y660297D02*
X921721Y660335D01*
X921723Y660372D01*
X921726Y660406D01*
X921730Y660437D01*
X921735Y660461D01*
X921741Y660479D01*
X921747Y660490D01*
X921753Y660494D01*
G01X921720Y657148D02*
X921721Y657186D01*
X921723Y657223D01*
X921726Y657257D01*
X921730Y657287D01*
X921735Y657311D01*
X921741Y657330D01*
X921747Y657341D01*
X921753Y657344D01*
G01X921720Y653998D02*
X921721Y654036D01*
X921723Y654073D01*
X921726Y654107D01*
X921730Y654137D01*
X921735Y654162D01*
X921741Y654180D01*
X921747Y654191D01*
X921753Y654195D01*
G01X921720Y650848D02*
X921721Y650887D01*
X921723Y650924D01*
X921726Y650957D01*
X921730Y650988D01*
X921735Y651012D01*
X921741Y651030D01*
X921747Y651041D01*
X921753Y651045D01*
G01X921720Y647699D02*
X921721Y647737D01*
X921723Y647774D01*
X921726Y647808D01*
X921730Y647838D01*
X921735Y647863D01*
X921741Y647881D01*
X921747Y647892D01*
X921753Y647896D01*
G01X920569Y660297D02*
X920571Y660335D01*
X920580Y660372D01*
X920593Y660406D01*
X920612Y660437D01*
X920634Y660461D01*
X920659Y660479D01*
X920687Y660490D01*
X920717Y660494D01*
G01X920569Y657148D02*
X920571Y657186D01*
X920580Y657223D01*
X920593Y657257D01*
X920612Y657287D01*
X920634Y657311D01*
X920659Y657330D01*
X920687Y657341D01*
X920717Y657344D01*
G01X920569Y653998D02*
X920571Y654036D01*
X920580Y654073D01*
X920593Y654107D01*
X920612Y654137D01*
X920634Y654162D01*
X920659Y654180D01*
X920687Y654191D01*
X920717Y654195D01*
G01X920569Y650848D02*
X920571Y650887D01*
X920580Y650924D01*
X920593Y650957D01*
X920612Y650988D01*
X920634Y651012D01*
X920659Y651030D01*
X920687Y651041D01*
X920717Y651045D01*
G01X920569Y647699D02*
X920571Y647737D01*
X920580Y647774D01*
X920593Y647808D01*
X920612Y647838D01*
X920634Y647863D01*
X920659Y647881D01*
X920687Y647892D01*
X920717Y647896D01*
G01X921013Y699370D02*
X921023Y699469D01*
X921051Y699541D01*
X921090Y699567D01*
G01X921013Y696220D02*
X921023Y696319D01*
X921051Y696391D01*
X921090Y696417D01*
G01X921013Y693071D02*
X921023Y693169D01*
X921051Y693241D01*
X921090Y693268D01*
G01X921013Y689921D02*
X921023Y690020D01*
X921051Y690092D01*
X921090Y690118D01*
G01X921013Y686772D02*
X921023Y686870D01*
X921051Y686942D01*
X921090Y686969D01*
G01X921013Y683622D02*
X921023Y683720D01*
X921051Y683793D01*
X921090Y683819D01*
G01X921013Y680472D02*
X921023Y680571D01*
X921051Y680643D01*
X921090Y680669D01*
G01X921013Y677323D02*
X921023Y677421D01*
X921051Y677493D01*
X921090Y677520D01*
G01X921013Y674173D02*
X921023Y674272D01*
X921051Y674344D01*
X921090Y674370D01*
G01X921013Y671024D02*
X921023Y671122D01*
X921051Y671194D01*
X921090Y671220D01*
G01X921013Y667874D02*
X921023Y667972D01*
X921051Y668044D01*
X921090Y668071D01*
G01X921013Y664724D02*
X921023Y664823D01*
X921051Y664895D01*
X921090Y664921D01*
G01X921013Y661575D02*
X921023Y661673D01*
X921051Y661745D01*
X921090Y661772D01*
G01X921013Y658425D02*
X921023Y658524D01*
X921051Y658596D01*
X921090Y658622D01*
G01X921013Y652126D02*
X921023Y652224D01*
X921051Y652296D01*
X921090Y652323D01*
G01X921013Y648976D02*
X921023Y649075D01*
X921051Y649147D01*
X921090Y649173D01*
G01X921013Y645827D02*
X921023Y645925D01*
X921051Y645997D01*
X921090Y646024D01*
G01X921454Y699626D02*
X921531Y700217D01*
G01X921454Y694626D02*
X921531Y695217D01*
G01X921454Y689626D02*
X921531Y690217D01*
G01X921454Y684626D02*
X921531Y685217D01*
G01X921454Y674626D02*
X921531Y675217D01*
G01X921454Y669626D02*
X921531Y670217D01*
G01X923422Y679626D02*
X923500Y680217D01*
G01X921454Y664626D02*
X921531Y665217D01*
G01X925935Y692677D02*
X925901Y692578D01*
X925813Y692507D01*
X925687Y692480D01*
G01X920329Y699626D02*
X920602Y700217D01*
G01X920329Y694626D02*
X920602Y695217D01*
G01X920329Y689626D02*
X920602Y690217D01*
G01X920329Y684626D02*
X920602Y685217D01*
G01X922298Y679626D02*
X922570Y680217D01*
G01X920329Y674626D02*
X920602Y675217D01*
G01X920329Y669626D02*
X920602Y670217D01*
G01X920329Y664626D02*
X920602Y665217D01*
G01X925757Y663642D02*
X925893Y663838D01*
X926028Y664035D01*
X926162Y664232D01*
G01X925657Y698642D02*
X925796Y698838D01*
X925934Y699035D01*
X926071Y699232D01*
G01X925657Y693642D02*
X925796Y693838D01*
X925934Y694035D01*
X926071Y694232D01*
G01X925657Y688642D02*
X925796Y688838D01*
X925934Y689035D01*
X926071Y689232D01*
G01X925657Y683642D02*
X925796Y683838D01*
X925934Y684035D01*
X926071Y684232D01*
G01X927626Y678642D02*
X927765Y678838D01*
X927903Y679035D01*
X928040Y679232D01*
G01X925657Y673642D02*
X925796Y673838D01*
X925934Y674035D01*
X926071Y674232D01*
G01X925657Y668642D02*
X925796Y668838D01*
X925934Y669035D01*
X926071Y669232D01*
G01X919844Y665217D02*
X919420Y664626D01*
G01X919912Y700217D02*
X919485Y699626D01*
G01X919912Y695217D02*
X919485Y694626D01*
G01X919912Y690217D02*
X919485Y689626D01*
G01X919912Y685217D02*
X919485Y684626D01*
G01X921880Y680217D02*
X921454Y679626D01*
G01X919912Y675217D02*
X919485Y674626D01*
G01X919912Y670217D02*
X919485Y669626D01*
G01X929921Y663661D02*
X927953Y661693D01*
G01X921090Y655472D02*
X921051Y655446D01*
X921023Y655374D01*
X921013Y655276D01*
G01X925687Y632638D02*
X925815Y632665D01*
X925904Y632738D01*
X925935Y632835D01*
G01X925687Y635787D02*
X925815Y635815D01*
X925904Y635888D01*
X925935Y635984D01*
G01X925687Y638937D02*
X925815Y638965D01*
X925904Y639037D01*
X925935Y639134D01*
G01X925687Y642087D02*
X925815Y642114D01*
X925904Y642187D01*
X925935Y642283D01*
G01X925687Y645236D02*
X925815Y645264D01*
X925904Y645337D01*
X925935Y645433D01*
G01X925697Y643368D02*
X925824Y643396D01*
X925913Y643468D01*
X925944Y643565D01*
G01X920639Y630276D02*
X920611Y630272D01*
X920586Y630261D01*
X920562Y630243D01*
X920541Y630218D01*
X920524Y630188D01*
X920511Y630154D01*
X920503Y630118D01*
X920500Y630079D01*
G01X920639Y633425D02*
X920611Y633421D01*
X920586Y633410D01*
X920562Y633392D01*
X920541Y633367D01*
X920524Y633338D01*
X920511Y633304D01*
X920503Y633267D01*
X920500Y633228D01*
G01X920639Y636575D02*
X920611Y636571D01*
X920586Y636560D01*
X920562Y636542D01*
X920541Y636517D01*
X920524Y636487D01*
X920511Y636454D01*
X920503Y636417D01*
X920500Y636378D01*
G01X920639Y639724D02*
X920611Y639720D01*
X920586Y639709D01*
X920562Y639691D01*
X920541Y639667D01*
X920524Y639637D01*
X920511Y639603D01*
X920503Y639567D01*
X920500Y639528D01*
G01X920639Y642874D02*
X920611Y642870D01*
X920586Y642859D01*
X920562Y642841D01*
X920541Y642816D01*
X920524Y642787D01*
X920511Y642753D01*
X920503Y642716D01*
X920500Y642677D01*
G01X919485Y629626D02*
X926071D01*
G01X925935Y629685D02*
X919323D01*
G01Y630079D02*
X925935D01*
G01X925657Y630217D02*
X919912D01*
G01X925687Y630276D02*
X919603D01*
G01X925687Y632638D02*
X919603D01*
G01X925935Y632835D02*
X919323D01*
G01Y633228D02*
X925935D01*
G01X925687Y633425D02*
X919603D01*
G01X925657Y633642D02*
X919912D01*
G01X919485Y634232D02*
X926071D01*
G01X919485Y634626D02*
X926071D01*
G01X925657Y635217D02*
X919912D01*
G01X925687Y635787D02*
X919603D01*
G01X925935Y635984D02*
X919323D01*
G01Y636378D02*
X925935D01*
G01X925687Y636575D02*
X919603D01*
G01X925757Y638642D02*
X919844D01*
G01X925687Y638937D02*
X919603D01*
G01X925935Y639134D02*
X919323D01*
G01X919420Y639232D02*
X926162D01*
G01X919323Y639528D02*
X925935D01*
G01X919420Y639626D02*
X926162D01*
G01X925687Y639724D02*
X919603D01*
G01X925757Y640217D02*
X919844D01*
G01X929921Y641004D02*
X923452D01*
G01X925687Y642087D02*
X919603D01*
G01X925935Y642283D02*
X919323D01*
G01Y642677D02*
X925935D01*
G01X925687Y642874D02*
X919603D01*
G01X919889Y643368D02*
X925697D01*
G01X919626Y643565D02*
X925944D01*
G01Y644549D02*
X919626D01*
G01X919889Y644746D02*
X925697D01*
G01X925687Y645236D02*
X919603D01*
G01X920717Y643368D02*
X920688Y643372D01*
X920660Y643383D01*
X920635Y643401D01*
X920612Y643426D01*
X920594Y643456D01*
X920580Y643489D01*
X920572Y643526D01*
X920569Y643565D01*
G01X921753Y643368D02*
X921747Y643372D01*
X921741Y643383D01*
X921735Y643401D01*
X921730Y643426D01*
X921726Y643456D01*
X921723Y643489D01*
X921721Y643526D01*
X921720Y643565D01*
G01X921090Y632638D02*
X921051Y632664D01*
X921023Y632736D01*
X921013Y632835D01*
G01X921090Y635787D02*
X921051Y635814D01*
X921023Y635886D01*
X921013Y635984D01*
G01X921090Y638937D02*
X921051Y638963D01*
X921023Y639035D01*
X921013Y639134D01*
G01X921090Y642087D02*
X921051Y642113D01*
X921023Y642185D01*
X921013Y642283D01*
G01X921090Y645236D02*
X921051Y645263D01*
X921023Y645335D01*
X921013Y645433D01*
G01X927953Y642165D02*
X929921Y640197D01*
G01X919912Y633642D02*
X919485Y634232D01*
G01X919844Y638642D02*
X919420Y639232D01*
G01X926071Y634626D02*
X925934Y634824D01*
X925796Y635020D01*
X925657Y635217D01*
G01X926162Y639626D02*
X926028Y639823D01*
X925893Y640020D01*
X925757Y640217D01*
G01X920602Y633642D02*
X920329Y634232D01*
G01X920602Y638642D02*
X920329Y639232D01*
G01X925944Y644549D02*
X925911Y644648D01*
X925823Y644719D01*
X925697Y644746D01*
G01X925935Y630079D02*
X925903Y630176D01*
X925815Y630248D01*
X925687Y630276D01*
G01X925935Y633228D02*
X925903Y633325D01*
X925815Y633397D01*
X925687Y633425D01*
G01X925935Y636378D02*
X925903Y636475D01*
X925815Y636547D01*
X925687Y636575D01*
G01X925935Y639528D02*
X925903Y639624D01*
X925815Y639696D01*
X925687Y639724D01*
G01X925935Y642677D02*
X925903Y642774D01*
X925815Y642846D01*
X925687Y642874D01*
G01X920500Y632835D02*
X920503Y632796D01*
X920511Y632759D01*
X920523Y632726D01*
X920541Y632695D01*
X920561Y632671D01*
X920585Y632653D01*
X920611Y632642D01*
X920639Y632638D01*
G01X920500Y635984D02*
X920503Y635946D01*
X920511Y635909D01*
X920523Y635875D01*
X920541Y635845D01*
X920561Y635820D01*
X920585Y635802D01*
X920611Y635791D01*
X920639Y635787D01*
G01X920500Y639134D02*
X920503Y639096D01*
X920511Y639059D01*
X920523Y639025D01*
X920541Y638994D01*
X920561Y638970D01*
X920585Y638952D01*
X920611Y638941D01*
X920639Y638937D01*
G01X920500Y642283D02*
X920503Y642245D01*
X920511Y642208D01*
X920523Y642174D01*
X920541Y642144D01*
X920561Y642120D01*
X920585Y642102D01*
X920611Y642091D01*
X920639Y642087D01*
G01X920500Y645433D02*
X920503Y645395D01*
X920511Y645358D01*
X920523Y645324D01*
X920541Y645294D01*
X920561Y645269D01*
X920585Y645251D01*
X920611Y645240D01*
X920639Y645236D01*
G01X921454Y634232D02*
X921531Y633642D01*
G01X921454Y639232D02*
X921531Y638642D01*
G01X919323Y642677D02*
Y642283D01*
G01Y639528D02*
Y639134D01*
G01Y636378D02*
Y635984D01*
G01Y633228D02*
Y632835D01*
G01Y630079D02*
Y629685D01*
G01X919420Y639232D02*
Y639626D01*
G01X919485Y634232D02*
Y634626D01*
G01X919626Y643565D02*
Y644549D01*
G01X920329Y634232D02*
Y634626D01*
G01Y639232D02*
Y639626D01*
G01X920500Y642677D02*
Y642283D01*
G01Y639528D02*
Y639134D01*
G01Y636378D02*
Y635984D01*
G01Y633228D02*
Y632835D01*
G01Y630079D02*
Y629685D01*
G01X920569Y643565D02*
Y644549D01*
G01X921013Y629685D02*
Y630079D01*
G01Y635984D02*
Y636378D01*
G01Y632835D02*
Y633228D01*
G01Y639134D02*
Y639528D01*
G01Y642283D02*
Y642677D01*
G01X921454Y639626D02*
Y639232D01*
G01Y634626D02*
Y634232D01*
G01X921720Y643565D02*
Y644549D01*
G01X923452Y642185D02*
Y641004D01*
G01X925935Y629685D02*
Y630079D01*
G01Y635984D02*
Y636378D01*
G01Y632835D02*
Y633228D01*
G01Y639134D02*
Y639528D01*
G01Y642283D02*
Y642677D01*
G01X925944Y644549D02*
Y643565D01*
G01X926071Y634626D02*
Y634232D01*
G01X926162Y639626D02*
Y639232D01*
G01X928740Y641004D02*
Y662854D01*
G01X928910Y641208D02*
Y635827D01*
G01X921720Y644549D02*
X921721Y644587D01*
X921723Y644624D01*
X921726Y644658D01*
X921730Y644689D01*
X921735Y644713D01*
X921741Y644731D01*
X921747Y644742D01*
X921753Y644746D01*
G01X920569Y644549D02*
X920571Y644587D01*
X920580Y644624D01*
X920593Y644658D01*
X920612Y644689D01*
X920634Y644713D01*
X920659Y644731D01*
X920687Y644742D01*
X920717Y644746D01*
G01X921013Y642677D02*
X921023Y642776D01*
X921051Y642848D01*
X921090Y642874D01*
G01X921013Y633228D02*
X921023Y633327D01*
X921051Y633399D01*
X921090Y633425D01*
G01X921013Y630079D02*
X921023Y630177D01*
X921051Y630249D01*
X921090Y630276D01*
G01X921454Y639626D02*
X921531Y640217D01*
G01X921454Y634626D02*
X921531Y635217D01*
G01X920329Y639626D02*
X920602Y640217D01*
G01X920329Y634626D02*
X920602Y635217D01*
G01X925757Y638642D02*
X925893Y638838D01*
X926028Y639035D01*
X926162Y639232D01*
G01X919844Y640217D02*
X919420Y639626D01*
G01X919912Y635217D02*
X919485Y634626D01*
G01X921090Y639724D02*
X921051Y639698D01*
X921023Y639626D01*
X921013Y639528D01*
G01X921090Y636575D02*
X921051Y636548D01*
X921023Y636476D01*
X921013Y636378D01*
G01X925657Y633642D02*
X925796Y633838D01*
X925934Y634035D01*
X926071Y634232D01*
G01X925687Y708228D02*
X925815Y708256D01*
X925904Y708329D01*
X925935Y708425D01*
G01X925687Y711378D02*
X925815Y711406D01*
X925904Y711478D01*
X925935Y711575D01*
G01X925687Y714528D02*
X925815Y714555D01*
X925904Y714628D01*
X925935Y714724D01*
G01X925687Y717677D02*
X925815Y717705D01*
X925904Y717778D01*
X925935Y717874D01*
G01X925687Y723976D02*
X925815Y724004D01*
X925904Y724077D01*
X925935Y724173D01*
G01X925687Y727126D02*
X925815Y727154D01*
X925904Y727226D01*
X925935Y727323D01*
G01X925687Y730276D02*
X925815Y730303D01*
X925904Y730376D01*
X925935Y730472D01*
G01X925687Y733425D02*
X925815Y733453D01*
X925904Y733526D01*
X925935Y733622D01*
G01X920639Y705866D02*
X920611Y705862D01*
X920586Y705851D01*
X920562Y705833D01*
X920541Y705808D01*
X920524Y705779D01*
X920511Y705745D01*
X920503Y705708D01*
X920500Y705669D01*
G01X920639Y709016D02*
X920611Y709012D01*
X920586Y709001D01*
X920562Y708983D01*
X920541Y708958D01*
X920524Y708928D01*
X920511Y708894D01*
X920503Y708858D01*
X920500Y708819D01*
G01X920639Y712165D02*
X920611Y712161D01*
X920586Y712150D01*
X920562Y712132D01*
X920541Y712107D01*
X920524Y712078D01*
X920511Y712044D01*
X920503Y712007D01*
X920500Y711969D01*
G01X920639Y715315D02*
X920611Y715311D01*
X920586Y715300D01*
X920562Y715282D01*
X920541Y715257D01*
X920524Y715228D01*
X920511Y715194D01*
X920503Y715157D01*
X920500Y715118D01*
G01X920639Y718465D02*
X920611Y718461D01*
X920586Y718450D01*
X920562Y718431D01*
X920541Y718407D01*
X920524Y718377D01*
X920511Y718343D01*
X920503Y718307D01*
X920500Y718268D01*
G01X920639Y721614D02*
X920611Y721610D01*
X920586Y721599D01*
X920562Y721581D01*
X920541Y721556D01*
X920524Y721527D01*
X920511Y721493D01*
X920503Y721456D01*
X920500Y721417D01*
G01X920639Y724764D02*
X920611Y724760D01*
X920586Y724749D01*
X920562Y724731D01*
X920541Y724706D01*
X920524Y724676D01*
X920511Y724643D01*
X920503Y724606D01*
X920500Y724567D01*
G01X920639Y727913D02*
X920611Y727909D01*
X920586Y727898D01*
X920562Y727880D01*
X920541Y727856D01*
X920524Y727826D01*
X920511Y727792D01*
X920503Y727756D01*
X920500Y727717D01*
G01X920639Y731063D02*
X920611Y731059D01*
X920586Y731048D01*
X920562Y731030D01*
X920541Y731005D01*
X920524Y730976D01*
X920511Y730942D01*
X920503Y730905D01*
X920500Y730866D01*
G01X920639Y734213D02*
X920611Y734209D01*
X920586Y734198D01*
X920562Y734180D01*
X920541Y734155D01*
X920524Y734125D01*
X920511Y734091D01*
X920503Y734055D01*
X920500Y734016D01*
G01X925935Y705276D02*
X919323D01*
G01Y705669D02*
X925935D01*
G01X925687Y705866D02*
X919603D01*
G01X925687Y708228D02*
X919603D01*
G01X925935Y708425D02*
X919323D01*
G01X925657Y708642D02*
X919912D01*
G01X919323Y708819D02*
X925935D01*
G01X925687Y709016D02*
X919603D01*
G01X919485Y709232D02*
X926071D01*
G01X919485Y709626D02*
X926071D01*
G01X925657Y710217D02*
X919912D01*
G01X925687Y711378D02*
X919603D01*
G01X925935Y711575D02*
X919323D01*
G01Y711969D02*
X925935D01*
G01X925687Y712165D02*
X919603D01*
G01X925657Y713642D02*
X919912D01*
G01X919485Y714232D02*
X926071D01*
G01X925687Y714528D02*
X919603D01*
G01X919485Y714626D02*
X926071D01*
G01X925935Y714724D02*
X919323D01*
G01Y715118D02*
X925935D01*
G01X925657Y715217D02*
X919912D01*
G01X925687Y715315D02*
X919603D01*
G01X925687Y717677D02*
X919603D01*
G01X925935Y717874D02*
X919323D01*
G01Y718268D02*
X925935D01*
G01X925687Y718465D02*
X919603D01*
G01X927626Y718642D02*
X921880D01*
G01X921454Y719232D02*
X928040D01*
G01X921454Y719626D02*
X928040D01*
G01X927626Y720217D02*
X921880D01*
G01X925687Y720827D02*
X919603D01*
G01X925935Y721024D02*
X919323D01*
G01Y721417D02*
X925935D01*
G01X925687Y721614D02*
X919603D01*
G01X925657Y723642D02*
X919912D01*
G01X925687Y723976D02*
X919603D01*
G01X925935Y724173D02*
X919323D01*
G01X919485Y724232D02*
X926071D01*
G01X919323Y724567D02*
X925935D01*
G01X919485Y724626D02*
X926071D01*
G01X925687Y724764D02*
X919603D01*
G01X925657Y725217D02*
X919912D01*
G01X925687Y727126D02*
X919603D01*
G01X925935Y727323D02*
X919323D01*
G01Y727717D02*
X925935D01*
G01X925687Y727913D02*
X919603D01*
G01X925657Y728642D02*
X919912D01*
G01X919485Y729232D02*
X926071D01*
G01X919485Y729626D02*
X926071D01*
G01X925657Y730217D02*
X919912D01*
G01X925687Y730276D02*
X919603D01*
G01X925935Y730472D02*
X919323D01*
G01Y730866D02*
X925935D01*
G01X925687Y731063D02*
X919603D01*
G01X925687Y733425D02*
X919603D01*
G01X925935Y733622D02*
X919323D01*
G01X925657Y733642D02*
X919912D01*
G01X919323Y734016D02*
X925935D01*
G01X925687Y734213D02*
X919603D01*
G01X919485Y734232D02*
X926071D01*
G01X919485Y734626D02*
X926071D01*
G01X925657Y735217D02*
X919912D01*
G01X933204Y743169D02*
X929921D01*
G01X925687Y721614D02*
X925814Y721587D01*
X925903Y721514D01*
X925935Y721417D01*
G01X921090Y708228D02*
X921051Y708255D01*
X921023Y708327D01*
X921013Y708425D01*
G01X921090Y711378D02*
X921051Y711404D01*
X921023Y711476D01*
X921013Y711575D01*
G01X921090Y714528D02*
X921051Y714554D01*
X921023Y714626D01*
X921013Y714724D01*
G01X921090Y717677D02*
X921051Y717704D01*
X921023Y717776D01*
X921013Y717874D01*
G01X921090Y720827D02*
X921051Y720853D01*
X921023Y720925D01*
X921013Y721024D01*
G01X921090Y723976D02*
X921051Y724003D01*
X921023Y724075D01*
X921013Y724173D01*
G01X921090Y727126D02*
X921051Y727152D01*
X921023Y727224D01*
X921013Y727323D01*
G01X921090Y730276D02*
X921051Y730302D01*
X921023Y730374D01*
X921013Y730472D01*
G01X921090Y733425D02*
X921051Y733452D01*
X921023Y733524D01*
X921013Y733622D01*
G01X927953Y743169D02*
X929921Y741201D01*
G01X919912Y708642D02*
X919485Y709232D01*
G01X919912Y713642D02*
X919485Y714232D01*
G01X921880Y718642D02*
X921454Y719232D01*
G01X919912Y723642D02*
X919485Y724232D01*
G01X919912Y728642D02*
X919485Y729232D01*
G01X919912Y733642D02*
X919485Y734232D01*
G01X926071Y709626D02*
X925934Y709824D01*
X925796Y710020D01*
X925657Y710217D01*
G01X926071Y714626D02*
X925934Y714824D01*
X925796Y715020D01*
X925657Y715217D01*
G01X928040Y719626D02*
X927903Y719824D01*
X927765Y720020D01*
X927626Y720217D01*
G01X926071Y724626D02*
X925934Y724824D01*
X925796Y725020D01*
X925657Y725217D01*
G01X926071Y729626D02*
X925934Y729824D01*
X925796Y730020D01*
X925657Y730217D01*
G01X926071Y734626D02*
X925934Y734824D01*
X925796Y735020D01*
X925657Y735217D01*
G01X920602Y708642D02*
X920329Y709232D01*
G01X920602Y713642D02*
X920329Y714232D01*
G01X922570Y718642D02*
X922298Y719232D01*
G01X920602Y723642D02*
X920329Y724232D01*
G01X920602Y728642D02*
X920329Y729232D01*
G01X920602Y733642D02*
X920329Y734232D01*
G01X925935Y705669D02*
X925903Y705766D01*
X925815Y705838D01*
X925687Y705866D01*
G01X925935Y708819D02*
X925903Y708916D01*
X925815Y708988D01*
X925687Y709016D01*
G01X925935Y711969D02*
X925903Y712065D01*
X925815Y712137D01*
X925687Y712165D01*
G01X925935Y715118D02*
X925903Y715215D01*
X925815Y715287D01*
X925687Y715315D01*
G01X925935Y718268D02*
X925903Y718365D01*
X925815Y718437D01*
X925687Y718465D01*
G01X925935Y724567D02*
X925903Y724664D01*
X925815Y724736D01*
X925687Y724764D01*
G01X925935Y727717D02*
X925903Y727813D01*
X925815Y727885D01*
X925687Y727913D01*
G01X925935Y730866D02*
X925903Y730963D01*
X925815Y731035D01*
X925687Y731063D01*
G01X925935Y734016D02*
X925903Y734113D01*
X925815Y734185D01*
X925687Y734213D01*
G01X920500Y708425D02*
X920503Y708387D01*
X920511Y708350D01*
X920523Y708316D01*
X920541Y708286D01*
X920561Y708261D01*
X920585Y708243D01*
X920611Y708232D01*
X920639Y708228D01*
G01X920500Y711575D02*
X920503Y711537D01*
X920511Y711500D01*
X920523Y711466D01*
X920541Y711435D01*
X920561Y711411D01*
X920585Y711393D01*
X920611Y711382D01*
X920639Y711378D01*
G01X920500Y714724D02*
X920503Y714686D01*
X920511Y714649D01*
X920523Y714615D01*
X920541Y714585D01*
X920561Y714561D01*
X920585Y714543D01*
X920611Y714531D01*
X920639Y714528D01*
G01X920500Y717874D02*
X920503Y717836D01*
X920511Y717799D01*
X920523Y717765D01*
X920541Y717735D01*
X920561Y717710D01*
X920585Y717692D01*
X920611Y717681D01*
X920639Y717677D01*
G01X920500Y721024D02*
X920503Y720985D01*
X920511Y720948D01*
X920523Y720915D01*
X920541Y720884D01*
X920561Y720860D01*
X920585Y720842D01*
X920611Y720831D01*
X920639Y720827D01*
G01X920500Y724173D02*
X920503Y724135D01*
X920511Y724098D01*
X920523Y724064D01*
X920541Y724034D01*
X920561Y724009D01*
X920585Y723991D01*
X920611Y723980D01*
X920639Y723976D01*
G01X920500Y727323D02*
X920503Y727285D01*
X920511Y727248D01*
X920523Y727214D01*
X920541Y727183D01*
X920561Y727159D01*
X920585Y727141D01*
X920611Y727130D01*
X920639Y727126D01*
G01X920500Y730472D02*
X920503Y730434D01*
X920511Y730397D01*
X920523Y730363D01*
X920541Y730333D01*
X920561Y730309D01*
X920585Y730291D01*
X920611Y730280D01*
X920639Y730276D01*
G01X920500Y733622D02*
X920503Y733584D01*
X920511Y733547D01*
X920523Y733513D01*
X920541Y733483D01*
X920561Y733458D01*
X920585Y733440D01*
X920611Y733429D01*
X920639Y733425D01*
G01X921454Y709232D02*
X921531Y708642D01*
G01X921454Y714232D02*
X921531Y713642D01*
G01X921454Y724232D02*
X921531Y723642D01*
G01Y728642D02*
X921454Y729232D01*
G01X923422Y719232D02*
X923500Y718642D01*
G01X921454Y734232D02*
X921531Y733642D01*
G01X919323Y734016D02*
Y733622D01*
G01Y727717D02*
Y727323D01*
G01Y730866D02*
Y730472D01*
G01Y724567D02*
Y724173D01*
G01Y721417D02*
Y721024D01*
G01Y718268D02*
Y717874D01*
G01Y715118D02*
Y714724D01*
G01Y708819D02*
Y708425D01*
G01Y711969D02*
Y711575D01*
G01Y705669D02*
Y705276D01*
G01X919485Y709232D02*
Y709626D01*
G01Y714232D02*
Y714626D01*
G01Y724232D02*
Y724626D01*
G01Y729232D02*
Y729626D01*
G01Y734232D02*
Y734626D01*
G01X920329Y709232D02*
Y709626D01*
G01Y714232D02*
Y714626D01*
G01Y724232D02*
Y724626D01*
G01Y729232D02*
Y729626D01*
G01Y734232D02*
Y734626D01*
G01X920500Y734016D02*
Y733622D01*
G01Y727717D02*
Y727323D01*
G01Y730866D02*
Y730472D01*
G01Y724567D02*
Y724173D01*
G01Y721417D02*
Y721024D01*
G01Y718268D02*
Y717874D01*
G01Y715118D02*
Y714724D01*
G01Y708819D02*
Y708425D01*
G01Y711969D02*
Y711575D01*
G01Y705669D02*
Y705276D01*
G01X921013D02*
Y705669D01*
G01Y708425D02*
Y708819D01*
G01Y711575D02*
Y711969D01*
G01Y714724D02*
Y715118D01*
G01Y721024D02*
Y721417D01*
G01Y717874D02*
Y718268D01*
G01Y724173D02*
Y724567D01*
G01Y727323D02*
Y727717D01*
G01Y730472D02*
Y730866D01*
G01Y733622D02*
Y734016D01*
G01X921454Y734626D02*
Y734232D01*
G01Y724626D02*
Y724232D01*
G01Y714626D02*
Y714232D01*
G01Y709626D02*
Y709232D01*
G01Y729232D02*
Y729626D01*
G01Y719232D02*
Y719626D01*
G01X922298Y719232D02*
Y719626D01*
G01X923422D02*
Y719232D01*
G01X925935Y705276D02*
Y705669D01*
G01Y708425D02*
Y708819D01*
G01Y711575D02*
Y711969D01*
G01Y714724D02*
Y715118D01*
G01Y721024D02*
Y721417D01*
G01Y717874D02*
Y718268D01*
G01Y724173D02*
Y724567D01*
G01Y727323D02*
Y727717D01*
G01Y730472D02*
Y730866D01*
G01Y733622D02*
Y734016D01*
G01X926071Y734626D02*
Y734232D01*
G01Y729626D02*
Y729232D01*
G01Y724626D02*
Y724232D01*
G01Y714626D02*
Y714232D01*
G01Y709626D02*
Y709232D01*
G01X928040Y719626D02*
Y719232D01*
G01X931890Y743169D02*
Y750335D01*
G01X936614Y745138D02*
Y746870D01*
G01X921013Y734016D02*
X921023Y734114D01*
X921051Y734186D01*
X921090Y734213D01*
G01X921013Y730866D02*
X921023Y730965D01*
X921051Y731037D01*
X921090Y731063D01*
G01X921013Y727717D02*
X921023Y727815D01*
X921051Y727887D01*
X921090Y727913D01*
G01X921013Y724567D02*
X921023Y724665D01*
X921051Y724737D01*
X921090Y724764D01*
G01X921013Y721417D02*
X921023Y721516D01*
X921051Y721588D01*
X921090Y721614D01*
G01X921013Y718268D02*
X921023Y718366D01*
X921051Y718438D01*
X921090Y718465D01*
G01X921013Y715118D02*
X921023Y715217D01*
X921051Y715289D01*
X921090Y715315D01*
G01X921013Y711969D02*
X921023Y712067D01*
X921051Y712139D01*
X921090Y712165D01*
G01X921013Y708819D02*
X921023Y708917D01*
X921051Y708989D01*
X921090Y709016D01*
G01X921013Y705669D02*
X921023Y705768D01*
X921051Y705840D01*
X921090Y705866D01*
G01X921454Y734626D02*
X921531Y735217D01*
G01Y730217D02*
X921454Y729626D01*
G01Y724626D02*
X921531Y725217D01*
G01X921454Y714626D02*
X921531Y715217D01*
G01X921454Y709626D02*
X921531Y710217D01*
G01X923422Y719626D02*
X923500Y720217D01*
G01X933204Y743169D02*
X936614Y745138D01*
G01X925935Y721024D02*
X925901Y720924D01*
X925813Y720854D01*
X925687Y720827D01*
G01X920329Y734626D02*
X920602Y735217D01*
G01X920329Y729626D02*
X920602Y730217D01*
G01X920329Y724626D02*
X920602Y725217D01*
G01X922298Y719626D02*
X922570Y720217D01*
G01X920329Y714626D02*
X920602Y715217D01*
G01X920329Y709626D02*
X920602Y710217D01*
G01X925657Y733642D02*
X925796Y733838D01*
X925934Y734035D01*
X926071Y734232D01*
G01X925657Y728642D02*
X925796Y728838D01*
X925934Y729035D01*
X926071Y729232D01*
G01X925657Y723642D02*
X925796Y723838D01*
X925934Y724035D01*
X926071Y724232D01*
G01X927626Y718642D02*
X927765Y718838D01*
X927903Y719035D01*
X928040Y719232D01*
G01X925657Y713642D02*
X925796Y713838D01*
X925934Y714035D01*
X926071Y714232D01*
G01X925657Y708642D02*
X925796Y708838D01*
X925934Y709035D01*
X926071Y709232D01*
G01X919912Y735217D02*
X919485Y734626D01*
G01X919912Y730217D02*
X919485Y729626D01*
G01X919912Y725217D02*
X919485Y724626D01*
G01X921880Y720217D02*
X921454Y719626D01*
G01X919912Y715217D02*
X919485Y714626D01*
G01X919912Y710217D02*
X919485Y709626D01*
G01X927953Y738248D02*
X929921Y740217D01*
G01X931894Y750408D02*
X936614Y745767D01*
G01Y746870D02*
X931890Y751516D01*
G01X931921Y751485D02*
X931979Y751344D01*
X931984Y751105D01*
G01X931947Y750784D02*
X931984Y751107D01*
X931978Y751348D01*
X931921Y751485D01*
G01X931948Y750785D02*
X931894Y750408D01*
G01X925687Y705079D02*
X925815Y705106D01*
X925904Y705179D01*
X925935Y705276D01*
G01X920639Y702717D02*
X920611Y702713D01*
X920586Y702702D01*
X920562Y702683D01*
X920541Y702659D01*
X920524Y702629D01*
X920511Y702595D01*
X920503Y702559D01*
X920500Y702520D01*
G01X919323D02*
X925935D01*
G01X925687Y702717D02*
X919603D01*
G01X925657Y703642D02*
X919912D01*
G01X919485Y704232D02*
X926071D01*
G01X919485Y704626D02*
X926071D01*
G01X925687Y705079D02*
X919603D01*
G01X925657Y705217D02*
X919912D01*
G01X921090Y705079D02*
X921051Y705105D01*
X921023Y705177D01*
X921013Y705276D01*
G01X919912Y703642D02*
X919485Y704232D01*
G01X926071Y704626D02*
X925934Y704824D01*
X925796Y705020D01*
X925657Y705217D01*
G01X920602Y703642D02*
X920329Y704232D01*
G01X925935Y702520D02*
X925903Y702617D01*
X925815Y702689D01*
X925687Y702717D01*
G01X920500Y705276D02*
X920503Y705237D01*
X920511Y705200D01*
X920523Y705167D01*
X920541Y705136D01*
X920561Y705112D01*
X920585Y705094D01*
X920611Y705083D01*
X920639Y705079D01*
G01X921454Y704232D02*
X921531Y703642D01*
G01X919485Y704232D02*
Y704626D01*
G01X920329Y704232D02*
Y704626D01*
G01X921454D02*
Y704232D01*
G01X926071Y704626D02*
Y704232D01*
G01X921013Y702520D02*
X921023Y702618D01*
X921051Y702690D01*
X921090Y702717D01*
G01X921454Y704626D02*
X921531Y705217D01*
G01X920329Y704626D02*
X920602Y705217D01*
G01X925657Y703642D02*
X925796Y703838D01*
X925934Y704035D01*
X926071Y704232D01*
G01X919912Y705217D02*
X919485Y704626D01*
G01X982289Y1068883D02*
G03X1013785I15748J0D01*
G01X982289D02*
G03X1013785I15748J0D01*
G01X982289D02*
G03X1013785I15748J0D01*
G01X925944Y1065809D02*
X919626D01*
G01X919889Y1066006D02*
X925697D01*
G01X921720Y1065809D02*
X921721Y1065847D01*
X921723Y1065884D01*
X921726Y1065918D01*
X921730Y1065948D01*
X921735Y1065973D01*
X921741Y1065991D01*
X921747Y1066002D01*
X921753Y1066006D01*
G01X920569Y1065809D02*
X920571Y1065847D01*
X920580Y1065884D01*
X920593Y1065918D01*
X920612Y1065948D01*
X920634Y1065973D01*
X920659Y1065991D01*
X920687Y1066002D01*
X920717Y1066006D01*
G01X925944Y1065809D02*
X925911Y1065908D01*
X925823Y1065979D01*
X925697Y1066006D01*
G01X925687Y1016102D02*
X925815Y1016130D01*
X925904Y1016203D01*
X925935Y1016299D01*
G01X925687Y1019252D02*
X925815Y1019280D01*
X925904Y1019352D01*
X925935Y1019449D01*
G01X925687Y1022402D02*
X925815Y1022429D01*
X925904Y1022502D01*
X925935Y1022598D01*
G01X925687Y1025551D02*
X925815Y1025579D01*
X925904Y1025652D01*
X925935Y1025748D01*
G01X925687Y1028701D02*
X925815Y1028728D01*
X925904Y1028801D01*
X925935Y1028898D01*
G01X925687Y1031850D02*
X925815Y1031878D01*
X925904Y1031951D01*
X925935Y1032047D01*
G01X925687Y1035000D02*
X925815Y1035028D01*
X925904Y1035100D01*
X925935Y1035197D01*
G01X925687Y1038150D02*
X925815Y1038177D01*
X925904Y1038250D01*
X925935Y1038346D01*
G01X925687Y1041299D02*
X925815Y1041327D01*
X925904Y1041400D01*
X925935Y1041496D01*
G01X925687Y1044449D02*
X925815Y1044476D01*
X925904Y1044549D01*
X925935Y1044646D01*
G01X925687Y1047598D02*
X925815Y1047626D01*
X925904Y1047699D01*
X925935Y1047795D01*
G01X925687Y1050748D02*
X925815Y1050776D01*
X925904Y1050848D01*
X925935Y1050945D01*
G01X925687Y1053898D02*
X925815Y1053925D01*
X925904Y1053998D01*
X925935Y1054094D01*
G01X925687Y1057047D02*
X925815Y1057075D01*
X925904Y1057148D01*
X925935Y1057244D01*
G01X925687Y1060197D02*
X925815Y1060224D01*
X925904Y1060297D01*
X925935Y1060394D01*
G01X925687Y1063346D02*
X925815Y1063374D01*
X925904Y1063447D01*
X925935Y1063543D01*
G01X925697Y1048880D02*
X925824Y1048907D01*
X925913Y1048980D01*
X925944Y1049077D01*
G01X925697Y1052030D02*
X925824Y1052057D01*
X925913Y1052130D01*
X925944Y1052226D01*
G01X925697Y1055179D02*
X925824Y1055207D01*
X925913Y1055279D01*
X925944Y1055376D01*
G01X925697Y1058329D02*
X925824Y1058356D01*
X925913Y1058429D01*
X925944Y1058526D01*
G01X925697Y1061478D02*
X925824Y1061506D01*
X925913Y1061578D01*
X925944Y1061675D01*
G01X925697Y1064628D02*
X925824Y1064656D01*
X925913Y1064728D01*
X925944Y1064825D01*
G01X920639Y1016890D02*
X920611Y1016886D01*
X920586Y1016875D01*
X920562Y1016857D01*
X920541Y1016832D01*
X920524Y1016802D01*
X920511Y1016769D01*
X920503Y1016732D01*
X920500Y1016693D01*
G01X920639Y1020039D02*
X920611Y1020035D01*
X920586Y1020024D01*
X920562Y1020006D01*
X920541Y1019981D01*
X920524Y1019952D01*
X920511Y1019918D01*
X920503Y1019881D01*
X920500Y1019843D01*
G01X920639Y1023189D02*
X920611Y1023185D01*
X920586Y1023174D01*
X920562Y1023156D01*
X920541Y1023131D01*
X920524Y1023102D01*
X920511Y1023068D01*
X920503Y1023031D01*
X920500Y1022992D01*
G01X920639Y1026339D02*
X920611Y1026335D01*
X920586Y1026324D01*
X920562Y1026306D01*
X920541Y1026281D01*
X920524Y1026251D01*
X920511Y1026217D01*
X920503Y1026181D01*
X920500Y1026142D01*
G01X920639Y1029488D02*
X920611Y1029484D01*
X920586Y1029473D01*
X920562Y1029455D01*
X920541Y1029430D01*
X920524Y1029401D01*
X920511Y1029367D01*
X920503Y1029330D01*
X920500Y1029291D01*
G01X920639Y1032638D02*
X920611Y1032634D01*
X920586Y1032623D01*
X920562Y1032605D01*
X920541Y1032580D01*
X920524Y1032550D01*
X920511Y1032517D01*
X920503Y1032480D01*
X920500Y1032441D01*
G01X920639Y1035787D02*
X920611Y1035783D01*
X920586Y1035772D01*
X920562Y1035754D01*
X920541Y1035730D01*
X920524Y1035700D01*
X920511Y1035666D01*
X920503Y1035630D01*
X920500Y1035591D01*
G01X920639Y1038937D02*
X920611Y1038933D01*
X920586Y1038922D01*
X920562Y1038904D01*
X920541Y1038879D01*
X920524Y1038850D01*
X920511Y1038816D01*
X920503Y1038779D01*
X920500Y1038740D01*
G01X920639Y1042087D02*
X920611Y1042083D01*
X920586Y1042072D01*
X920562Y1042054D01*
X920541Y1042029D01*
X920524Y1041999D01*
X920511Y1041965D01*
X920503Y1041929D01*
X920500Y1041890D01*
G01X920639Y1045236D02*
X920611Y1045232D01*
X920586Y1045221D01*
X920562Y1045203D01*
X920541Y1045178D01*
X920524Y1045149D01*
X920511Y1045115D01*
X920503Y1045078D01*
X920500Y1045039D01*
G01X920639Y1048386D02*
X920611Y1048382D01*
X920586Y1048371D01*
X920562Y1048353D01*
X920541Y1048328D01*
X920524Y1048298D01*
X920511Y1048265D01*
X920503Y1048228D01*
X920500Y1048189D01*
G01X920639Y1051535D02*
X920611Y1051531D01*
X920586Y1051520D01*
X920562Y1051502D01*
X920541Y1051478D01*
X920524Y1051448D01*
X920511Y1051414D01*
X920503Y1051378D01*
X920500Y1051339D01*
G01X920639Y1054685D02*
X920611Y1054681D01*
X920586Y1054670D01*
X920562Y1054652D01*
X920541Y1054627D01*
X920524Y1054598D01*
X920511Y1054564D01*
X920503Y1054527D01*
X920500Y1054488D01*
G01X920639Y1057835D02*
X920611Y1057831D01*
X920586Y1057820D01*
X920562Y1057802D01*
X920541Y1057777D01*
X920524Y1057747D01*
X920511Y1057713D01*
X920503Y1057677D01*
X920500Y1057638D01*
G01X920639Y1060984D02*
X920611Y1060980D01*
X920586Y1060969D01*
X920562Y1060951D01*
X920541Y1060926D01*
X920524Y1060897D01*
X920511Y1060863D01*
X920503Y1060826D01*
X920500Y1060787D01*
G01X933204Y1006201D02*
X929921D01*
G01X920639Y1064134D02*
X920611Y1064130D01*
X920586Y1064119D01*
X920562Y1064101D01*
X920541Y1064076D01*
X920524Y1064046D01*
X920511Y1064013D01*
X920503Y1063976D01*
X920500Y1063937D01*
G01X925657Y1014154D02*
X919912D01*
G01X919485Y1014744D02*
X926071D01*
G01X919485Y1015138D02*
X926071D01*
G01X925657Y1015728D02*
X919912D01*
G01X925687Y1016102D02*
X919603D01*
G01X925935Y1016299D02*
X919323D01*
G01Y1016693D02*
X925935D01*
G01X925687Y1016890D02*
X919603D01*
G01X925657Y1019154D02*
X919912D01*
G01X925687Y1019252D02*
X919603D01*
G01X925935Y1019449D02*
X919323D01*
G01X919485Y1019744D02*
X926071D01*
G01X919323Y1019843D02*
X925935D01*
G01X925687Y1020039D02*
X919603D01*
G01X919485Y1020138D02*
X926071D01*
G01X925657Y1020728D02*
X919912D01*
G01X925687Y1022402D02*
X919603D01*
G01X925935Y1022598D02*
X919323D01*
G01Y1022992D02*
X925935D01*
G01X925687Y1023189D02*
X919603D01*
G01X925657Y1024154D02*
X919912D01*
G01X919485Y1024744D02*
X926071D01*
G01X919485Y1025138D02*
X926071D01*
G01X925687Y1025551D02*
X919603D01*
G01X925657Y1025728D02*
X919912D01*
G01X925935Y1025748D02*
X919323D01*
G01Y1026142D02*
X925935D01*
G01X925687Y1026339D02*
X919603D01*
G01X925687Y1028701D02*
X919603D01*
G01X925935Y1028898D02*
X919323D01*
G01X925657Y1029154D02*
X919912D01*
G01X919323Y1029291D02*
X925935D01*
G01X925687Y1029488D02*
X919603D01*
G01X919485Y1029744D02*
X926071D01*
G01X919485Y1030138D02*
X926071D01*
G01X925657Y1030728D02*
X919912D01*
G01X925687Y1031850D02*
X919603D01*
G01X925935Y1032047D02*
X919323D01*
G01Y1032441D02*
X925935D01*
G01X925687Y1032638D02*
X919603D01*
G01X925657Y1034154D02*
X919912D01*
G01X919485Y1034744D02*
X926071D01*
G01X925687Y1035000D02*
X919603D01*
G01X919485Y1035138D02*
X926071D01*
G01X925935Y1035197D02*
X919323D01*
G01Y1035591D02*
X925935D01*
G01X925657Y1035728D02*
X919912D01*
G01X925687Y1035787D02*
X919603D01*
G01X925687Y1038150D02*
X919603D01*
G01X925935Y1038346D02*
X919323D01*
G01Y1038740D02*
X925935D01*
G01X925687Y1038937D02*
X919603D01*
G01X925657Y1039154D02*
X919912D01*
G01X919485Y1039744D02*
X926071D01*
G01X919485Y1040138D02*
X926071D01*
G01X925657Y1040728D02*
X919912D01*
G01X925687Y1041299D02*
X919603D01*
G01X925935Y1041496D02*
X919323D01*
G01Y1041890D02*
X925935D01*
G01X925687Y1042087D02*
X919603D01*
G01X925757Y1044154D02*
X919844D01*
G01X925687Y1044449D02*
X919603D01*
G01X925935Y1044646D02*
X919323D01*
G01X919420Y1044744D02*
X926162D01*
G01X919323Y1045039D02*
X925935D01*
G01X919420Y1045138D02*
X926162D01*
G01X925687Y1045236D02*
X919603D01*
G01X925757Y1045728D02*
X919844D01*
G01X929921Y1046516D02*
X923452D01*
G01X925687Y1047598D02*
X919603D01*
G01X925935Y1047795D02*
X919323D01*
G01Y1048189D02*
X925935D01*
G01X925687Y1048386D02*
X919603D01*
G01X919889Y1048880D02*
X925697D01*
G01X919626Y1049077D02*
X925944D01*
G01Y1050061D02*
X919626D01*
G01X919889Y1050258D02*
X925697D01*
G01X925687Y1050748D02*
X919603D01*
G01X925935Y1050945D02*
X919323D01*
G01Y1051339D02*
X925935D01*
G01X925687Y1051535D02*
X919603D01*
G01X919889Y1052030D02*
X925697D01*
G01X919626Y1052226D02*
X925944D01*
G01Y1053211D02*
X919626D01*
G01X919889Y1053407D02*
X925697D01*
G01X925687Y1053898D02*
X919603D01*
G01X925935Y1054094D02*
X919323D01*
G01Y1054488D02*
X925935D01*
G01X925687Y1054685D02*
X919603D01*
G01X919889Y1055179D02*
X925697D01*
G01X919626Y1055376D02*
X925944D01*
G01Y1056360D02*
X919626D01*
G01X919889Y1056557D02*
X925697D01*
G01X925687Y1057047D02*
X919603D01*
G01X925935Y1057244D02*
X919323D01*
G01Y1057638D02*
X925935D01*
G01X925687Y1057835D02*
X919603D01*
G01X919889Y1058329D02*
X925697D01*
G01X919626Y1058526D02*
X925944D01*
G01Y1059510D02*
X919626D01*
G01X919889Y1059707D02*
X925697D01*
G01X925687Y1060197D02*
X919603D01*
G01X925935Y1060394D02*
X919323D01*
G01Y1060787D02*
X925935D01*
G01X925687Y1060984D02*
X919603D01*
G01X919889Y1061478D02*
X925697D01*
G01X919626Y1061675D02*
X925944D01*
G01Y1062659D02*
X919626D01*
G01X919889Y1062856D02*
X925697D01*
G01X925687Y1063346D02*
X919603D01*
G01X925935Y1063543D02*
X919323D01*
G01Y1063937D02*
X925935D01*
G01X925687Y1064134D02*
X919603D01*
G01X919889Y1064628D02*
X925697D01*
G01X919626Y1064825D02*
X925944D01*
G01X920717Y1048880D02*
X920688Y1048884D01*
X920660Y1048895D01*
X920635Y1048913D01*
X920612Y1048938D01*
X920594Y1048967D01*
X920580Y1049001D01*
X920572Y1049038D01*
X920569Y1049077D01*
G01X920717Y1052030D02*
X920688Y1052033D01*
X920660Y1052044D01*
X920635Y1052063D01*
X920612Y1052087D01*
X920594Y1052117D01*
X920580Y1052151D01*
X920572Y1052187D01*
X920569Y1052226D01*
G01X920717Y1055179D02*
X920688Y1055183D01*
X920660Y1055194D01*
X920635Y1055212D01*
X920612Y1055237D01*
X920594Y1055267D01*
X920580Y1055300D01*
X920572Y1055337D01*
X920569Y1055376D01*
G01X920717Y1058329D02*
X920688Y1058333D01*
X920660Y1058344D01*
X920635Y1058362D01*
X920612Y1058387D01*
X920594Y1058416D01*
X920580Y1058450D01*
X920572Y1058487D01*
X920569Y1058526D01*
G01X920717Y1061478D02*
X920688Y1061482D01*
X920660Y1061493D01*
X920635Y1061511D01*
X920612Y1061536D01*
X920594Y1061566D01*
X920580Y1061600D01*
X920572Y1061636D01*
X920569Y1061675D01*
G01X920717Y1064628D02*
X920688Y1064632D01*
X920660Y1064643D01*
X920635Y1064661D01*
X920612Y1064686D01*
X920594Y1064715D01*
X920580Y1064749D01*
X920572Y1064786D01*
X920569Y1064825D01*
G01X921090Y1060984D02*
X921051Y1060958D01*
X921023Y1060885D01*
X921013Y1060787D01*
G01X921090Y1045236D02*
X921051Y1045210D01*
X921023Y1045137D01*
X921013Y1045039D01*
G01X921090Y1042087D02*
X921051Y1042060D01*
X921023Y1041988D01*
X921013Y1041890D01*
G01X921090Y1032638D02*
X921051Y1032611D01*
X921023Y1032539D01*
X921013Y1032441D01*
G01X921090Y1029488D02*
X921051Y1029462D01*
X921023Y1029389D01*
X921013Y1029291D01*
G01X921090Y1026339D02*
X921051Y1026312D01*
X921023Y1026240D01*
X921013Y1026142D01*
G01X921090Y1016890D02*
X921051Y1016863D01*
X921023Y1016791D01*
X921013Y1016693D01*
G01X925757Y1044154D02*
X925893Y1044350D01*
X926028Y1044546D01*
X926162Y1044744D01*
G01X925657Y1039154D02*
X925796Y1039350D01*
X925934Y1039546D01*
X926071Y1039744D01*
G01X925657Y1034154D02*
X925796Y1034350D01*
X925934Y1034546D01*
X926071Y1034744D01*
G01X919844Y1045728D02*
X919420Y1045138D01*
G01X919912Y1040728D02*
X919485Y1040138D01*
G01X919912Y1035728D02*
X919485Y1035138D01*
G01X919912Y1030728D02*
X919485Y1030138D01*
G01X919912Y1025728D02*
X919485Y1025138D01*
G01X929921Y1008169D02*
X927953Y1006201D01*
G01X921753Y1048880D02*
X921747Y1048884D01*
X921741Y1048895D01*
X921735Y1048913D01*
X921730Y1048938D01*
X921726Y1048967D01*
X921723Y1049001D01*
X921721Y1049038D01*
X921720Y1049077D01*
G01X921753Y1052030D02*
X921747Y1052033D01*
X921741Y1052044D01*
X921735Y1052063D01*
X921730Y1052087D01*
X921726Y1052117D01*
X921723Y1052151D01*
X921721Y1052187D01*
X921720Y1052226D01*
G01X921753Y1055179D02*
X921747Y1055183D01*
X921741Y1055194D01*
X921735Y1055212D01*
X921730Y1055237D01*
X921726Y1055267D01*
X921723Y1055300D01*
X921721Y1055337D01*
X921720Y1055376D01*
G01X921753Y1058329D02*
X921747Y1058333D01*
X921741Y1058344D01*
X921735Y1058362D01*
X921730Y1058387D01*
X921726Y1058416D01*
X921723Y1058450D01*
X921721Y1058487D01*
X921720Y1058526D01*
G01X921753Y1061478D02*
X921747Y1061482D01*
X921741Y1061493D01*
X921735Y1061511D01*
X921730Y1061536D01*
X921726Y1061566D01*
X921723Y1061600D01*
X921721Y1061636D01*
X921720Y1061675D01*
G01X921753Y1064628D02*
X921747Y1064632D01*
X921741Y1064643D01*
X921735Y1064661D01*
X921730Y1064686D01*
X921726Y1064715D01*
X921723Y1064749D01*
X921721Y1064786D01*
X921720Y1064825D01*
G01X921090Y1016102D02*
X921051Y1016129D01*
X921023Y1016201D01*
X921013Y1016299D01*
G01X921090Y1019252D02*
X921051Y1019278D01*
X921023Y1019350D01*
X921013Y1019449D01*
G01X921090Y1022402D02*
X921051Y1022428D01*
X921023Y1022500D01*
X921013Y1022598D01*
G01X921090Y1025551D02*
X921051Y1025578D01*
X921023Y1025650D01*
X921013Y1025748D01*
G01X921090Y1028701D02*
X921051Y1028727D01*
X921023Y1028799D01*
X921013Y1028898D01*
G01X921090Y1031850D02*
X921051Y1031877D01*
X921023Y1031949D01*
X921013Y1032047D01*
G01X921090Y1035000D02*
X921051Y1035026D01*
X921023Y1035098D01*
X921013Y1035197D01*
G01X921090Y1038150D02*
X921051Y1038176D01*
X921023Y1038248D01*
X921013Y1038346D01*
G01X921090Y1041299D02*
X921051Y1041326D01*
X921023Y1041398D01*
X921013Y1041496D01*
G01X921090Y1044449D02*
X921051Y1044475D01*
X921023Y1044547D01*
X921013Y1044646D01*
G01X921090Y1047598D02*
X921051Y1047625D01*
X921023Y1047697D01*
X921013Y1047795D01*
G01X921090Y1050748D02*
X921051Y1050774D01*
X921023Y1050846D01*
X921013Y1050945D01*
G01X921090Y1053898D02*
X921051Y1053924D01*
X921023Y1053996D01*
X921013Y1054094D01*
G01X921090Y1057047D02*
X921051Y1057074D01*
X921023Y1057146D01*
X921013Y1057244D01*
G01X921090Y1060197D02*
X921051Y1060223D01*
X921023Y1060295D01*
X921013Y1060394D01*
G01X921090Y1063346D02*
X921051Y1063373D01*
X921023Y1063445D01*
X921013Y1063543D01*
G01X929921Y1009154D02*
X927953Y1011122D01*
G01X920329Y1045138D02*
X920602Y1045728D01*
G01X920329Y1040138D02*
X920602Y1040728D01*
G01X920329Y1035138D02*
X920602Y1035728D01*
G01X920329Y1030138D02*
X920602Y1030728D01*
G01X920329Y1025138D02*
X920602Y1025728D01*
G01X920329Y1020138D02*
X920602Y1020728D01*
G01X920329Y1015138D02*
X920602Y1015728D01*
G01X925657Y1029154D02*
X925796Y1029350D01*
X925934Y1029546D01*
X926071Y1029744D01*
G01X925657Y1024154D02*
X925796Y1024350D01*
X925934Y1024546D01*
X926071Y1024744D01*
G01X925657Y1019154D02*
X925796Y1019350D01*
X925934Y1019546D01*
X926071Y1019744D01*
G01X925657Y1014154D02*
X925796Y1014350D01*
X925934Y1014546D01*
X926071Y1014744D01*
G01X919912Y1020728D02*
X919485Y1020138D01*
G01X919912Y1015728D02*
X919485Y1015138D01*
G01X927953Y1047677D02*
X929921Y1045709D01*
G01X919912Y1014154D02*
X919485Y1014744D01*
G01X919912Y1019154D02*
X919485Y1019744D01*
G01X919912Y1024154D02*
X919485Y1024744D01*
G01X919912Y1029154D02*
X919485Y1029744D01*
G01X919912Y1034154D02*
X919485Y1034744D01*
G01X919912Y1039154D02*
X919485Y1039744D01*
G01X919844Y1044154D02*
X919420Y1044744D01*
G01X926071Y1015138D02*
X925934Y1015335D01*
X925796Y1015532D01*
X925657Y1015728D01*
G01X926071Y1020138D02*
X925934Y1020335D01*
X925796Y1020532D01*
X925657Y1020728D01*
G01X926071Y1025138D02*
X925934Y1025335D01*
X925796Y1025532D01*
X925657Y1025728D01*
G01X926071Y1030138D02*
X925934Y1030335D01*
X925796Y1030532D01*
X925657Y1030728D01*
G01X926071Y1035138D02*
X925934Y1035335D01*
X925796Y1035532D01*
X925657Y1035728D01*
G01X926071Y1040138D02*
X925934Y1040335D01*
X925796Y1040532D01*
X925657Y1040728D01*
G01X926162Y1045138D02*
X926028Y1045335D01*
X925893Y1045532D01*
X925757Y1045728D01*
G01X920602Y1014154D02*
X920329Y1014744D01*
G01X920602Y1019154D02*
X920329Y1019744D01*
G01X920602Y1024154D02*
X920329Y1024744D01*
G01X920602Y1029154D02*
X920329Y1029744D01*
G01X920602Y1034154D02*
X920329Y1034744D01*
G01X920602Y1039154D02*
X920329Y1039744D01*
G01X920602Y1044154D02*
X920329Y1044744D01*
G01X920500Y1016299D02*
X920503Y1016261D01*
X920511Y1016224D01*
X920523Y1016190D01*
X920541Y1016160D01*
X920561Y1016135D01*
X920585Y1016117D01*
X920611Y1016106D01*
X920639Y1016102D01*
G01X920500Y1019449D02*
X920503Y1019411D01*
X920511Y1019374D01*
X920523Y1019340D01*
X920541Y1019309D01*
X920561Y1019285D01*
X920585Y1019267D01*
X920611Y1019256D01*
X920639Y1019252D01*
G01X920500Y1022598D02*
X920503Y1022560D01*
X920511Y1022523D01*
X920523Y1022489D01*
X920541Y1022459D01*
X920561Y1022435D01*
X920585Y1022417D01*
X920611Y1022406D01*
X920639Y1022402D01*
G01X920500Y1025748D02*
X920503Y1025710D01*
X920511Y1025673D01*
X920523Y1025639D01*
X920541Y1025609D01*
X920561Y1025584D01*
X920585Y1025566D01*
X920611Y1025555D01*
X920639Y1025551D01*
G01X920500Y1028898D02*
X920503Y1028859D01*
X920511Y1028822D01*
X920523Y1028789D01*
X920541Y1028758D01*
X920561Y1028734D01*
X920585Y1028716D01*
X920611Y1028705D01*
X920639Y1028701D01*
G01X920500Y1032047D02*
X920503Y1032009D01*
X920511Y1031972D01*
X920523Y1031938D01*
X920541Y1031908D01*
X920561Y1031883D01*
X920585Y1031865D01*
X920611Y1031854D01*
X920639Y1031850D01*
G01X920500Y1035197D02*
X920503Y1035159D01*
X920511Y1035122D01*
X920523Y1035088D01*
X920541Y1035057D01*
X920561Y1035033D01*
X920585Y1035015D01*
X920611Y1035004D01*
X920639Y1035000D01*
G01X920500Y1038346D02*
X920503Y1038308D01*
X920511Y1038271D01*
X920523Y1038237D01*
X920541Y1038207D01*
X920561Y1038183D01*
X920585Y1038165D01*
X920611Y1038154D01*
X920639Y1038150D01*
G01X920500Y1041496D02*
X920503Y1041458D01*
X920511Y1041421D01*
X920523Y1041387D01*
X920541Y1041357D01*
X920561Y1041332D01*
X920585Y1041314D01*
X920611Y1041303D01*
X920639Y1041299D01*
G01X920500Y1044646D02*
X920503Y1044607D01*
X920511Y1044570D01*
X920523Y1044537D01*
X920541Y1044506D01*
X920561Y1044482D01*
X920585Y1044464D01*
X920611Y1044453D01*
X920639Y1044449D01*
G01X920500Y1047795D02*
X920503Y1047757D01*
X920511Y1047720D01*
X920523Y1047686D01*
X920541Y1047656D01*
X920561Y1047631D01*
X920585Y1047613D01*
X920611Y1047602D01*
X920639Y1047598D01*
G01X920500Y1050945D02*
X920503Y1050907D01*
X920511Y1050870D01*
X920523Y1050836D01*
X920541Y1050806D01*
X920561Y1050781D01*
X920585Y1050763D01*
X920611Y1050752D01*
X920639Y1050748D01*
G01X920500Y1054094D02*
X920503Y1054056D01*
X920511Y1054019D01*
X920523Y1053985D01*
X920541Y1053955D01*
X920561Y1053931D01*
X920585Y1053913D01*
X920611Y1053902D01*
X920639Y1053898D01*
G01X920500Y1057244D02*
X920503Y1057206D01*
X920511Y1057169D01*
X920523Y1057135D01*
X920541Y1057105D01*
X920561Y1057080D01*
X920585Y1057062D01*
X920611Y1057051D01*
X920639Y1057047D01*
G01X920500Y1060394D02*
X920503Y1060356D01*
X920511Y1060319D01*
X920523Y1060285D01*
X920541Y1060254D01*
X920561Y1060230D01*
X920585Y1060212D01*
X920611Y1060201D01*
X920639Y1060197D01*
G01X920500Y1063543D02*
X920503Y1063505D01*
X920511Y1063468D01*
X920523Y1063434D01*
X920541Y1063404D01*
X920561Y1063380D01*
X920585Y1063361D01*
X920611Y1063350D01*
X920639Y1063346D01*
G01X919323Y1063937D02*
Y1063543D01*
G01Y1060787D02*
Y1060394D01*
G01Y1054488D02*
Y1054094D01*
G01Y1057638D02*
Y1057244D01*
G01Y1051339D02*
Y1050945D01*
G01Y1048189D02*
Y1047795D01*
G01Y1045039D02*
Y1044646D01*
G01Y1041890D02*
Y1041496D01*
G01Y1035591D02*
Y1035197D01*
G01Y1038740D02*
Y1038346D01*
G01Y1032441D02*
Y1032047D01*
G01Y1029291D02*
Y1028898D01*
G01Y1022992D02*
Y1022598D01*
G01Y1026142D02*
Y1025748D01*
G01Y1019843D02*
Y1019449D01*
G01Y1016693D02*
Y1016299D01*
G01X919420Y1044744D02*
Y1045138D01*
G01X919485Y1014744D02*
Y1015138D01*
G01Y1019744D02*
Y1020138D01*
G01Y1024744D02*
Y1025138D01*
G01Y1029744D02*
Y1030138D01*
G01Y1034744D02*
Y1035138D01*
G01Y1039744D02*
Y1040138D01*
G01X919626Y1052226D02*
Y1053211D01*
G01Y1049077D02*
Y1050061D01*
G01Y1055376D02*
Y1056360D01*
G01Y1061675D02*
Y1062659D01*
G01Y1058526D02*
Y1059510D01*
G01Y1064825D02*
Y1065809D01*
G01X920329Y1014744D02*
Y1015138D01*
G01Y1019744D02*
Y1020138D01*
G01Y1024744D02*
Y1025138D01*
G01Y1029744D02*
Y1030138D01*
G01Y1034744D02*
Y1035138D01*
G01Y1039744D02*
Y1040138D01*
G01Y1044744D02*
Y1045138D01*
G01X920500Y1063937D02*
Y1063543D01*
G01Y1060787D02*
Y1060394D01*
G01Y1054488D02*
Y1054094D01*
G01Y1057638D02*
Y1057244D01*
G01Y1051339D02*
Y1050945D01*
G01Y1048189D02*
Y1047795D01*
G01Y1045039D02*
Y1044646D01*
G01Y1041890D02*
Y1041496D01*
G01Y1035591D02*
Y1035197D01*
G01Y1038740D02*
Y1038346D01*
G01Y1032441D02*
Y1032047D01*
G01Y1029291D02*
Y1028898D01*
G01Y1022992D02*
Y1022598D01*
G01Y1026142D02*
Y1025748D01*
G01Y1019843D02*
Y1019449D01*
G01Y1016693D02*
Y1016299D01*
G01X920569Y1052226D02*
Y1053211D01*
G01Y1049077D02*
Y1050061D01*
G01Y1055376D02*
Y1056360D01*
G01Y1061675D02*
Y1062659D01*
G01Y1058526D02*
Y1059510D01*
G01Y1064825D02*
Y1065809D01*
G01X921013Y1016299D02*
Y1016693D01*
G01Y1019449D02*
Y1019843D01*
G01Y1022598D02*
Y1022992D01*
G01Y1025748D02*
Y1026142D01*
G01Y1028898D02*
Y1029291D01*
G01Y1032047D02*
Y1032441D01*
G01Y1035197D02*
Y1035591D01*
G01Y1038346D02*
Y1038740D01*
G01Y1041496D02*
Y1041890D01*
G01Y1047795D02*
Y1048189D01*
G01Y1044646D02*
Y1045039D01*
G01Y1050945D02*
Y1051339D01*
G01Y1054094D02*
Y1054488D01*
G01Y1057244D02*
Y1057638D01*
G01Y1060394D02*
Y1060787D01*
G01Y1063543D02*
Y1063937D01*
G01X921454Y1045138D02*
Y1044744D01*
G01Y1040138D02*
Y1039744D01*
G01Y1035138D02*
Y1034744D01*
G01Y1030138D02*
Y1029744D01*
G01Y1025138D02*
Y1024744D01*
G01Y1020138D02*
Y1019744D01*
G01Y1015138D02*
Y1014744D01*
G01X921720Y1052226D02*
Y1053211D01*
G01Y1049077D02*
Y1050061D01*
G01Y1055376D02*
Y1056360D01*
G01Y1061675D02*
Y1062659D01*
G01Y1058526D02*
Y1059510D01*
G01Y1064825D02*
Y1065809D01*
G01X923452Y1047697D02*
Y1046516D01*
G01X925935Y1016299D02*
Y1016693D01*
G01Y1019449D02*
Y1019843D01*
G01Y1022598D02*
Y1022992D01*
G01Y1025748D02*
Y1026142D01*
G01Y1028898D02*
Y1029291D01*
G01Y1032047D02*
Y1032441D01*
G01Y1035197D02*
Y1035591D01*
G01Y1038346D02*
Y1038740D01*
G01Y1041496D02*
Y1041890D01*
G01Y1047795D02*
Y1048189D01*
G01Y1044646D02*
Y1045039D01*
G01Y1050945D02*
Y1051339D01*
G01Y1054094D02*
Y1054488D01*
G01Y1057244D02*
Y1057638D01*
G01Y1060394D02*
Y1060787D01*
G01Y1063543D02*
Y1063937D01*
G01X925944Y1065809D02*
Y1064825D01*
G01Y1062659D02*
Y1061675D01*
G01Y1059510D02*
Y1058526D01*
G01Y1056360D02*
Y1055376D01*
G01Y1053211D02*
Y1052226D01*
G01Y1050061D02*
Y1049077D01*
G01X926071Y1040138D02*
Y1039744D01*
G01Y1035138D02*
Y1034744D01*
G01Y1030138D02*
Y1029744D01*
G01Y1025138D02*
Y1024744D01*
G01Y1020138D02*
Y1019744D01*
G01Y1015138D02*
Y1014744D01*
G01X926162Y1045138D02*
Y1044744D01*
G01X927953Y1011122D02*
Y1143760D01*
G01X928740Y1041339D02*
Y1010335D01*
G01Y1046516D02*
Y1068366D01*
G01X928799Y1144154D02*
Y1010728D01*
G01X928910Y1046720D02*
Y1041339D01*
G01X929921Y1006201D02*
Y1148681D01*
G01X921720Y1062659D02*
X921721Y1062698D01*
X921723Y1062735D01*
X921726Y1062769D01*
X921730Y1062799D01*
X921735Y1062823D01*
X921741Y1062841D01*
X921747Y1062852D01*
X921753Y1062856D01*
G01X921720Y1059510D02*
X921721Y1059548D01*
X921723Y1059585D01*
X921726Y1059619D01*
X921730Y1059649D01*
X921735Y1059674D01*
X921741Y1059692D01*
X921747Y1059703D01*
X921753Y1059707D01*
G01X921720Y1056360D02*
X921721Y1056398D01*
X921723Y1056435D01*
X921726Y1056469D01*
X921730Y1056500D01*
X921735Y1056524D01*
X921741Y1056542D01*
X921747Y1056553D01*
X921753Y1056557D01*
G01X921720Y1053211D02*
X921721Y1053249D01*
X921723Y1053286D01*
X921726Y1053320D01*
X921730Y1053350D01*
X921735Y1053374D01*
X921741Y1053393D01*
X921747Y1053404D01*
X921753Y1053407D01*
G01X921720Y1050061D02*
X921721Y1050099D01*
X921723Y1050136D01*
X921726Y1050170D01*
X921730Y1050200D01*
X921735Y1050225D01*
X921741Y1050243D01*
X921747Y1050254D01*
X921753Y1050258D01*
G01X920569Y1062659D02*
X920571Y1062698D01*
X920580Y1062735D01*
X920593Y1062769D01*
X920612Y1062799D01*
X920634Y1062823D01*
X920659Y1062841D01*
X920687Y1062852D01*
X920717Y1062856D01*
G01X920569Y1059510D02*
X920571Y1059548D01*
X920580Y1059585D01*
X920593Y1059619D01*
X920612Y1059649D01*
X920634Y1059674D01*
X920659Y1059692D01*
X920687Y1059703D01*
X920717Y1059707D01*
G01X920569Y1056360D02*
X920571Y1056398D01*
X920580Y1056435D01*
X920593Y1056469D01*
X920612Y1056500D01*
X920634Y1056524D01*
X920659Y1056542D01*
X920687Y1056553D01*
X920717Y1056557D01*
G01X920569Y1053211D02*
X920571Y1053249D01*
X920580Y1053286D01*
X920593Y1053320D01*
X920612Y1053350D01*
X920634Y1053374D01*
X920659Y1053393D01*
X920687Y1053404D01*
X920717Y1053407D01*
G01X920569Y1050061D02*
X920571Y1050099D01*
X920580Y1050136D01*
X920593Y1050170D01*
X920612Y1050200D01*
X920634Y1050225D01*
X920659Y1050243D01*
X920687Y1050254D01*
X920717Y1050258D01*
G01X921013Y1063937D02*
X921023Y1064035D01*
X921051Y1064107D01*
X921090Y1064134D01*
G01X921013Y1057638D02*
X921023Y1057736D01*
X921051Y1057808D01*
X921090Y1057835D01*
G01X921013Y1054488D02*
X921023Y1054587D01*
X921051Y1054659D01*
X921090Y1054685D01*
G01X921013Y1051339D02*
X921023Y1051437D01*
X921051Y1051509D01*
X921090Y1051535D01*
G01X921013Y1048189D02*
X921023Y1048287D01*
X921051Y1048359D01*
X921090Y1048386D01*
G01X921013Y1038740D02*
X921023Y1038839D01*
X921051Y1038911D01*
X921090Y1038937D01*
G01X921013Y1035591D02*
X921023Y1035689D01*
X921051Y1035761D01*
X921090Y1035787D01*
G01X921013Y1022992D02*
X921023Y1023091D01*
X921051Y1023163D01*
X921090Y1023189D01*
G01X921013Y1019843D02*
X921023Y1019941D01*
X921051Y1020013D01*
X921090Y1020039D01*
G01X921454Y1045138D02*
X921531Y1045728D01*
G01X921454Y1040138D02*
X921531Y1040728D01*
G01X921454Y1035138D02*
X921531Y1035728D01*
G01X921454Y1030138D02*
X921531Y1030728D01*
G01X921454Y1025138D02*
X921531Y1025728D01*
G01X921454Y1020138D02*
X921531Y1020728D01*
G01X921454Y1015138D02*
X921531Y1015728D01*
G01X925944Y1050061D02*
X925911Y1050160D01*
X925823Y1050231D01*
X925697Y1050258D01*
G01X925944Y1053211D02*
X925911Y1053310D01*
X925823Y1053381D01*
X925697Y1053407D01*
G01X925944Y1056360D02*
X925911Y1056459D01*
X925823Y1056530D01*
X925697Y1056557D01*
G01X925944Y1059510D02*
X925911Y1059609D01*
X925823Y1059680D01*
X925697Y1059707D01*
G01X925944Y1062659D02*
X925911Y1062759D01*
X925823Y1062830D01*
X925697Y1062856D01*
G01X925935Y1016693D02*
X925903Y1016790D01*
X925815Y1016862D01*
X925687Y1016890D01*
G01X925935Y1019843D02*
X925903Y1019939D01*
X925815Y1020011D01*
X925687Y1020039D01*
G01X925935Y1022992D02*
X925903Y1023089D01*
X925815Y1023161D01*
X925687Y1023189D01*
G01X925935Y1026142D02*
X925903Y1026239D01*
X925815Y1026311D01*
X925687Y1026339D01*
G01X925935Y1029291D02*
X925903Y1029388D01*
X925815Y1029460D01*
X925687Y1029488D01*
G01X925935Y1032441D02*
X925903Y1032538D01*
X925815Y1032610D01*
X925687Y1032638D01*
G01X925935Y1035591D02*
X925903Y1035687D01*
X925815Y1035759D01*
X925687Y1035787D01*
G01X925935Y1038740D02*
X925903Y1038837D01*
X925815Y1038909D01*
X925687Y1038937D01*
G01X925935Y1041890D02*
X925903Y1041987D01*
X925815Y1042059D01*
X925687Y1042087D01*
G01X925935Y1045039D02*
X925903Y1045136D01*
X925815Y1045208D01*
X925687Y1045236D01*
G01X925935Y1048189D02*
X925903Y1048286D01*
X925815Y1048358D01*
X925687Y1048386D01*
G01X925935Y1051339D02*
X925903Y1051435D01*
X925815Y1051507D01*
X925687Y1051535D01*
G01X925935Y1054488D02*
X925903Y1054585D01*
X925815Y1054657D01*
X925687Y1054685D01*
G01X925935Y1057638D02*
X925903Y1057735D01*
X925815Y1057807D01*
X925687Y1057835D01*
G01X925935Y1060787D02*
X925903Y1060884D01*
X925815Y1060956D01*
X925687Y1060984D01*
G01X925935Y1063937D02*
X925903Y1064034D01*
X925815Y1064106D01*
X925687Y1064134D01*
G01X921454Y1014744D02*
X921531Y1014154D01*
G01X921454Y1019744D02*
X921531Y1019154D01*
G01X921454Y1024744D02*
X921531Y1024154D01*
G01X921454Y1029744D02*
X921531Y1029154D01*
G01X921454Y1034744D02*
X921531Y1034154D01*
G01X921454Y1039744D02*
X921531Y1039154D01*
G01X921454Y1044744D02*
X921531Y1044154D01*
G01X933204Y1006201D02*
X936614Y1004232D01*
G01Y1003603D02*
X931894Y998962D01*
G01X936614Y1002500D02*
X931890Y997854D01*
G01X931921Y997885D02*
X931979Y998025D01*
X931984Y998265D01*
G01X931921Y997885D02*
X931978Y998020D01*
X931984Y998256D01*
X931948Y998584D01*
G01X931890Y999035D02*
Y1006201D01*
G01X936614Y1004232D02*
Y1002500D01*
G01X931949Y998576D02*
X931894Y998962D01*
G01X1011816Y1082663D02*
G03X984257I-13779J0D01*
G01X1013785D02*
G03X982289I-15748J0D01*
G01X1013785D02*
G03X982289I-15748J0D01*
G01X1013785D02*
G03X982289I-15748J0D01*
G01X984257D02*
Y1080300D01*
G01X982289Y1068883D02*
Y1082663D01*
G01Y1068883D02*
Y1082663D01*
G01Y1068883D02*
Y1082663D01*
G01X984257Y1080300D02*
X992131D01*
G01X925687Y1066496D02*
X925815Y1066524D01*
X925904Y1066596D01*
X925935Y1066693D01*
G01X925687Y1069646D02*
X925815Y1069673D01*
X925904Y1069746D01*
X925935Y1069843D01*
G01X925687Y1072795D02*
X925815Y1072823D01*
X925904Y1072896D01*
X925935Y1072992D01*
G01X925687Y1075945D02*
X925815Y1075972D01*
X925904Y1076045D01*
X925935Y1076142D01*
G01X925687Y1079094D02*
X925815Y1079122D01*
X925904Y1079195D01*
X925935Y1079291D01*
G01X925687Y1082244D02*
X925815Y1082272D01*
X925904Y1082344D01*
X925935Y1082441D01*
G01X925687Y1085394D02*
X925815Y1085421D01*
X925904Y1085494D01*
X925935Y1085591D01*
G01X925687Y1088543D02*
X925815Y1088571D01*
X925904Y1088644D01*
X925935Y1088740D01*
G01X925687Y1091693D02*
X925815Y1091720D01*
X925904Y1091793D01*
X925935Y1091890D01*
G01X925687Y1094843D02*
X925815Y1094870D01*
X925904Y1094943D01*
X925935Y1095039D01*
G01X925687Y1101142D02*
X925815Y1101169D01*
X925904Y1101242D01*
X925935Y1101339D01*
G01X925687Y1104291D02*
X925815Y1104319D01*
X925904Y1104392D01*
X925935Y1104488D01*
G01X920639Y1067283D02*
X920611Y1067280D01*
X920586Y1067269D01*
X920562Y1067250D01*
X920541Y1067226D01*
X920524Y1067196D01*
X920511Y1067162D01*
X920503Y1067126D01*
X920500Y1067087D01*
G01X920639Y1070433D02*
X920611Y1070429D01*
X920586Y1070418D01*
X920562Y1070400D01*
X920541Y1070375D01*
X920524Y1070346D01*
X920511Y1070312D01*
X920503Y1070275D01*
X920500Y1070236D01*
G01X920639Y1073583D02*
X920611Y1073579D01*
X920586Y1073568D01*
X920562Y1073550D01*
X920541Y1073525D01*
X920524Y1073495D01*
X920511Y1073461D01*
X920503Y1073425D01*
X920500Y1073386D01*
G01X920639Y1076732D02*
X920611Y1076728D01*
X920586Y1076717D01*
X920562Y1076699D01*
X920541Y1076674D01*
X920524Y1076645D01*
X920511Y1076611D01*
X920503Y1076574D01*
X920500Y1076535D01*
G01X920639Y1079882D02*
X920611Y1079878D01*
X920586Y1079867D01*
X920562Y1079849D01*
X920541Y1079824D01*
X920524Y1079794D01*
X920511Y1079761D01*
X920503Y1079724D01*
X920500Y1079685D01*
G01X920639Y1083031D02*
X920611Y1083028D01*
X920586Y1083017D01*
X920562Y1082998D01*
X920541Y1082974D01*
X920524Y1082944D01*
X920511Y1082910D01*
X920503Y1082874D01*
X920500Y1082835D01*
G01X920639Y1086181D02*
X920611Y1086177D01*
X920586Y1086166D01*
X920562Y1086148D01*
X920541Y1086123D01*
X920524Y1086094D01*
X920511Y1086060D01*
X920503Y1086023D01*
X920500Y1085984D01*
G01X920639Y1089331D02*
X920611Y1089327D01*
X920586Y1089316D01*
X920562Y1089298D01*
X920541Y1089273D01*
X920524Y1089243D01*
X920511Y1089209D01*
X920503Y1089173D01*
X920500Y1089134D01*
G01X920639Y1092480D02*
X920611Y1092476D01*
X920586Y1092465D01*
X920562Y1092447D01*
X920541Y1092422D01*
X920524Y1092393D01*
X920511Y1092359D01*
X920503Y1092322D01*
X920500Y1092283D01*
G01X920639Y1095630D02*
X920611Y1095626D01*
X920586Y1095615D01*
X920562Y1095597D01*
X920541Y1095572D01*
X920524Y1095543D01*
X920511Y1095509D01*
X920503Y1095472D01*
X920500Y1095433D01*
G01X920639Y1098780D02*
X920611Y1098776D01*
X920586Y1098765D01*
X920562Y1098746D01*
X920541Y1098722D01*
X920524Y1098692D01*
X920511Y1098658D01*
X920503Y1098622D01*
X920500Y1098583D01*
G01X920639Y1101929D02*
X920611Y1101925D01*
X920586Y1101914D01*
X920562Y1101896D01*
X920541Y1101871D01*
X920524Y1101842D01*
X920511Y1101808D01*
X920503Y1101771D01*
X920500Y1101732D01*
G01X920639Y1105079D02*
X920611Y1105075D01*
X920586Y1105064D01*
X920562Y1105046D01*
X920541Y1105021D01*
X920524Y1104991D01*
X920511Y1104957D01*
X920503Y1104921D01*
X920500Y1104882D01*
G01X925687Y1066496D02*
X919603D01*
G01X925935Y1066693D02*
X919323D01*
G01Y1067087D02*
X925935D01*
G01X925687Y1067283D02*
X919603D01*
G01X923452Y1068366D02*
X929921D01*
G01X925757Y1069154D02*
X919844D01*
G01X925687Y1069646D02*
X919603D01*
G01X919420Y1069744D02*
X926162D01*
G01X925935Y1069843D02*
X919323D01*
G01X919420Y1070138D02*
X926162D01*
G01X919323Y1070236D02*
X925935D01*
G01X925687Y1070433D02*
X919603D01*
G01X925757Y1070728D02*
X919844D01*
G01X925687Y1072795D02*
X919603D01*
G01X925935Y1072992D02*
X919323D01*
G01Y1073386D02*
X925935D01*
G01X925687Y1073583D02*
X919603D01*
G01X925657Y1074154D02*
X919912D01*
G01X919485Y1074744D02*
X926071D01*
G01X919485Y1075138D02*
X926071D01*
G01X925657Y1075728D02*
X919912D01*
G01X925687Y1075945D02*
X919603D01*
G01X925935Y1076142D02*
X919323D01*
G01Y1076535D02*
X925935D01*
G01X925687Y1076732D02*
X919603D01*
G01X925687Y1079094D02*
X919603D01*
G01X925657Y1079154D02*
X919912D01*
G01X925935Y1079291D02*
X919323D01*
G01Y1079685D02*
X925935D01*
G01X919485Y1079744D02*
X926071D01*
G01X925687Y1079882D02*
X919603D01*
G01X919485Y1080138D02*
X926071D01*
G01X925657Y1080728D02*
X919912D01*
G01X925687Y1082244D02*
X919603D01*
G01X925935Y1082441D02*
X919323D01*
G01Y1082835D02*
X925935D01*
G01X925687Y1083031D02*
X919603D01*
G01X927626Y1084154D02*
X921880D01*
G01X921454Y1084744D02*
X928040D01*
G01X921454Y1085138D02*
X928040D01*
G01X925687Y1085394D02*
X919603D01*
G01X925935Y1085591D02*
X919323D01*
G01X927626Y1085728D02*
X921880D01*
G01X919323Y1085984D02*
X925935D01*
G01X925687Y1086181D02*
X919603D01*
G01X925687Y1088543D02*
X919603D01*
G01X925935Y1088740D02*
X919323D01*
G01Y1089134D02*
X925935D01*
G01X925657Y1089154D02*
X919912D01*
G01X925687Y1089331D02*
X919603D01*
G01X919485Y1089744D02*
X926071D01*
G01X919485Y1090138D02*
X926071D01*
G01X925657Y1090728D02*
X919912D01*
G01X925687Y1091693D02*
X919603D01*
G01X925935Y1091890D02*
X919323D01*
G01Y1092283D02*
X925935D01*
G01X925687Y1092480D02*
X919603D01*
G01X925657Y1094154D02*
X919912D01*
G01X919485Y1094744D02*
X926071D01*
G01X925687Y1094843D02*
X919603D01*
G01X925935Y1095039D02*
X919323D01*
G01X919485Y1095138D02*
X926071D01*
G01X919323Y1095433D02*
X925935D01*
G01X925687Y1095630D02*
X919603D01*
G01X925657Y1095728D02*
X919912D01*
G01X925687Y1097992D02*
X919603D01*
G01X925935Y1098189D02*
X919323D01*
G01Y1098583D02*
X925935D01*
G01X925687Y1098780D02*
X919603D01*
G01X925657Y1099154D02*
X919912D01*
G01X919485Y1099744D02*
X926071D01*
G01X919485Y1100138D02*
X926071D01*
G01X925657Y1100728D02*
X919912D01*
G01X925687Y1101142D02*
X919603D01*
G01X925935Y1101339D02*
X919323D01*
G01Y1101732D02*
X925935D01*
G01X925687Y1101929D02*
X919603D01*
G01X925657Y1104154D02*
X919912D01*
G01X925687Y1104291D02*
X919603D01*
G01X925935Y1104488D02*
X919323D01*
G01X919485Y1104744D02*
X926071D01*
G01X919323Y1104882D02*
X925935D01*
G01X925687Y1105079D02*
X919603D01*
G01X919485Y1105138D02*
X926071D01*
G01X925687Y1098780D02*
X925814Y1098752D01*
X925903Y1098679D01*
X925935Y1098583D01*
G01X925757Y1069154D02*
X925893Y1069350D01*
X926028Y1069546D01*
X926162Y1069744D01*
G01X925657Y1104154D02*
X925796Y1104350D01*
X925934Y1104546D01*
X926071Y1104744D01*
G01X925657Y1099154D02*
X925796Y1099350D01*
X925934Y1099546D01*
X926071Y1099744D01*
G01X925657Y1094154D02*
X925796Y1094350D01*
X925934Y1094546D01*
X926071Y1094744D01*
G01X925657Y1089154D02*
X925796Y1089350D01*
X925934Y1089546D01*
X926071Y1089744D01*
G01X927626Y1084154D02*
X927765Y1084350D01*
X927903Y1084546D01*
X928040Y1084744D01*
G01X925657Y1079154D02*
X925796Y1079350D01*
X925934Y1079546D01*
X926071Y1079744D01*
G01X925657Y1074154D02*
X925796Y1074350D01*
X925934Y1074546D01*
X926071Y1074744D01*
G01X919844Y1070728D02*
X919420Y1070138D01*
G01X919912Y1105728D02*
X919485Y1105138D01*
G01X919912Y1100728D02*
X919485Y1100138D01*
G01X919912Y1095728D02*
X919485Y1095138D01*
G01X919912Y1090728D02*
X919485Y1090138D01*
G01X921880Y1085728D02*
X921454Y1085138D01*
G01X919912Y1080728D02*
X919485Y1080138D01*
G01X919912Y1075728D02*
X919485Y1075138D01*
G01X929921Y1069173D02*
X927953Y1067205D01*
G01X921090Y1066496D02*
X921051Y1066522D01*
X921023Y1066594D01*
X921013Y1066693D01*
G01X921090Y1069646D02*
X921051Y1069672D01*
X921023Y1069744D01*
X921013Y1069843D01*
G01X921090Y1072795D02*
X921051Y1072822D01*
X921023Y1072894D01*
X921013Y1072992D01*
G01X921090Y1075945D02*
X921051Y1075971D01*
X921023Y1076043D01*
X921013Y1076142D01*
G01X921090Y1079094D02*
X921051Y1079121D01*
X921023Y1079193D01*
X921013Y1079291D01*
G01X921090Y1082244D02*
X921051Y1082270D01*
X921023Y1082343D01*
X921013Y1082441D01*
G01X921090Y1085394D02*
X921051Y1085420D01*
X921023Y1085492D01*
X921013Y1085591D01*
G01X921090Y1088543D02*
X921051Y1088570D01*
X921023Y1088642D01*
X921013Y1088740D01*
G01X921090Y1091693D02*
X921051Y1091719D01*
X921023Y1091791D01*
X921013Y1091890D01*
G01X921090Y1094843D02*
X921051Y1094869D01*
X921023Y1094941D01*
X921013Y1095039D01*
G01X921454Y1105138D02*
X921531Y1105728D01*
G01X925935Y1098189D02*
X925901Y1098090D01*
X925813Y1098019D01*
X925687Y1097992D01*
G01X920329Y1105138D02*
X920602Y1105728D01*
G01X920329Y1100138D02*
X920602Y1100728D01*
G01X920329Y1095138D02*
X920602Y1095728D01*
G01X920329Y1090138D02*
X920602Y1090728D01*
G01X922298Y1085138D02*
X922570Y1085728D01*
G01X920329Y1080138D02*
X920602Y1080728D01*
G01X920329Y1075138D02*
X920602Y1075728D01*
G01X920329Y1070138D02*
X920602Y1070728D01*
G01X921090Y1097992D02*
X921051Y1098019D01*
X921023Y1098091D01*
X921013Y1098189D01*
G01X921090Y1101142D02*
X921051Y1101168D01*
X921023Y1101240D01*
X921013Y1101339D01*
G01X921090Y1104291D02*
X921051Y1104318D01*
X921023Y1104390D01*
X921013Y1104488D01*
G01X919912Y1074154D02*
X919485Y1074744D01*
G01X919912Y1079154D02*
X919485Y1079744D01*
G01X921880Y1084154D02*
X921454Y1084744D01*
G01X919912Y1089154D02*
X919485Y1089744D01*
G01X919912Y1094154D02*
X919485Y1094744D01*
G01X919912Y1099154D02*
X919485Y1099744D01*
G01X919844Y1069154D02*
X919420Y1069744D01*
G01X926071Y1075138D02*
X925934Y1075335D01*
X925796Y1075532D01*
X925657Y1075728D01*
G01X926071Y1080138D02*
X925934Y1080335D01*
X925796Y1080532D01*
X925657Y1080728D01*
G01X926162Y1070138D02*
X926028Y1070335D01*
X925893Y1070532D01*
X925757Y1070728D01*
G01X920500Y1066693D02*
X920503Y1066655D01*
X920511Y1066618D01*
X920523Y1066584D01*
X920541Y1066554D01*
X920561Y1066529D01*
X920585Y1066511D01*
X920611Y1066500D01*
X920639Y1066496D01*
G01X920500Y1069843D02*
X920503Y1069804D01*
X920511Y1069767D01*
X920523Y1069733D01*
X920541Y1069703D01*
X920561Y1069679D01*
X920585Y1069661D01*
X920611Y1069650D01*
X920639Y1069646D01*
G01X920500Y1072992D02*
X920503Y1072954D01*
X920511Y1072917D01*
X920523Y1072883D01*
X920541Y1072853D01*
X920561Y1072828D01*
X920585Y1072810D01*
X920611Y1072799D01*
X920639Y1072795D01*
G01X920500Y1076142D02*
X920503Y1076104D01*
X920511Y1076067D01*
X920523Y1076033D01*
X920541Y1076002D01*
X920561Y1075978D01*
X920585Y1075960D01*
X920611Y1075949D01*
X920639Y1075945D01*
G01X920500Y1079291D02*
X920503Y1079253D01*
X920511Y1079216D01*
X920523Y1079182D01*
X920541Y1079152D01*
X920561Y1079128D01*
X920585Y1079109D01*
X920611Y1079098D01*
X920639Y1079094D01*
G01X920500Y1082441D02*
X920503Y1082403D01*
X920511Y1082366D01*
X920523Y1082332D01*
X920541Y1082302D01*
X920561Y1082277D01*
X920585Y1082259D01*
X920611Y1082248D01*
X920639Y1082244D01*
G01X920500Y1085591D02*
X920503Y1085552D01*
X920511Y1085515D01*
X920523Y1085481D01*
X920541Y1085451D01*
X920561Y1085427D01*
X920585Y1085409D01*
X920611Y1085398D01*
X920639Y1085394D01*
G01X920500Y1088740D02*
X920503Y1088702D01*
X920511Y1088665D01*
X920523Y1088631D01*
X920541Y1088601D01*
X920561Y1088576D01*
X920585Y1088558D01*
X920611Y1088547D01*
X920639Y1088543D01*
G01X920500Y1091890D02*
X920503Y1091852D01*
X920511Y1091815D01*
X920523Y1091781D01*
X920541Y1091750D01*
X920561Y1091726D01*
X920585Y1091708D01*
X920611Y1091697D01*
X920639Y1091693D01*
G01X920500Y1095039D02*
X920503Y1095001D01*
X920511Y1094964D01*
X920523Y1094930D01*
X920541Y1094900D01*
X920561Y1094876D01*
X920585Y1094857D01*
X920611Y1094846D01*
X920639Y1094843D01*
G01X920500Y1098189D02*
X920503Y1098151D01*
X920511Y1098114D01*
X920523Y1098080D01*
X920541Y1098050D01*
X920561Y1098025D01*
X920585Y1098007D01*
X920611Y1097996D01*
X920639Y1097992D01*
G01X920500Y1101339D02*
X920503Y1101300D01*
X920511Y1101263D01*
X920523Y1101230D01*
X920541Y1101199D01*
X920561Y1101175D01*
X920585Y1101157D01*
X920611Y1101146D01*
X920639Y1101142D01*
G01X920500Y1104488D02*
X920503Y1104450D01*
X920511Y1104413D01*
X920523Y1104379D01*
X920541Y1104349D01*
X920561Y1104324D01*
X920585Y1104306D01*
X920611Y1104295D01*
X920639Y1104291D01*
G01X919323Y1101732D02*
Y1101339D01*
G01Y1104882D02*
Y1104488D01*
G01Y1098583D02*
Y1098189D01*
G01Y1095433D02*
Y1095039D01*
G01Y1092283D02*
Y1091890D01*
G01Y1089134D02*
Y1088740D01*
G01Y1082835D02*
Y1082441D01*
G01Y1085984D02*
Y1085591D01*
G01Y1079685D02*
Y1079291D01*
G01Y1073386D02*
Y1072992D01*
G01Y1076535D02*
Y1076142D01*
G01Y1070236D02*
Y1069843D01*
G01Y1067087D02*
Y1066693D01*
G01X919420Y1069744D02*
Y1070138D01*
G01X919485Y1074744D02*
Y1075138D01*
G01Y1079744D02*
Y1080138D01*
G01Y1089744D02*
Y1090138D01*
G01Y1094744D02*
Y1095138D01*
G01Y1099744D02*
Y1100138D01*
G01Y1104744D02*
Y1105138D01*
G01X920329Y1069744D02*
Y1070138D01*
G01Y1074744D02*
Y1075138D01*
G01Y1079744D02*
Y1080138D01*
G01Y1089744D02*
Y1090138D01*
G01Y1094744D02*
Y1095138D01*
G01Y1099744D02*
Y1100138D01*
G01Y1104744D02*
Y1105138D01*
G01X920500Y1101732D02*
Y1101339D01*
G01Y1104882D02*
Y1104488D01*
G01Y1098583D02*
Y1098189D01*
G01Y1095433D02*
Y1095039D01*
G01Y1092283D02*
Y1091890D01*
G01Y1089134D02*
Y1088740D01*
G01Y1082835D02*
Y1082441D01*
G01Y1085984D02*
Y1085591D01*
G01Y1079685D02*
Y1079291D01*
G01Y1073386D02*
Y1072992D01*
G01Y1076535D02*
Y1076142D01*
G01Y1070236D02*
Y1069843D01*
G01Y1067087D02*
Y1066693D01*
G01X921013D02*
Y1067087D01*
G01Y1069843D02*
Y1070236D01*
G01Y1072992D02*
Y1073386D01*
G01Y1076142D02*
Y1076535D01*
G01Y1079291D02*
Y1079685D01*
G01Y1082441D02*
Y1082835D01*
G01Y1085591D02*
Y1085984D01*
G01Y1088740D02*
Y1089134D01*
G01Y1095039D02*
Y1095433D01*
G01Y1091890D02*
Y1092283D01*
G01Y1098189D02*
Y1098583D01*
G01Y1101339D02*
Y1101732D01*
G01Y1104488D02*
Y1104882D01*
G01X921454Y1105138D02*
Y1104744D01*
G01Y1100138D02*
Y1099744D01*
G01Y1095138D02*
Y1094744D01*
G01Y1090138D02*
Y1089744D01*
G01Y1080138D02*
Y1079744D01*
G01Y1075138D02*
Y1074744D01*
G01Y1070138D02*
Y1069744D01*
G01Y1084744D02*
Y1085138D01*
G01X922298Y1084744D02*
Y1085138D01*
G01X923422D02*
Y1084744D01*
G01X923452Y1068366D02*
Y1067185D01*
G01X925935Y1066693D02*
Y1067087D01*
G01Y1069843D02*
Y1070236D01*
G01Y1072992D02*
Y1073386D01*
G01Y1076142D02*
Y1076535D01*
G01Y1079291D02*
Y1079685D01*
G01Y1082441D02*
Y1082835D01*
G01Y1085591D02*
Y1085984D01*
G01Y1088740D02*
Y1089134D01*
G01Y1095039D02*
Y1095433D01*
G01Y1091890D02*
Y1092283D01*
G01Y1098189D02*
Y1098583D01*
G01Y1101339D02*
Y1101732D01*
G01Y1104488D02*
Y1104882D01*
G01X926071Y1105138D02*
Y1104744D01*
G01Y1100138D02*
Y1099744D01*
G01Y1095138D02*
Y1094744D01*
G01Y1090138D02*
Y1089744D01*
G01Y1080138D02*
Y1079744D01*
G01Y1075138D02*
Y1074744D01*
G01X926162Y1070138D02*
Y1069744D01*
G01X928040Y1085138D02*
Y1084744D01*
G01X928740Y1144547D02*
Y1073642D01*
G01X928910D02*
Y1068162D01*
G01X921013Y1104882D02*
X921023Y1104980D01*
X921051Y1105052D01*
X921090Y1105079D01*
G01X921013Y1101732D02*
X921023Y1101831D01*
X921051Y1101903D01*
X921090Y1101929D01*
G01X921013Y1098583D02*
X921023Y1098681D01*
X921051Y1098753D01*
X921090Y1098780D01*
G01X921013Y1095433D02*
X921023Y1095531D01*
X921051Y1095604D01*
X921090Y1095630D01*
G01X921013Y1092283D02*
X921023Y1092382D01*
X921051Y1092454D01*
X921090Y1092480D01*
G01X921013Y1089134D02*
X921023Y1089232D01*
X921051Y1089304D01*
X921090Y1089331D01*
G01X921013Y1085984D02*
X921023Y1086083D01*
X921051Y1086155D01*
X921090Y1086181D01*
G01X921013Y1082835D02*
X921023Y1082933D01*
X921051Y1083005D01*
X921090Y1083031D01*
G01X921013Y1079685D02*
X921023Y1079783D01*
X921051Y1079856D01*
X921090Y1079882D01*
G01X921013Y1076535D02*
X921023Y1076634D01*
X921051Y1076706D01*
X921090Y1076732D01*
G01X921013Y1073386D02*
X921023Y1073484D01*
X921051Y1073556D01*
X921090Y1073583D01*
G01X921013Y1070236D02*
X921023Y1070335D01*
X921051Y1070407D01*
X921090Y1070433D01*
G01X921013Y1067087D02*
X921023Y1067185D01*
X921051Y1067257D01*
X921090Y1067283D01*
G01X921454Y1100138D02*
X921531Y1100728D01*
G01X921454Y1095138D02*
X921531Y1095728D01*
G01X921454Y1090138D02*
X921531Y1090728D01*
G01X921454Y1080138D02*
X921531Y1080728D01*
G01X921454Y1075138D02*
X921531Y1075728D01*
G01X923422Y1085138D02*
X923500Y1085728D01*
G01X921454Y1070138D02*
X921531Y1070728D01*
G01X919912Y1104154D02*
X919485Y1104744D01*
G01X928040Y1085138D02*
X927903Y1085335D01*
X927765Y1085532D01*
X927626Y1085728D01*
G01X926071Y1090138D02*
X925934Y1090335D01*
X925796Y1090532D01*
X925657Y1090728D01*
G01X926071Y1095138D02*
X925934Y1095335D01*
X925796Y1095532D01*
X925657Y1095728D01*
G01X926071Y1100138D02*
X925934Y1100335D01*
X925796Y1100532D01*
X925657Y1100728D01*
G01X926071Y1105138D02*
X925934Y1105335D01*
X925796Y1105532D01*
X925657Y1105728D01*
G01X920602Y1069154D02*
X920329Y1069744D01*
G01X920602Y1074154D02*
X920329Y1074744D01*
G01X920602Y1079154D02*
X920329Y1079744D01*
G01X922570Y1084154D02*
X922298Y1084744D01*
G01X920602Y1089154D02*
X920329Y1089744D01*
G01X920602Y1094154D02*
X920329Y1094744D01*
G01X920602Y1099154D02*
X920329Y1099744D01*
G01X920602Y1104154D02*
X920329Y1104744D01*
G01X925935Y1067087D02*
X925903Y1067183D01*
X925815Y1067256D01*
X925687Y1067283D01*
G01X925935Y1070236D02*
X925903Y1070333D01*
X925815Y1070405D01*
X925687Y1070433D01*
G01X925935Y1073386D02*
X925903Y1073483D01*
X925815Y1073555D01*
X925687Y1073583D01*
G01X925935Y1076535D02*
X925903Y1076632D01*
X925815Y1076704D01*
X925687Y1076732D01*
G01X925935Y1079685D02*
X925903Y1079782D01*
X925815Y1079854D01*
X925687Y1079882D01*
G01X925935Y1082835D02*
X925903Y1082931D01*
X925815Y1083004D01*
X925687Y1083031D01*
G01X925935Y1085984D02*
X925903Y1086081D01*
X925815Y1086153D01*
X925687Y1086181D01*
G01X925935Y1089134D02*
X925903Y1089231D01*
X925815Y1089303D01*
X925687Y1089331D01*
G01X925935Y1092283D02*
X925903Y1092380D01*
X925815Y1092452D01*
X925687Y1092480D01*
G01X925935Y1095433D02*
X925903Y1095530D01*
X925815Y1095602D01*
X925687Y1095630D01*
G01X925935Y1101732D02*
X925903Y1101829D01*
X925815Y1101901D01*
X925687Y1101929D01*
G01X925935Y1104882D02*
X925903Y1104979D01*
X925815Y1105051D01*
X925687Y1105079D01*
G01X921454Y1069744D02*
X921531Y1069154D01*
G01X921454Y1074744D02*
X921531Y1074154D01*
G01X921454Y1079744D02*
X921531Y1079154D01*
G01X921454Y1089744D02*
X921531Y1089154D01*
G01X921454Y1094744D02*
X921531Y1094154D01*
G01X923422Y1084744D02*
X923500Y1084154D01*
G01X921454Y1099744D02*
X921531Y1099154D01*
G01X921454Y1104744D02*
X921531Y1104154D01*
G01X925687Y1129488D02*
X925815Y1129516D01*
X925904Y1129589D01*
X925935Y1129685D01*
G01X925687Y1132638D02*
X925815Y1132665D01*
X925904Y1132738D01*
X925935Y1132835D01*
G01X925687Y1135787D02*
X925815Y1135815D01*
X925904Y1135888D01*
X925935Y1135984D01*
G01X925687Y1138937D02*
X925815Y1138965D01*
X925904Y1139037D01*
X925935Y1139134D01*
G01X920639Y1127126D02*
X920611Y1127122D01*
X920586Y1127111D01*
X920562Y1127093D01*
X920541Y1127068D01*
X920524Y1127039D01*
X920511Y1127005D01*
X920503Y1126968D01*
X920500Y1126929D01*
G01X920639Y1130276D02*
X920611Y1130272D01*
X920586Y1130261D01*
X920562Y1130243D01*
X920541Y1130218D01*
X920524Y1130188D01*
X920511Y1130154D01*
X920503Y1130118D01*
X920500Y1130079D01*
G01X920639Y1133425D02*
X920611Y1133421D01*
X920586Y1133410D01*
X920562Y1133392D01*
X920541Y1133367D01*
X920524Y1133338D01*
X920511Y1133304D01*
X920503Y1133267D01*
X920500Y1133228D01*
G01X920639Y1136575D02*
X920611Y1136571D01*
X920586Y1136560D01*
X920562Y1136542D01*
X920541Y1136517D01*
X920524Y1136487D01*
X920511Y1136454D01*
X920503Y1136417D01*
X920500Y1136378D01*
G01X927626Y1125728D02*
X921880D01*
G01X925687Y1126339D02*
X919603D01*
G01X925935Y1126535D02*
X919323D01*
G01Y1126929D02*
X925935D01*
G01X925687Y1127126D02*
X919603D01*
G01X925657Y1129154D02*
X919912D01*
G01X925687Y1129488D02*
X919603D01*
G01X925935Y1129685D02*
X919323D01*
G01X919485Y1129744D02*
X926071D01*
G01X919323Y1130079D02*
X925935D01*
G01X919485Y1130138D02*
X926071D01*
G01X925687Y1130276D02*
X919603D01*
G01X925657Y1130728D02*
X919912D01*
G01X925687Y1132638D02*
X919603D01*
G01X925935Y1132835D02*
X919323D01*
G01Y1133228D02*
X925935D01*
G01X925687Y1133425D02*
X919603D01*
G01X925657Y1134154D02*
X919912D01*
G01X919485Y1134744D02*
X926071D01*
G01X919485Y1135138D02*
X926071D01*
G01X925657Y1135728D02*
X919912D01*
G01X925687Y1135787D02*
X919603D01*
G01X925935Y1135984D02*
X919323D01*
G01Y1136378D02*
X925935D01*
G01X925687Y1136575D02*
X919603D01*
G01X925687Y1127126D02*
X925814Y1127098D01*
X925903Y1127026D01*
X925935Y1126929D01*
G01X920329Y1135138D02*
X920602Y1135728D01*
G01X920329Y1130138D02*
X920602Y1130728D01*
G01X925657Y1134154D02*
X925796Y1134350D01*
X925934Y1134546D01*
X926071Y1134744D01*
G01X925657Y1129154D02*
X925796Y1129350D01*
X925934Y1129546D01*
X926071Y1129744D01*
G01X919912Y1135728D02*
X919485Y1135138D01*
G01X919912Y1130728D02*
X919485Y1130138D01*
G01X921531Y1135728D02*
X921454Y1135138D01*
G01Y1130138D02*
X921531Y1130728D01*
G01X925935Y1126535D02*
X925901Y1126436D01*
X925813Y1126365D01*
X925687Y1126339D01*
G01X921090D02*
X921051Y1126365D01*
X921023Y1126437D01*
X921013Y1126535D01*
G01X921090Y1129488D02*
X921051Y1129515D01*
X921023Y1129587D01*
X921013Y1129685D01*
G01X921090Y1132638D02*
X921051Y1132664D01*
X921023Y1132736D01*
X921013Y1132835D01*
G01X921090Y1135787D02*
X921051Y1135814D01*
X921023Y1135886D01*
X921013Y1135984D01*
G01X921090Y1138937D02*
X921051Y1138963D01*
X921023Y1139035D01*
X921013Y1139134D01*
G01X920500Y1126535D02*
X920503Y1126497D01*
X920511Y1126460D01*
X920523Y1126426D01*
X920541Y1126396D01*
X920561Y1126372D01*
X920585Y1126354D01*
X920611Y1126343D01*
X920639Y1126339D01*
G01X920500Y1129685D02*
X920503Y1129647D01*
X920511Y1129610D01*
X920523Y1129576D01*
X920541Y1129546D01*
X920561Y1129521D01*
X920585Y1129503D01*
X920611Y1129492D01*
X920639Y1129488D01*
G01X920500Y1132835D02*
X920503Y1132796D01*
X920511Y1132759D01*
X920523Y1132726D01*
X920541Y1132695D01*
X920561Y1132671D01*
X920585Y1132653D01*
X920611Y1132642D01*
X920639Y1132638D01*
G01X920500Y1135984D02*
X920503Y1135946D01*
X920511Y1135909D01*
X920523Y1135875D01*
X920541Y1135845D01*
X920561Y1135820D01*
X920585Y1135802D01*
X920611Y1135791D01*
X920639Y1135787D01*
G01X920500Y1139134D02*
X920503Y1139096D01*
X920511Y1139059D01*
X920523Y1139025D01*
X920541Y1138994D01*
X920561Y1138970D01*
X920585Y1138952D01*
X920611Y1138941D01*
X920639Y1138937D01*
G01X919323Y1136378D02*
Y1135984D01*
G01Y1133228D02*
Y1132835D01*
G01Y1130079D02*
Y1129685D01*
G01Y1126929D02*
Y1126535D01*
G01X919485Y1129744D02*
Y1130138D01*
G01Y1134744D02*
Y1135138D01*
G01X920329Y1129744D02*
Y1130138D01*
G01Y1134744D02*
Y1135138D01*
G01X920500Y1136378D02*
Y1135984D01*
G01Y1133228D02*
Y1132835D01*
G01Y1130079D02*
Y1129685D01*
G01Y1126929D02*
Y1126535D01*
G01X921013D02*
Y1126929D01*
G01Y1132835D02*
Y1133228D01*
G01Y1129685D02*
Y1130079D01*
G01Y1135984D02*
Y1136378D01*
G01X921454Y1130138D02*
Y1129744D01*
G01Y1134744D02*
Y1135138D01*
G01X925935Y1126535D02*
Y1126929D01*
G01Y1132835D02*
Y1133228D01*
G01Y1129685D02*
Y1130079D01*
G01Y1135984D02*
Y1136378D01*
G01X926071Y1135138D02*
Y1134744D01*
G01Y1130138D02*
Y1129744D01*
G01X921013Y1136378D02*
X921023Y1136476D01*
X921051Y1136548D01*
X921090Y1136575D01*
G01X921013Y1133228D02*
X921023Y1133327D01*
X921051Y1133399D01*
X921090Y1133425D01*
G01X921013Y1130079D02*
X921023Y1130177D01*
X921051Y1130249D01*
X921090Y1130276D01*
G01X921013Y1126929D02*
X921023Y1127028D01*
X921051Y1127100D01*
X921090Y1127126D01*
G01X919912Y1129154D02*
X919485Y1129744D01*
G01X919912Y1134154D02*
X919485Y1134744D01*
G01X926071Y1130138D02*
X925934Y1130335D01*
X925796Y1130532D01*
X925657Y1130728D01*
G01X926071Y1135138D02*
X925934Y1135335D01*
X925796Y1135532D01*
X925657Y1135728D01*
G01X920602Y1129154D02*
X920329Y1129744D01*
G01X920602Y1134154D02*
X920329Y1134744D01*
G01X925935Y1130079D02*
X925903Y1130176D01*
X925815Y1130248D01*
X925687Y1130276D01*
G01X925935Y1133228D02*
X925903Y1133325D01*
X925815Y1133397D01*
X925687Y1133425D01*
G01X925935Y1136378D02*
X925903Y1136475D01*
X925815Y1136547D01*
X925687Y1136575D01*
G01X921454Y1129744D02*
X921531Y1129154D01*
G01Y1134154D02*
X921454Y1134744D01*
G01X925687Y1107441D02*
X925815Y1107469D01*
X925904Y1107541D01*
X925935Y1107638D01*
G01X925687Y1110591D02*
X925815Y1110618D01*
X925904Y1110691D01*
X925935Y1110787D01*
G01X925687Y1113740D02*
X925815Y1113768D01*
X925904Y1113841D01*
X925935Y1113937D01*
G01X925687Y1116890D02*
X925815Y1116917D01*
X925904Y1116990D01*
X925935Y1117087D01*
G01X925687Y1120039D02*
X925815Y1120067D01*
X925904Y1120140D01*
X925935Y1120236D01*
G01X925687Y1123189D02*
X925815Y1123217D01*
X925904Y1123289D01*
X925935Y1123386D01*
G01X920639Y1108228D02*
X920611Y1108224D01*
X920586Y1108213D01*
X920562Y1108195D01*
X920541Y1108170D01*
X920524Y1108141D01*
X920511Y1108107D01*
X920503Y1108070D01*
X920500Y1108031D01*
G01X920639Y1111378D02*
X920611Y1111374D01*
X920586Y1111363D01*
X920562Y1111345D01*
X920541Y1111320D01*
X920524Y1111291D01*
X920511Y1111257D01*
X920503Y1111220D01*
X920500Y1111181D01*
G01X920639Y1114528D02*
X920611Y1114524D01*
X920586Y1114513D01*
X920562Y1114494D01*
X920541Y1114470D01*
X920524Y1114440D01*
X920511Y1114406D01*
X920503Y1114370D01*
X920500Y1114331D01*
G01X920639Y1117677D02*
X920611Y1117673D01*
X920586Y1117662D01*
X920562Y1117644D01*
X920541Y1117619D01*
X920524Y1117590D01*
X920511Y1117556D01*
X920503Y1117519D01*
X920500Y1117480D01*
G01X920639Y1120827D02*
X920611Y1120823D01*
X920586Y1120812D01*
X920562Y1120794D01*
X920541Y1120769D01*
X920524Y1120739D01*
X920511Y1120706D01*
X920503Y1120669D01*
X920500Y1120630D01*
G01X920639Y1123976D02*
X920611Y1123972D01*
X920586Y1123961D01*
X920562Y1123943D01*
X920541Y1123919D01*
X920524Y1123889D01*
X920511Y1123855D01*
X920503Y1123819D01*
X920500Y1123780D01*
G01X925657Y1105728D02*
X919912D01*
G01X925687Y1107441D02*
X919603D01*
G01X925935Y1107638D02*
X919323D01*
G01Y1108031D02*
X925935D01*
G01X925687Y1108228D02*
X919603D01*
G01X925657Y1109154D02*
X919912D01*
G01X919485Y1109744D02*
X926071D01*
G01X919485Y1110138D02*
X926071D01*
G01X925687Y1110591D02*
X919603D01*
G01X925657Y1110728D02*
X919912D01*
G01X925935Y1110787D02*
X919323D01*
G01Y1111181D02*
X925935D01*
G01X925687Y1111378D02*
X919603D01*
G01X925687Y1113740D02*
X919603D01*
G01X925935Y1113937D02*
X919323D01*
G01X925657Y1114154D02*
X919912D01*
G01X919323Y1114331D02*
X925935D01*
G01X925687Y1114528D02*
X919603D01*
G01X919485Y1114744D02*
X926071D01*
G01X919485Y1115138D02*
X926071D01*
G01X925657Y1115728D02*
X919912D01*
G01X925687Y1116890D02*
X919603D01*
G01X925935Y1117087D02*
X919323D01*
G01Y1117480D02*
X925935D01*
G01X925687Y1117677D02*
X919603D01*
G01X925657Y1119154D02*
X919912D01*
G01X919485Y1119744D02*
X926071D01*
G01X925687Y1120039D02*
X919603D01*
G01X919485Y1120138D02*
X926071D01*
G01X925935Y1120236D02*
X919323D01*
G01Y1120630D02*
X925935D01*
G01X925657Y1120728D02*
X919912D01*
G01X925687Y1120827D02*
X919603D01*
G01X925687Y1123189D02*
X919603D01*
G01X925935Y1123386D02*
X919323D01*
G01Y1123780D02*
X925935D01*
G01X925687Y1123976D02*
X919603D01*
G01X927626Y1124154D02*
X921880D01*
G01X921454Y1124744D02*
X928040D01*
G01X921454Y1125138D02*
X928040D01*
G01X927626Y1124154D02*
X927765Y1124350D01*
X927903Y1124546D01*
X928040Y1124744D01*
G01X925657Y1119154D02*
X925796Y1119350D01*
X925934Y1119546D01*
X926071Y1119744D01*
G01X925657Y1114154D02*
X925796Y1114350D01*
X925934Y1114546D01*
X926071Y1114744D01*
G01X925657Y1109154D02*
X925796Y1109350D01*
X925934Y1109546D01*
X926071Y1109744D01*
G01X921880Y1125728D02*
X921454Y1125138D01*
G01X919912Y1120728D02*
X919485Y1120138D01*
G01X919912Y1115728D02*
X919485Y1115138D01*
G01X919912Y1110728D02*
X919485Y1110138D01*
G01X921454Y1120138D02*
X921531Y1120728D01*
G01X921454Y1115138D02*
X921531Y1115728D01*
G01X923422Y1125138D02*
X923500Y1125728D01*
G01X921454Y1110138D02*
X921531Y1110728D01*
G01X922298Y1125138D02*
X922570Y1125728D01*
G01X920329Y1120138D02*
X920602Y1120728D01*
G01X920329Y1115138D02*
X920602Y1115728D01*
G01X920329Y1110138D02*
X920602Y1110728D01*
G01X921090Y1107441D02*
X921051Y1107467D01*
X921023Y1107539D01*
X921013Y1107638D01*
G01X921090Y1110591D02*
X921051Y1110617D01*
X921023Y1110689D01*
X921013Y1110787D01*
G01X921090Y1113740D02*
X921051Y1113767D01*
X921023Y1113839D01*
X921013Y1113937D01*
G01X921090Y1116890D02*
X921051Y1116916D01*
X921023Y1116988D01*
X921013Y1117087D01*
G01X921090Y1120039D02*
X921051Y1120066D01*
X921023Y1120138D01*
X921013Y1120236D01*
G01X921090Y1123189D02*
X921051Y1123215D01*
X921023Y1123287D01*
X921013Y1123386D01*
G01X920500Y1107638D02*
X920503Y1107600D01*
X920511Y1107563D01*
X920523Y1107529D01*
X920541Y1107498D01*
X920561Y1107474D01*
X920585Y1107456D01*
X920611Y1107445D01*
X920639Y1107441D01*
G01X920500Y1110787D02*
X920503Y1110749D01*
X920511Y1110712D01*
X920523Y1110678D01*
X920541Y1110648D01*
X920561Y1110624D01*
X920585Y1110606D01*
X920611Y1110594D01*
X920639Y1110591D01*
G01X920500Y1113937D02*
X920503Y1113899D01*
X920511Y1113862D01*
X920523Y1113828D01*
X920541Y1113798D01*
X920561Y1113773D01*
X920585Y1113755D01*
X920611Y1113744D01*
X920639Y1113740D01*
G01X920500Y1117087D02*
X920503Y1117048D01*
X920511Y1117011D01*
X920523Y1116978D01*
X920541Y1116947D01*
X920561Y1116923D01*
X920585Y1116905D01*
X920611Y1116894D01*
X920639Y1116890D01*
G01X920500Y1120236D02*
X920503Y1120198D01*
X920511Y1120161D01*
X920523Y1120127D01*
X920541Y1120097D01*
X920561Y1120072D01*
X920585Y1120054D01*
X920611Y1120043D01*
X920639Y1120039D01*
G01X920500Y1123386D02*
X920503Y1123348D01*
X920511Y1123311D01*
X920523Y1123277D01*
X920541Y1123246D01*
X920561Y1123222D01*
X920585Y1123204D01*
X920611Y1123193D01*
X920639Y1123189D01*
G01X919323Y1123780D02*
Y1123386D01*
G01Y1120630D02*
Y1120236D01*
G01Y1117480D02*
Y1117087D01*
G01Y1114331D02*
Y1113937D01*
G01Y1111181D02*
Y1110787D01*
G01Y1108031D02*
Y1107638D01*
G01X919485Y1109744D02*
Y1110138D01*
G01Y1114744D02*
Y1115138D01*
G01Y1119744D02*
Y1120138D01*
G01X920329Y1109744D02*
Y1110138D01*
G01Y1114744D02*
Y1115138D01*
G01Y1119744D02*
Y1120138D01*
G01X920500Y1123780D02*
Y1123386D01*
G01Y1120630D02*
Y1120236D01*
G01Y1117480D02*
Y1117087D01*
G01Y1114331D02*
Y1113937D01*
G01Y1111181D02*
Y1110787D01*
G01Y1108031D02*
Y1107638D01*
G01X921013D02*
Y1108031D01*
G01Y1113937D02*
Y1114331D01*
G01Y1110787D02*
Y1111181D01*
G01Y1117087D02*
Y1117480D01*
G01Y1123386D02*
Y1123780D01*
G01Y1120236D02*
Y1120630D01*
G01X921454Y1120138D02*
Y1119744D01*
G01Y1115138D02*
Y1114744D01*
G01Y1110138D02*
Y1109744D01*
G01Y1124744D02*
Y1125138D01*
G01X922298Y1124744D02*
Y1125138D01*
G01X923422D02*
Y1124744D01*
G01X925935Y1107638D02*
Y1108031D01*
G01Y1113937D02*
Y1114331D01*
G01Y1110787D02*
Y1111181D01*
G01Y1117087D02*
Y1117480D01*
G01Y1123386D02*
Y1123780D01*
G01Y1120236D02*
Y1120630D01*
G01X926071Y1120138D02*
Y1119744D01*
G01Y1115138D02*
Y1114744D01*
G01Y1110138D02*
Y1109744D01*
G01X928040Y1125138D02*
Y1124744D01*
G01X921013Y1123780D02*
X921023Y1123878D01*
X921051Y1123950D01*
X921090Y1123976D01*
G01X921013Y1120630D02*
X921023Y1120728D01*
X921051Y1120800D01*
X921090Y1120827D01*
G01X921013Y1117480D02*
X921023Y1117579D01*
X921051Y1117651D01*
X921090Y1117677D01*
G01X921013Y1114331D02*
X921023Y1114429D01*
X921051Y1114501D01*
X921090Y1114528D01*
G01X921013Y1111181D02*
X921023Y1111280D01*
X921051Y1111352D01*
X921090Y1111378D01*
G01X921013Y1108031D02*
X921023Y1108130D01*
X921051Y1108202D01*
X921090Y1108228D01*
G01X919912Y1109154D02*
X919485Y1109744D01*
G01X919912Y1114154D02*
X919485Y1114744D01*
G01X919912Y1119154D02*
X919485Y1119744D01*
G01X921880Y1124154D02*
X921454Y1124744D01*
G01X926071Y1110138D02*
X925934Y1110335D01*
X925796Y1110532D01*
X925657Y1110728D01*
G01X926071Y1115138D02*
X925934Y1115335D01*
X925796Y1115532D01*
X925657Y1115728D01*
G01X926071Y1120138D02*
X925934Y1120335D01*
X925796Y1120532D01*
X925657Y1120728D01*
G01X928040Y1125138D02*
X927903Y1125335D01*
X927765Y1125532D01*
X927626Y1125728D01*
G01X920602Y1109154D02*
X920329Y1109744D01*
G01X920602Y1114154D02*
X920329Y1114744D01*
G01X920602Y1119154D02*
X920329Y1119744D01*
G01X922570Y1124154D02*
X922298Y1124744D01*
G01X925935Y1108031D02*
X925903Y1108128D01*
X925815Y1108200D01*
X925687Y1108228D01*
G01X925935Y1111181D02*
X925903Y1111278D01*
X925815Y1111350D01*
X925687Y1111378D01*
G01X925935Y1114331D02*
X925903Y1114428D01*
X925815Y1114500D01*
X925687Y1114528D01*
G01X925935Y1117480D02*
X925903Y1117577D01*
X925815Y1117649D01*
X925687Y1117677D01*
G01X925935Y1120630D02*
X925903Y1120727D01*
X925815Y1120799D01*
X925687Y1120827D01*
G01X925935Y1123780D02*
X925903Y1123876D01*
X925815Y1123948D01*
X925687Y1123976D01*
G01X921454Y1109744D02*
X921531Y1109154D01*
G01X921454Y1114744D02*
X921531Y1114154D01*
G01X921454Y1119744D02*
X921531Y1119154D01*
G01X923422Y1124744D02*
X923500Y1124154D01*
G01X933204Y1148681D02*
X936614Y1150650D01*
G01X920639Y1139724D02*
X920611Y1139720D01*
X920586Y1139709D01*
X920562Y1139691D01*
X920541Y1139667D01*
X920524Y1139637D01*
X920511Y1139603D01*
X920503Y1139567D01*
X920500Y1139528D01*
G01X925687Y1138937D02*
X919603D01*
G01X925935Y1139134D02*
X919323D01*
G01X925657Y1139154D02*
X919912D01*
G01X919323Y1139528D02*
X925935D01*
G01X925687Y1139724D02*
X919603D01*
G01X919485Y1139744D02*
X926071D01*
G01X919485Y1140138D02*
X926071D01*
G01X925657Y1140728D02*
X919912D01*
G01X933204Y1148681D02*
X929921D01*
G01X927953Y1143760D02*
X929921Y1145728D01*
G01X920329Y1140138D02*
X920602Y1140728D01*
G01X925657Y1139154D02*
X925796Y1139350D01*
X925934Y1139546D01*
X926071Y1139744D01*
G01X919912Y1140728D02*
X919485Y1140138D01*
G01X921454D02*
X921531Y1140728D01*
G01X919323Y1139528D02*
Y1139134D01*
G01X919485Y1139744D02*
Y1140138D01*
G01X920329Y1139744D02*
Y1140138D01*
G01X920500Y1139528D02*
Y1139134D01*
G01X921013D02*
Y1139528D01*
G01X921454Y1140138D02*
Y1139744D01*
G01X925935Y1139134D02*
Y1139528D01*
G01X926071Y1140138D02*
Y1139744D01*
G01X931890Y1148681D02*
Y1155846D01*
G01X936614Y1150650D02*
Y1152382D01*
G01X921013Y1139528D02*
X921023Y1139626D01*
X921051Y1139698D01*
X921090Y1139724D01*
G01X931947Y1156296D02*
X931984Y1156619D01*
X931978Y1156860D01*
X931921Y1156996D01*
G01X931948Y1156297D02*
X931894Y1155920D01*
G01D02*
X936614Y1151278D01*
G01Y1152382D02*
X931890Y1157028D01*
G01X927953Y1148681D02*
X929921Y1146713D01*
G01X919912Y1139154D02*
X919485Y1139744D01*
G01X926071Y1140138D02*
X925934Y1140335D01*
X925796Y1140532D01*
X925657Y1140728D01*
G01X920602Y1139154D02*
X920329Y1139744D01*
G01X931921Y1156996D02*
X931979Y1156856D01*
X931984Y1156617D01*
G01X925935Y1139528D02*
X925903Y1139624D01*
X925815Y1139696D01*
X925687Y1139724D01*
G01X921454Y1139744D02*
X921531Y1139154D01*
G01X919912Y1426240D02*
X919485Y1425650D01*
G01X925657Y1429665D02*
X925796Y1429861D01*
X925934Y1430058D01*
X926071Y1430256D01*
G01X920329Y1425650D02*
X920602Y1426240D01*
G01X921013Y1428504D02*
X921023Y1428602D01*
X921051Y1428674D01*
X921090Y1428701D01*
G01X921013Y1425354D02*
X921023Y1425453D01*
X921051Y1425525D01*
X921090Y1425551D01*
G01X921454Y1425650D02*
X921531Y1426240D01*
G01X925687Y1427913D02*
X925815Y1427941D01*
X925904Y1428014D01*
X925935Y1428110D01*
G01X920639Y1425551D02*
X920611Y1425547D01*
X920586Y1425536D01*
X920562Y1425518D01*
X920541Y1425493D01*
X920524Y1425464D01*
X920511Y1425430D01*
X920503Y1425393D01*
X920500Y1425354D01*
G01X920639Y1428701D02*
X920611Y1428697D01*
X920586Y1428686D01*
X920562Y1428668D01*
X920541Y1428643D01*
X920524Y1428613D01*
X920511Y1428580D01*
X920503Y1428543D01*
X920500Y1428504D01*
G01Y1428110D02*
X920503Y1428072D01*
X920511Y1428035D01*
X920523Y1428001D01*
X920541Y1427971D01*
X920561Y1427946D01*
X920585Y1427928D01*
X920611Y1427917D01*
X920639Y1427913D01*
G01X919323Y1428504D02*
Y1428110D01*
G01X920500Y1428504D02*
Y1428110D01*
G01X921013D02*
Y1428504D01*
G01X925935Y1428110D02*
Y1428504D01*
G01X919323Y1425354D02*
X925935D01*
G01X925687Y1425551D02*
X919603D01*
G01X919485Y1425650D02*
X926071D01*
G01X925657Y1426240D02*
X919912D01*
G01X925687Y1427913D02*
X919603D01*
G01X925935Y1428110D02*
X919323D01*
G01Y1428504D02*
X925935D01*
G01X925687Y1428701D02*
X919603D01*
G01X925657Y1429665D02*
X919912D01*
G01X921454Y1430256D02*
X921531Y1429665D01*
G01X925935Y1425354D02*
X925903Y1425451D01*
X925815Y1425523D01*
X925687Y1425551D01*
G01X925935Y1428504D02*
X925903Y1428601D01*
X925815Y1428673D01*
X925687Y1428701D01*
G01X921090Y1427913D02*
X921051Y1427940D01*
X921023Y1428012D01*
X921013Y1428110D01*
G01X919912Y1429665D02*
X919485Y1430256D01*
G01X926071Y1425650D02*
X925934Y1425847D01*
X925796Y1426044D01*
X925657Y1426240D01*
G01X920602Y1429665D02*
X920329Y1430256D01*
G01X921090Y1422402D02*
X921051Y1422375D01*
X921023Y1422303D01*
X921013Y1422205D01*
G01X929921Y1413681D02*
X927953Y1411713D01*
G01X936614Y1409115D02*
X931894Y1404474D01*
G01X936614Y1408012D02*
X931890Y1403366D01*
G01X919912Y1421240D02*
X919485Y1420650D01*
G01X925657Y1424665D02*
X925796Y1424861D01*
X925934Y1425058D01*
X926071Y1425256D01*
G01X925657Y1419665D02*
X925796Y1419861D01*
X925934Y1420058D01*
X926071Y1420256D01*
G01X931921Y1403397D02*
X931979Y1403537D01*
X931984Y1403777D01*
G01X931921Y1403397D02*
X931978Y1403532D01*
X931984Y1403767D01*
X931948Y1404096D01*
G01X920329Y1420650D02*
X920602Y1421240D01*
G01X921454Y1420650D02*
X921531Y1421240D01*
G01X925687Y1421614D02*
X925815Y1421642D01*
X925904Y1421715D01*
X925935Y1421811D01*
G01X925687Y1424764D02*
X925815Y1424791D01*
X925904Y1424864D01*
X925935Y1424961D01*
G01X920639Y1422402D02*
X920611Y1422398D01*
X920586Y1422387D01*
X920562Y1422369D01*
X920541Y1422344D01*
X920524Y1422314D01*
X920511Y1422280D01*
X920503Y1422244D01*
X920500Y1422205D01*
G01Y1421811D02*
X920503Y1421773D01*
X920511Y1421736D01*
X920523Y1421702D01*
X920541Y1421672D01*
X920561Y1421647D01*
X920585Y1421629D01*
X920611Y1421618D01*
X920639Y1421614D01*
G01X920500Y1424961D02*
X920503Y1424922D01*
X920511Y1424885D01*
X920523Y1424852D01*
X920541Y1424821D01*
X920561Y1424797D01*
X920585Y1424779D01*
X920611Y1424768D01*
X920639Y1424764D01*
G01X919323Y1425354D02*
Y1424961D01*
G01Y1422205D02*
Y1421811D01*
G01X919485Y1420256D02*
Y1420650D01*
G01Y1425256D02*
Y1425650D01*
G01X920329Y1420256D02*
Y1420650D01*
G01Y1425256D02*
Y1425650D01*
G01X920500Y1425354D02*
Y1424961D01*
G01Y1422205D02*
Y1421811D01*
G01X921013D02*
Y1422205D01*
G01Y1424961D02*
Y1425354D01*
G01X921454Y1425650D02*
Y1425256D01*
G01Y1420650D02*
Y1420256D01*
G01X925935Y1421811D02*
Y1422205D01*
G01Y1424961D02*
Y1425354D01*
G01X926071Y1425650D02*
Y1425256D01*
G01Y1420650D02*
Y1420256D01*
G01X927953Y1416634D02*
Y1549272D01*
G01X928740Y1446850D02*
Y1415846D01*
G01X928799Y1549665D02*
Y1416240D01*
G01X929921Y1411713D02*
Y1554193D01*
G01X931890Y1404547D02*
Y1411713D01*
G01X936614Y1409744D02*
Y1408012D01*
G01X933204Y1411713D02*
X929921D01*
G01X925657Y1419665D02*
X919912D01*
G01X919485Y1420256D02*
X926071D01*
G01X919485Y1420650D02*
X926071D01*
G01X925657Y1421240D02*
X919912D01*
G01X925687Y1421614D02*
X919603D01*
G01X925935Y1421811D02*
X919323D01*
G01Y1422205D02*
X925935D01*
G01X925687Y1422402D02*
X919603D01*
G01X925657Y1424665D02*
X919912D01*
G01X925687Y1424764D02*
X919603D01*
G01X925935Y1424961D02*
X919323D01*
G01X919485Y1425256D02*
X926071D01*
G01X921454Y1420256D02*
X921531Y1419665D01*
G01X921454Y1425256D02*
X921531Y1424665D01*
G01X925935Y1422205D02*
X925903Y1422302D01*
X925815Y1422374D01*
X925687Y1422402D01*
G01X931949Y1404088D02*
X931894Y1404474D01*
G01X933204Y1411713D02*
X936614Y1409744D01*
G01X921090Y1421614D02*
X921051Y1421641D01*
X921023Y1421713D01*
X921013Y1421811D01*
G01X921090Y1424764D02*
X921051Y1424790D01*
X921023Y1424862D01*
X921013Y1424961D01*
G01X929921Y1414665D02*
X927953Y1416634D01*
G01X919912Y1419665D02*
X919485Y1420256D01*
G01X919912Y1424665D02*
X919485Y1425256D01*
G01X926071Y1420650D02*
X925934Y1420847D01*
X925796Y1421044D01*
X925657Y1421240D01*
G01X920602Y1419665D02*
X920329Y1420256D01*
G01X920602Y1424665D02*
X920329Y1425256D01*
G01X921090Y1450748D02*
X921051Y1450722D01*
X921023Y1450649D01*
X921013Y1450551D01*
G01X921090Y1447598D02*
X921051Y1447572D01*
X921023Y1447500D01*
X921013Y1447402D01*
G01X921090Y1438150D02*
X921051Y1438123D01*
X921023Y1438051D01*
X921013Y1437953D01*
G01X921090Y1435000D02*
X921051Y1434974D01*
X921023Y1434901D01*
X921013Y1434803D01*
G01X921090Y1431850D02*
X921051Y1431824D01*
X921023Y1431752D01*
X921013Y1431654D01*
G01X925757Y1449665D02*
X925893Y1449861D01*
X926028Y1450058D01*
X926162Y1450256D01*
G01X925657Y1444665D02*
X925796Y1444861D01*
X925934Y1445058D01*
X926071Y1445256D01*
G01X925657Y1439665D02*
X925796Y1439861D01*
X925934Y1440058D01*
X926071Y1440256D01*
G01X925657Y1434665D02*
X925796Y1434861D01*
X925934Y1435058D01*
X926071Y1435256D01*
G01X919844Y1451240D02*
X919420Y1450650D01*
G01X919912Y1446240D02*
X919485Y1445650D01*
G01X919912Y1441240D02*
X919485Y1440650D01*
G01X919912Y1436240D02*
X919485Y1435650D01*
G01X919912Y1431240D02*
X919485Y1430650D01*
G01X920329Y1450650D02*
X920602Y1451240D01*
G01X920329Y1445650D02*
X920602Y1446240D01*
G01X920329Y1440650D02*
X920602Y1441240D01*
G01X920329Y1435650D02*
X920602Y1436240D01*
G01X920329Y1430650D02*
X920602Y1431240D01*
G01X920569Y1465022D02*
X920571Y1465060D01*
X920580Y1465097D01*
X920593Y1465131D01*
X920612Y1465161D01*
X920634Y1465185D01*
X920659Y1465204D01*
X920687Y1465215D01*
X920717Y1465219D01*
G01X920569Y1461872D02*
X920571Y1461910D01*
X920580Y1461947D01*
X920593Y1461981D01*
X920612Y1462011D01*
X920634Y1462036D01*
X920659Y1462054D01*
X920687Y1462065D01*
X920717Y1462069D01*
G01X920569Y1458722D02*
X920571Y1458761D01*
X920580Y1458798D01*
X920593Y1458831D01*
X920612Y1458862D01*
X920634Y1458886D01*
X920659Y1458904D01*
X920687Y1458915D01*
X920717Y1458919D01*
G01X920569Y1455573D02*
X920571Y1455611D01*
X920580Y1455648D01*
X920593Y1455682D01*
X920612Y1455712D01*
X920634Y1455737D01*
X920659Y1455755D01*
X920687Y1455766D01*
X920717Y1455770D01*
G01X921013Y1463150D02*
X921023Y1463248D01*
X921051Y1463320D01*
X921090Y1463346D01*
G01X921013Y1460000D02*
X921023Y1460098D01*
X921051Y1460170D01*
X921090Y1460197D01*
G01X921013Y1456850D02*
X921023Y1456949D01*
X921051Y1457021D01*
X921090Y1457047D01*
G01X921013Y1453701D02*
X921023Y1453799D01*
X921051Y1453871D01*
X921090Y1453898D01*
G01X921013Y1444252D02*
X921023Y1444350D01*
X921051Y1444422D01*
X921090Y1444449D01*
G01X921013Y1441102D02*
X921023Y1441201D01*
X921051Y1441273D01*
X921090Y1441299D01*
G01X921454Y1450650D02*
X921531Y1451240D01*
G01X921454Y1445650D02*
X921531Y1446240D01*
G01X921454Y1440650D02*
X921531Y1441240D01*
G01X921454Y1435650D02*
X921531Y1436240D01*
G01X921454Y1430650D02*
X921531Y1431240D01*
G01X925687Y1431063D02*
X925815Y1431091D01*
X925904Y1431163D01*
X925935Y1431260D01*
G01X925687Y1434213D02*
X925815Y1434240D01*
X925904Y1434313D01*
X925935Y1434409D01*
G01X925687Y1437362D02*
X925815Y1437390D01*
X925904Y1437463D01*
X925935Y1437559D01*
G01X925687Y1440512D02*
X925815Y1440539D01*
X925904Y1440612D01*
X925935Y1440709D01*
G01X925687Y1443661D02*
X925815Y1443689D01*
X925904Y1443762D01*
X925935Y1443858D01*
G01X925687Y1446811D02*
X925815Y1446839D01*
X925904Y1446911D01*
X925935Y1447008D01*
G01X925687Y1449961D02*
X925815Y1449988D01*
X925904Y1450061D01*
X925935Y1450157D01*
G01X925687Y1453110D02*
X925815Y1453138D01*
X925904Y1453211D01*
X925935Y1453307D01*
G01X925687Y1456260D02*
X925815Y1456287D01*
X925904Y1456360D01*
X925935Y1456457D01*
G01X925687Y1459409D02*
X925815Y1459437D01*
X925904Y1459510D01*
X925935Y1459606D01*
G01X925687Y1462559D02*
X925815Y1462587D01*
X925904Y1462659D01*
X925935Y1462756D01*
G01X925697Y1454392D02*
X925824Y1454419D01*
X925913Y1454492D01*
X925944Y1454589D01*
G01X925697Y1457541D02*
X925824Y1457569D01*
X925913Y1457641D01*
X925944Y1457738D01*
G01X925697Y1460691D02*
X925824Y1460719D01*
X925913Y1460791D01*
X925944Y1460888D01*
G01X925697Y1463841D02*
X925824Y1463868D01*
X925913Y1463941D01*
X925944Y1464037D01*
G01X920639Y1431850D02*
X920611Y1431846D01*
X920586Y1431835D01*
X920562Y1431817D01*
X920541Y1431793D01*
X920524Y1431763D01*
X920511Y1431729D01*
X920503Y1431693D01*
X920500Y1431654D01*
G01X920639Y1435000D02*
X920611Y1434996D01*
X920586Y1434985D01*
X920562Y1434967D01*
X920541Y1434942D01*
X920524Y1434913D01*
X920511Y1434879D01*
X920503Y1434842D01*
X920500Y1434803D01*
G01X920639Y1438150D02*
X920611Y1438146D01*
X920586Y1438135D01*
X920562Y1438117D01*
X920541Y1438092D01*
X920524Y1438062D01*
X920511Y1438028D01*
X920503Y1437992D01*
X920500Y1437953D01*
G01X920639Y1441299D02*
X920611Y1441295D01*
X920586Y1441284D01*
X920562Y1441266D01*
X920541Y1441241D01*
X920524Y1441212D01*
X920511Y1441178D01*
X920503Y1441141D01*
X920500Y1441102D01*
G01X920639Y1444449D02*
X920611Y1444445D01*
X920586Y1444434D01*
X920562Y1444416D01*
X920541Y1444391D01*
X920524Y1444361D01*
X920511Y1444328D01*
X920503Y1444291D01*
X920500Y1444252D01*
G01X920639Y1447598D02*
X920611Y1447594D01*
X920586Y1447583D01*
X920562Y1447565D01*
X920541Y1447541D01*
X920524Y1447511D01*
X920511Y1447477D01*
X920503Y1447441D01*
X920500Y1447402D01*
G01Y1431260D02*
X920503Y1431222D01*
X920511Y1431185D01*
X920523Y1431151D01*
X920541Y1431120D01*
X920561Y1431096D01*
X920585Y1431078D01*
X920611Y1431067D01*
X920639Y1431063D01*
G01X920500Y1434409D02*
X920503Y1434371D01*
X920511Y1434334D01*
X920523Y1434300D01*
X920541Y1434270D01*
X920561Y1434246D01*
X920585Y1434228D01*
X920611Y1434217D01*
X920639Y1434213D01*
G01X920500Y1437559D02*
X920503Y1437521D01*
X920511Y1437484D01*
X920523Y1437450D01*
X920541Y1437420D01*
X920561Y1437395D01*
X920585Y1437377D01*
X920611Y1437366D01*
X920639Y1437362D01*
G01X920500Y1440709D02*
X920503Y1440670D01*
X920511Y1440633D01*
X920523Y1440600D01*
X920541Y1440569D01*
X920561Y1440545D01*
X920585Y1440527D01*
X920611Y1440516D01*
X920639Y1440512D01*
G01X920500Y1443858D02*
X920503Y1443820D01*
X920511Y1443783D01*
X920523Y1443749D01*
X920541Y1443719D01*
X920561Y1443694D01*
X920585Y1443676D01*
X920611Y1443665D01*
X920639Y1443661D01*
G01X920500Y1447008D02*
X920503Y1446970D01*
X920511Y1446933D01*
X920523Y1446899D01*
X920541Y1446869D01*
X920561Y1446844D01*
X920585Y1446826D01*
X920611Y1446815D01*
X920639Y1446811D01*
G01X920500Y1450157D02*
X920503Y1450119D01*
X920511Y1450082D01*
X920523Y1450048D01*
X920541Y1450018D01*
X920561Y1449994D01*
X920585Y1449976D01*
X920611Y1449965D01*
X920639Y1449961D01*
G01X920500Y1453307D02*
X920503Y1453269D01*
X920511Y1453232D01*
X920523Y1453198D01*
X920541Y1453168D01*
X920561Y1453143D01*
X920585Y1453125D01*
X920611Y1453114D01*
X920639Y1453110D01*
G01X920500Y1456457D02*
X920503Y1456419D01*
X920511Y1456381D01*
X920523Y1456348D01*
X920541Y1456317D01*
X920561Y1456293D01*
X920585Y1456275D01*
X920611Y1456264D01*
X920639Y1456260D01*
G01X920500Y1459606D02*
X920503Y1459568D01*
X920511Y1459531D01*
X920523Y1459497D01*
X920541Y1459467D01*
X920561Y1459443D01*
X920585Y1459424D01*
X920611Y1459413D01*
X920639Y1459409D01*
G01X920500Y1462756D02*
X920503Y1462718D01*
X920511Y1462681D01*
X920523Y1462647D01*
X920541Y1462617D01*
X920561Y1462592D01*
X920585Y1462574D01*
X920611Y1462563D01*
X920639Y1462559D01*
G01X919323Y1463150D02*
Y1462756D01*
G01Y1460000D02*
Y1459606D01*
G01Y1453701D02*
Y1453307D01*
G01Y1456850D02*
Y1456457D01*
G01Y1450551D02*
Y1450157D01*
G01Y1447402D02*
Y1447008D01*
G01Y1444252D02*
Y1443858D01*
G01Y1441102D02*
Y1440709D01*
G01Y1437953D02*
Y1437559D01*
G01Y1434803D02*
Y1434409D01*
G01Y1431654D02*
Y1431260D01*
G01X919420Y1450256D02*
Y1450650D01*
G01X919485Y1430256D02*
Y1430650D01*
G01Y1435256D02*
Y1435650D01*
G01Y1440256D02*
Y1440650D01*
G01Y1445256D02*
Y1445650D01*
G01X919626Y1454589D02*
Y1455573D01*
G01Y1457738D02*
Y1458722D01*
G01Y1464037D02*
Y1465022D01*
G01Y1460888D02*
Y1461872D01*
G01X920329Y1430256D02*
Y1430650D01*
G01Y1435256D02*
Y1435650D01*
G01Y1440256D02*
Y1440650D01*
G01Y1445256D02*
Y1445650D01*
G01Y1450256D02*
Y1450650D01*
G01X920500Y1463150D02*
Y1462756D01*
G01Y1460000D02*
Y1459606D01*
G01Y1453701D02*
Y1453307D01*
G01Y1456850D02*
Y1456457D01*
G01Y1450551D02*
Y1450157D01*
G01Y1447402D02*
Y1447008D01*
G01Y1444252D02*
Y1443858D01*
G01Y1441102D02*
Y1440709D01*
G01Y1437953D02*
Y1437559D01*
G01Y1434803D02*
Y1434409D01*
G01Y1431654D02*
Y1431260D01*
G01X920569Y1454589D02*
Y1455573D01*
G01Y1457738D02*
Y1458722D01*
G01Y1464037D02*
Y1465022D01*
G01Y1460888D02*
Y1461872D01*
G01X921013Y1431260D02*
Y1431654D01*
G01Y1437559D02*
Y1437953D01*
G01Y1434409D02*
Y1434803D01*
G01Y1440709D02*
Y1441102D01*
G01Y1447008D02*
Y1447402D01*
G01Y1443858D02*
Y1444252D01*
G01Y1450157D02*
Y1450551D01*
G01Y1453307D02*
Y1453701D01*
G01Y1456457D02*
Y1456850D01*
G01Y1459606D02*
Y1460000D01*
G01Y1462756D02*
Y1463150D01*
G01X921454Y1450650D02*
Y1450256D01*
G01Y1445650D02*
Y1445256D01*
G01Y1440650D02*
Y1440256D01*
G01Y1435650D02*
Y1435256D01*
G01Y1430650D02*
Y1430256D01*
G01X921720Y1454589D02*
Y1455573D01*
G01Y1457738D02*
Y1458722D01*
G01Y1464037D02*
Y1465022D01*
G01Y1460888D02*
Y1461872D01*
G01X923452Y1453209D02*
Y1452028D01*
G01X925935Y1431260D02*
Y1431654D01*
G01Y1437559D02*
Y1437953D01*
G01Y1434409D02*
Y1434803D01*
G01Y1440709D02*
Y1441102D01*
G01Y1447008D02*
Y1447402D01*
G01Y1443858D02*
Y1444252D01*
G01Y1450157D02*
Y1450551D01*
G01Y1453307D02*
Y1453701D01*
G01Y1456457D02*
Y1456850D01*
G01Y1459606D02*
Y1460000D01*
G01Y1462756D02*
Y1463150D01*
G01X925944Y1465022D02*
Y1464037D01*
G01Y1461872D02*
Y1460888D01*
G01Y1458722D02*
Y1457738D01*
G01Y1455573D02*
Y1454589D01*
G01X926071Y1445650D02*
Y1445256D01*
G01Y1440650D02*
Y1440256D01*
G01Y1435650D02*
Y1435256D01*
G01Y1430650D02*
Y1430256D01*
G01X926162Y1450650D02*
Y1450256D01*
G01X928740Y1452028D02*
Y1473878D01*
G01X928910Y1452231D02*
Y1446850D01*
G01X921720Y1465022D02*
X921721Y1465060D01*
X921723Y1465097D01*
X921726Y1465131D01*
X921730Y1465161D01*
X921735Y1465185D01*
X921741Y1465204D01*
X921747Y1465215D01*
X921753Y1465219D01*
G01X921720Y1461872D02*
X921721Y1461910D01*
X921723Y1461947D01*
X921726Y1461981D01*
X921730Y1462011D01*
X921735Y1462036D01*
X921741Y1462054D01*
X921747Y1462065D01*
X921753Y1462069D01*
G01X921720Y1458722D02*
X921721Y1458761D01*
X921723Y1458798D01*
X921726Y1458831D01*
X921730Y1458862D01*
X921735Y1458886D01*
X921741Y1458904D01*
X921747Y1458915D01*
X921753Y1458919D01*
G01X921720Y1455573D02*
X921721Y1455611D01*
X921723Y1455648D01*
X921726Y1455682D01*
X921730Y1455712D01*
X921735Y1455737D01*
X921741Y1455755D01*
X921747Y1455766D01*
X921753Y1455770D01*
G01X920639Y1450748D02*
X920611Y1450744D01*
X920586Y1450733D01*
X920562Y1450715D01*
X920541Y1450690D01*
X920524Y1450661D01*
X920511Y1450627D01*
X920503Y1450590D01*
X920500Y1450551D01*
G01X920639Y1453898D02*
X920611Y1453894D01*
X920586Y1453883D01*
X920562Y1453865D01*
X920541Y1453840D01*
X920524Y1453810D01*
X920511Y1453776D01*
X920503Y1453740D01*
X920500Y1453701D01*
G01X920639Y1457047D02*
X920611Y1457043D01*
X920586Y1457032D01*
X920562Y1457014D01*
X920541Y1456989D01*
X920524Y1456960D01*
X920511Y1456926D01*
X920503Y1456889D01*
X920500Y1456850D01*
G01X920639Y1460197D02*
X920611Y1460193D01*
X920586Y1460182D01*
X920562Y1460164D01*
X920541Y1460139D01*
X920524Y1460109D01*
X920511Y1460076D01*
X920503Y1460039D01*
X920500Y1460000D01*
G01X920639Y1463346D02*
X920611Y1463343D01*
X920586Y1463331D01*
X920562Y1463313D01*
X920541Y1463289D01*
X920524Y1463259D01*
X920511Y1463225D01*
X920503Y1463189D01*
X920500Y1463150D01*
G01X919485Y1430256D02*
X926071D01*
G01X919485Y1430650D02*
X926071D01*
G01X925687Y1431063D02*
X919603D01*
G01X925657Y1431240D02*
X919912D01*
G01X925935Y1431260D02*
X919323D01*
G01Y1431654D02*
X925935D01*
G01X925687Y1431850D02*
X919603D01*
G01X925687Y1434213D02*
X919603D01*
G01X925935Y1434409D02*
X919323D01*
G01X925657Y1434665D02*
X919912D01*
G01X919323Y1434803D02*
X925935D01*
G01X925687Y1435000D02*
X919603D01*
G01X919485Y1435256D02*
X926071D01*
G01X919485Y1435650D02*
X926071D01*
G01X925657Y1436240D02*
X919912D01*
G01X925687Y1437362D02*
X919603D01*
G01X925935Y1437559D02*
X919323D01*
G01Y1437953D02*
X925935D01*
G01X925687Y1438150D02*
X919603D01*
G01X925657Y1439665D02*
X919912D01*
G01X919485Y1440256D02*
X926071D01*
G01X925687Y1440512D02*
X919603D01*
G01X919485Y1440650D02*
X926071D01*
G01X925935Y1440709D02*
X919323D01*
G01Y1441102D02*
X925935D01*
G01X925657Y1441240D02*
X919912D01*
G01X925687Y1441299D02*
X919603D01*
G01X925687Y1443661D02*
X919603D01*
G01X925935Y1443858D02*
X919323D01*
G01Y1444252D02*
X925935D01*
G01X925687Y1444449D02*
X919603D01*
G01X925657Y1444665D02*
X919912D01*
G01X919485Y1445256D02*
X926071D01*
G01X919485Y1445650D02*
X926071D01*
G01X925657Y1446240D02*
X919912D01*
G01X925687Y1446811D02*
X919603D01*
G01X925935Y1447008D02*
X919323D01*
G01Y1447402D02*
X925935D01*
G01X925687Y1447598D02*
X919603D01*
G01X925757Y1449665D02*
X919844D01*
G01X925687Y1449961D02*
X919603D01*
G01X925935Y1450157D02*
X919323D01*
G01X919420Y1450256D02*
X926162D01*
G01X919323Y1450551D02*
X925935D01*
G01X919420Y1450650D02*
X926162D01*
G01X925687Y1450748D02*
X919603D01*
G01X925757Y1451240D02*
X919844D01*
G01X929921Y1452028D02*
X923452D01*
G01X925687Y1453110D02*
X919603D01*
G01X925935Y1453307D02*
X919323D01*
G01Y1453701D02*
X925935D01*
G01X925687Y1453898D02*
X919603D01*
G01X919889Y1454392D02*
X925697D01*
G01X919626Y1454589D02*
X925944D01*
G01Y1455573D02*
X919626D01*
G01X919889Y1455770D02*
X925697D01*
G01X925687Y1456260D02*
X919603D01*
G01X925935Y1456457D02*
X919323D01*
G01Y1456850D02*
X925935D01*
G01X925687Y1457047D02*
X919603D01*
G01X919889Y1457541D02*
X925697D01*
G01X919626Y1457738D02*
X925944D01*
G01Y1458722D02*
X919626D01*
G01X919889Y1458919D02*
X925697D01*
G01X925687Y1459409D02*
X919603D01*
G01X925935Y1459606D02*
X919323D01*
G01Y1460000D02*
X925935D01*
G01X925687Y1460197D02*
X919603D01*
G01X919889Y1460691D02*
X925697D01*
G01X919626Y1460888D02*
X925944D01*
G01Y1461872D02*
X919626D01*
G01X919889Y1462069D02*
X925697D01*
G01X925687Y1462559D02*
X919603D01*
G01X925935Y1462756D02*
X919323D01*
G01Y1463150D02*
X925935D01*
G01X925687Y1463346D02*
X919603D01*
G01X919889Y1463841D02*
X925697D01*
G01X919626Y1464037D02*
X925944D01*
G01Y1465022D02*
X919626D01*
G01X919889Y1465219D02*
X925697D01*
G01X921454Y1435256D02*
X921531Y1434665D01*
G01X921454Y1440256D02*
X921531Y1439665D01*
G01X921454Y1445256D02*
X921531Y1444665D01*
G01X921454Y1450256D02*
X921531Y1449665D01*
G01X920717Y1454392D02*
X920688Y1454396D01*
X920660Y1454407D01*
X920635Y1454425D01*
X920612Y1454450D01*
X920594Y1454479D01*
X920580Y1454513D01*
X920572Y1454550D01*
X920569Y1454589D01*
G01X920717Y1457541D02*
X920688Y1457545D01*
X920660Y1457556D01*
X920635Y1457574D01*
X920612Y1457599D01*
X920594Y1457629D01*
X920580Y1457663D01*
X920572Y1457699D01*
X920569Y1457738D01*
G01X920717Y1460691D02*
X920688Y1460695D01*
X920660Y1460706D01*
X920635Y1460724D01*
X920612Y1460749D01*
X920594Y1460778D01*
X920580Y1460812D01*
X920572Y1460849D01*
X920569Y1460888D01*
G01X920717Y1463841D02*
X920688Y1463844D01*
X920660Y1463856D01*
X920635Y1463874D01*
X920612Y1463898D01*
X920594Y1463928D01*
X920580Y1463962D01*
X920572Y1463998D01*
X920569Y1464037D01*
G01X925944Y1455573D02*
X925911Y1455672D01*
X925823Y1455743D01*
X925697Y1455770D01*
G01X925944Y1458722D02*
X925911Y1458822D01*
X925823Y1458893D01*
X925697Y1458919D01*
G01X925944Y1461872D02*
X925911Y1461971D01*
X925823Y1462042D01*
X925697Y1462069D01*
G01X925944Y1465022D02*
X925911Y1465121D01*
X925823Y1465192D01*
X925697Y1465219D01*
G01X925935Y1431654D02*
X925903Y1431750D01*
X925815Y1431822D01*
X925687Y1431850D01*
G01X925935Y1434803D02*
X925903Y1434900D01*
X925815Y1434972D01*
X925687Y1435000D01*
G01X925935Y1437953D02*
X925903Y1438050D01*
X925815Y1438122D01*
X925687Y1438150D01*
G01X925935Y1441102D02*
X925903Y1441199D01*
X925815Y1441271D01*
X925687Y1441299D01*
G01X925935Y1444252D02*
X925903Y1444349D01*
X925815Y1444421D01*
X925687Y1444449D01*
G01X925935Y1447402D02*
X925903Y1447498D01*
X925815Y1447570D01*
X925687Y1447598D01*
G01X925935Y1450551D02*
X925903Y1450648D01*
X925815Y1450720D01*
X925687Y1450748D01*
G01X925935Y1453701D02*
X925903Y1453798D01*
X925815Y1453870D01*
X925687Y1453898D01*
G01X925935Y1456850D02*
X925903Y1456947D01*
X925815Y1457019D01*
X925687Y1457047D01*
G01X925935Y1460000D02*
X925903Y1460097D01*
X925815Y1460169D01*
X925687Y1460197D01*
G01X925935Y1463150D02*
X925903Y1463246D01*
X925815Y1463319D01*
X925687Y1463346D01*
G01X921753Y1454392D02*
X921747Y1454396D01*
X921741Y1454407D01*
X921735Y1454425D01*
X921730Y1454450D01*
X921726Y1454479D01*
X921723Y1454513D01*
X921721Y1454550D01*
X921720Y1454589D01*
G01X921753Y1457541D02*
X921747Y1457545D01*
X921741Y1457556D01*
X921735Y1457574D01*
X921730Y1457599D01*
X921726Y1457629D01*
X921723Y1457663D01*
X921721Y1457699D01*
X921720Y1457738D01*
G01X921753Y1460691D02*
X921747Y1460695D01*
X921741Y1460706D01*
X921735Y1460724D01*
X921730Y1460749D01*
X921726Y1460778D01*
X921723Y1460812D01*
X921721Y1460849D01*
X921720Y1460888D01*
G01X921753Y1463841D02*
X921747Y1463844D01*
X921741Y1463856D01*
X921735Y1463874D01*
X921730Y1463898D01*
X921726Y1463928D01*
X921723Y1463962D01*
X921721Y1463998D01*
X921720Y1464037D01*
G01X921090Y1431063D02*
X921051Y1431089D01*
X921023Y1431161D01*
X921013Y1431260D01*
G01X921090Y1434213D02*
X921051Y1434239D01*
X921023Y1434311D01*
X921013Y1434409D01*
G01X921090Y1437362D02*
X921051Y1437389D01*
X921023Y1437461D01*
X921013Y1437559D01*
G01X921090Y1440512D02*
X921051Y1440538D01*
X921023Y1440610D01*
X921013Y1440709D01*
G01X921090Y1443661D02*
X921051Y1443688D01*
X921023Y1443760D01*
X921013Y1443858D01*
G01X921090Y1446811D02*
X921051Y1446837D01*
X921023Y1446909D01*
X921013Y1447008D01*
G01X921090Y1449961D02*
X921051Y1449987D01*
X921023Y1450059D01*
X921013Y1450157D01*
G01X921090Y1453110D02*
X921051Y1453137D01*
X921023Y1453209D01*
X921013Y1453307D01*
G01X921090Y1456260D02*
X921051Y1456286D01*
X921023Y1456358D01*
X921013Y1456457D01*
G01X921090Y1459409D02*
X921051Y1459436D01*
X921023Y1459508D01*
X921013Y1459606D01*
G01X921090Y1462559D02*
X921051Y1462585D01*
X921023Y1462657D01*
X921013Y1462756D01*
G01X927953Y1453189D02*
X929921Y1451220D01*
G01X919912Y1434665D02*
X919485Y1435256D01*
G01X919912Y1439665D02*
X919485Y1440256D01*
G01X919912Y1444665D02*
X919485Y1445256D01*
G01X919844Y1449665D02*
X919420Y1450256D01*
G01X926071Y1430650D02*
X925934Y1430847D01*
X925796Y1431044D01*
X925657Y1431240D01*
G01X926071Y1435650D02*
X925934Y1435847D01*
X925796Y1436044D01*
X925657Y1436240D01*
G01X926071Y1440650D02*
X925934Y1440847D01*
X925796Y1441044D01*
X925657Y1441240D01*
G01X926071Y1445650D02*
X925934Y1445847D01*
X925796Y1446044D01*
X925657Y1446240D01*
G01X926162Y1450650D02*
X926028Y1450847D01*
X925893Y1451044D01*
X925757Y1451240D01*
G01X920602Y1434665D02*
X920329Y1435256D01*
G01X920602Y1439665D02*
X920329Y1440256D01*
G01X920602Y1444665D02*
X920329Y1445256D01*
G01X920602Y1449665D02*
X920329Y1450256D01*
G01X925657Y1499665D02*
X925796Y1499861D01*
X925934Y1500058D01*
X926071Y1500256D01*
G01X925657Y1494665D02*
X925796Y1494861D01*
X925934Y1495058D01*
X926071Y1495256D01*
G01X927626Y1489665D02*
X927765Y1489861D01*
X927903Y1490058D01*
X928040Y1490256D01*
G01X919912Y1501240D02*
X919485Y1500650D01*
G01X919912Y1496240D02*
X919485Y1495650D01*
G01X921880Y1491240D02*
X921454Y1490650D01*
G01X919912Y1486240D02*
X919485Y1485650D01*
G01X920329Y1500650D02*
X920602Y1501240D01*
G01X920329Y1495650D02*
X920602Y1496240D01*
G01X922298Y1490650D02*
X922570Y1491240D01*
G01X920329Y1485650D02*
X920602Y1486240D01*
G01X921013Y1500945D02*
X921023Y1501043D01*
X921051Y1501115D01*
X921090Y1501142D01*
G01X921013Y1497795D02*
X921023Y1497894D01*
X921051Y1497966D01*
X921090Y1497992D01*
G01X921013Y1494646D02*
X921023Y1494744D01*
X921051Y1494816D01*
X921090Y1494843D01*
G01X921013Y1491496D02*
X921023Y1491594D01*
X921051Y1491667D01*
X921090Y1491693D01*
G01X921013Y1488346D02*
X921023Y1488445D01*
X921051Y1488517D01*
X921090Y1488543D01*
G01X921454Y1500650D02*
X921531Y1501240D01*
G01X921454Y1495650D02*
X921531Y1496240D01*
G01X921454Y1485650D02*
X921531Y1486240D01*
G01X923422Y1490650D02*
X923500Y1491240D01*
G01X925687Y1487756D02*
X925815Y1487783D01*
X925904Y1487856D01*
X925935Y1487953D01*
G01X920500D02*
X920503Y1487915D01*
X920511Y1487878D01*
X920523Y1487844D01*
X920541Y1487813D01*
X920561Y1487789D01*
X920585Y1487771D01*
X920611Y1487760D01*
X920639Y1487756D01*
G01X920500Y1491102D02*
X920503Y1491064D01*
X920511Y1491027D01*
X920523Y1490993D01*
X920541Y1490963D01*
X920561Y1490939D01*
X920585Y1490920D01*
X920611Y1490909D01*
X920639Y1490906D01*
G01X920500Y1494252D02*
X920503Y1494214D01*
X920511Y1494177D01*
X920523Y1494143D01*
X920541Y1494113D01*
X920561Y1494088D01*
X920585Y1494070D01*
X920611Y1494059D01*
X920639Y1494055D01*
G01X920500Y1497402D02*
X920503Y1497363D01*
X920511Y1497326D01*
X920523Y1497293D01*
X920541Y1497262D01*
X920561Y1497238D01*
X920585Y1497220D01*
X920611Y1497209D01*
X920639Y1497205D01*
G01X920500Y1500551D02*
X920503Y1500513D01*
X920511Y1500476D01*
X920523Y1500442D01*
X920541Y1500412D01*
X920561Y1500387D01*
X920585Y1500369D01*
X920611Y1500358D01*
X920639Y1500354D01*
G01X919323Y1500945D02*
Y1500551D01*
G01Y1497795D02*
Y1497402D01*
G01Y1494646D02*
Y1494252D01*
G01Y1491496D02*
Y1491102D01*
G01Y1488346D02*
Y1487953D01*
G01X919485Y1495256D02*
Y1495650D01*
G01Y1500256D02*
Y1500650D01*
G01X920329Y1495256D02*
Y1495650D01*
G01Y1500256D02*
Y1500650D01*
G01X920500Y1500945D02*
Y1500551D01*
G01Y1497795D02*
Y1497402D01*
G01Y1494646D02*
Y1494252D01*
G01Y1491496D02*
Y1491102D01*
G01Y1488346D02*
Y1487953D01*
G01X921013D02*
Y1488346D01*
G01Y1491102D02*
Y1491496D01*
G01Y1497402D02*
Y1497795D01*
G01Y1494252D02*
Y1494646D01*
G01Y1500551D02*
Y1500945D01*
G01X921454Y1500650D02*
Y1500256D01*
G01Y1495650D02*
Y1495256D01*
G01Y1490256D02*
Y1490650D01*
G01X922298Y1490256D02*
Y1490650D01*
G01X923422D02*
Y1490256D01*
G01X925935Y1487953D02*
Y1488346D01*
G01Y1491102D02*
Y1491496D01*
G01Y1497402D02*
Y1497795D01*
G01Y1494252D02*
Y1494646D01*
G01Y1500551D02*
Y1500945D01*
G01X926071Y1500650D02*
Y1500256D01*
G01Y1495650D02*
Y1495256D01*
G01X928040Y1490650D02*
Y1490256D01*
G01X925687Y1490906D02*
X925815Y1490933D01*
X925904Y1491006D01*
X925935Y1491102D01*
G01X925687Y1494055D02*
X925815Y1494083D01*
X925904Y1494156D01*
X925935Y1494252D01*
G01X925687Y1497205D02*
X925815Y1497232D01*
X925904Y1497305D01*
X925935Y1497402D01*
G01X925687Y1500354D02*
X925815Y1500382D01*
X925904Y1500455D01*
X925935Y1500551D01*
G01X920639Y1488543D02*
X920611Y1488539D01*
X920586Y1488528D01*
X920562Y1488510D01*
X920541Y1488485D01*
X920524Y1488456D01*
X920511Y1488422D01*
X920503Y1488385D01*
X920500Y1488346D01*
G01X920639Y1491693D02*
X920611Y1491689D01*
X920586Y1491678D01*
X920562Y1491660D01*
X920541Y1491635D01*
X920524Y1491606D01*
X920511Y1491572D01*
X920503Y1491535D01*
X920500Y1491496D01*
G01X920639Y1494843D02*
X920611Y1494839D01*
X920586Y1494828D01*
X920562Y1494809D01*
X920541Y1494785D01*
X920524Y1494755D01*
X920511Y1494721D01*
X920503Y1494685D01*
X920500Y1494646D01*
G01X920639Y1497992D02*
X920611Y1497988D01*
X920586Y1497977D01*
X920562Y1497959D01*
X920541Y1497934D01*
X920524Y1497905D01*
X920511Y1497871D01*
X920503Y1497834D01*
X920500Y1497795D01*
G01X920639Y1501142D02*
X920611Y1501138D01*
X920586Y1501127D01*
X920562Y1501109D01*
X920541Y1501084D01*
X920524Y1501054D01*
X920511Y1501020D01*
X920503Y1500984D01*
X920500Y1500945D01*
G01X925687Y1485394D02*
X919603D01*
G01X919485Y1485650D02*
X926071D01*
G01X925657Y1486240D02*
X919912D01*
G01X925687Y1487756D02*
X919603D01*
G01X925935Y1487953D02*
X919323D01*
G01Y1488346D02*
X925935D01*
G01X925687Y1488543D02*
X919603D01*
G01X927626Y1489665D02*
X921880D01*
G01X921454Y1490256D02*
X928040D01*
G01X921454Y1490650D02*
X928040D01*
G01X925687Y1490906D02*
X919603D01*
G01X925935Y1491102D02*
X919323D01*
G01X927626Y1491240D02*
X921880D01*
G01X919323Y1491496D02*
X925935D01*
G01X925687Y1491693D02*
X919603D01*
G01X925687Y1494055D02*
X919603D01*
G01X925935Y1494252D02*
X919323D01*
G01Y1494646D02*
X925935D01*
G01X925657Y1494665D02*
X919912D01*
G01X925687Y1494843D02*
X919603D01*
G01X919485Y1495256D02*
X926071D01*
G01X919485Y1495650D02*
X926071D01*
G01X925657Y1496240D02*
X919912D01*
G01X925687Y1497205D02*
X919603D01*
G01X925935Y1497402D02*
X919323D01*
G01Y1497795D02*
X925935D01*
G01X925687Y1497992D02*
X919603D01*
G01X925657Y1499665D02*
X919912D01*
G01X919485Y1500256D02*
X926071D01*
G01X925687Y1500354D02*
X919603D01*
G01X925935Y1500551D02*
X919323D01*
G01X919485Y1500650D02*
X926071D01*
G01X919323Y1500945D02*
X925935D01*
G01X925687Y1501142D02*
X919603D01*
G01X925657Y1501240D02*
X919912D01*
G01X921454Y1495256D02*
X921531Y1494665D01*
G01X921454Y1500256D02*
X921531Y1499665D01*
G01X923422Y1490256D02*
X923500Y1489665D01*
G01X921880D02*
X921454Y1490256D01*
G01X926071Y1485650D02*
X925934Y1485847D01*
X925796Y1486044D01*
X925657Y1486240D01*
G01X922570Y1489665D02*
X922298Y1490256D01*
G01X920602Y1494665D02*
X920329Y1495256D01*
G01X920602Y1499665D02*
X920329Y1500256D01*
G01X925935Y1488346D02*
X925903Y1488443D01*
X925815Y1488515D01*
X925687Y1488543D01*
G01X925935Y1491496D02*
X925903Y1491593D01*
X925815Y1491665D01*
X925687Y1491693D01*
G01X925935Y1494646D02*
X925903Y1494743D01*
X925815Y1494815D01*
X925687Y1494843D01*
G01X925935Y1497795D02*
X925903Y1497892D01*
X925815Y1497964D01*
X925687Y1497992D01*
G01X925935Y1500945D02*
X925903Y1501042D01*
X925815Y1501114D01*
X925687Y1501142D01*
G01X921090Y1487756D02*
X921051Y1487782D01*
X921023Y1487854D01*
X921013Y1487953D01*
G01X921090Y1490906D02*
X921051Y1490932D01*
X921023Y1491004D01*
X921013Y1491102D01*
G01X921090Y1494055D02*
X921051Y1494081D01*
X921023Y1494154D01*
X921013Y1494252D01*
G01X921090Y1497205D02*
X921051Y1497231D01*
X921023Y1497303D01*
X921013Y1497402D01*
G01X921090Y1500354D02*
X921051Y1500381D01*
X921023Y1500453D01*
X921013Y1500551D01*
G01X919912Y1494665D02*
X919485Y1495256D01*
G01X919912Y1499665D02*
X919485Y1500256D01*
G01X928040Y1490650D02*
X927903Y1490847D01*
X927765Y1491044D01*
X927626Y1491240D01*
G01X926071Y1495650D02*
X925934Y1495847D01*
X925796Y1496044D01*
X925657Y1496240D01*
G01X926071Y1500650D02*
X925934Y1500847D01*
X925796Y1501044D01*
X925657Y1501240D01*
G01X921090Y1466496D02*
X921051Y1466470D01*
X921023Y1466397D01*
X921013Y1466299D01*
G01X929921Y1474685D02*
X927953Y1472717D01*
G01X925757Y1474665D02*
X925893Y1474861D01*
X926028Y1475058D01*
X926162Y1475256D01*
G01X925657Y1484665D02*
X925796Y1484861D01*
X925934Y1485058D01*
X926071Y1485256D01*
G01X925657Y1479665D02*
X925796Y1479861D01*
X925934Y1480058D01*
X926071Y1480256D01*
G01X919844Y1476240D02*
X919420Y1475650D01*
G01X919912Y1481240D02*
X919485Y1480650D01*
G01X920329D02*
X920602Y1481240D01*
G01X920329Y1475650D02*
X920602Y1476240D01*
G01X920569Y1471321D02*
X920571Y1471359D01*
X920580Y1471396D01*
X920593Y1471430D01*
X920612Y1471460D01*
X920634Y1471485D01*
X920659Y1471503D01*
X920687Y1471514D01*
X920717Y1471518D01*
G01X920569Y1468171D02*
X920571Y1468209D01*
X920580Y1468246D01*
X920593Y1468280D01*
X920612Y1468311D01*
X920634Y1468335D01*
X920659Y1468353D01*
X920687Y1468364D01*
X920717Y1468368D01*
G01X921013Y1485197D02*
X921023Y1485295D01*
X921051Y1485367D01*
X921090Y1485394D01*
G01X921013Y1482047D02*
X921023Y1482146D01*
X921051Y1482218D01*
X921090Y1482244D01*
G01X921013Y1478898D02*
X921023Y1478996D01*
X921051Y1479068D01*
X921090Y1479094D01*
G01X921013Y1475748D02*
X921023Y1475846D01*
X921051Y1475919D01*
X921090Y1475945D01*
G01X921013Y1472598D02*
X921023Y1472697D01*
X921051Y1472769D01*
X921090Y1472795D01*
G01X921013Y1469449D02*
X921023Y1469547D01*
X921051Y1469619D01*
X921090Y1469646D01*
G01X921454Y1480650D02*
X921531Y1481240D01*
G01X921454Y1475650D02*
X921531Y1476240D01*
G01X925687Y1465709D02*
X925815Y1465736D01*
X925904Y1465809D01*
X925935Y1465906D01*
G01X925687Y1468858D02*
X925815Y1468886D01*
X925904Y1468959D01*
X925935Y1469055D01*
G01X925687Y1472008D02*
X925815Y1472035D01*
X925904Y1472108D01*
X925935Y1472205D01*
G01X925687Y1475157D02*
X925815Y1475185D01*
X925904Y1475258D01*
X925935Y1475354D01*
G01X925687Y1478307D02*
X925815Y1478335D01*
X925904Y1478407D01*
X925935Y1478504D01*
G01X925687Y1481457D02*
X925815Y1481484D01*
X925904Y1481557D01*
X925935Y1481654D01*
G01X925687Y1484606D02*
X925815Y1484634D01*
X925904Y1484707D01*
X925935Y1484803D01*
G01X925697Y1466990D02*
X925824Y1467018D01*
X925913Y1467090D01*
X925944Y1467187D01*
G01X925697Y1470140D02*
X925824Y1470167D01*
X925913Y1470240D01*
X925944Y1470337D01*
G01X920500Y1465906D02*
X920503Y1465867D01*
X920511Y1465830D01*
X920523Y1465796D01*
X920541Y1465766D01*
X920561Y1465742D01*
X920585Y1465724D01*
X920611Y1465713D01*
X920639Y1465709D01*
G01X920500Y1469055D02*
X920503Y1469017D01*
X920511Y1468980D01*
X920523Y1468946D01*
X920541Y1468916D01*
X920561Y1468891D01*
X920585Y1468873D01*
X920611Y1468862D01*
X920639Y1468858D01*
G01X920500Y1472205D02*
X920503Y1472167D01*
X920511Y1472130D01*
X920523Y1472096D01*
X920541Y1472065D01*
X920561Y1472041D01*
X920585Y1472023D01*
X920611Y1472012D01*
X920639Y1472008D01*
G01X920500Y1475354D02*
X920503Y1475316D01*
X920511Y1475279D01*
X920523Y1475245D01*
X920541Y1475215D01*
X920561Y1475191D01*
X920585Y1475172D01*
X920611Y1475161D01*
X920639Y1475157D01*
G01X920500Y1478504D02*
X920503Y1478466D01*
X920511Y1478429D01*
X920523Y1478395D01*
X920541Y1478365D01*
X920561Y1478340D01*
X920585Y1478322D01*
X920611Y1478311D01*
X920639Y1478307D01*
G01X920500Y1481654D02*
X920503Y1481615D01*
X920511Y1481578D01*
X920523Y1481544D01*
X920541Y1481514D01*
X920561Y1481490D01*
X920585Y1481472D01*
X920611Y1481461D01*
X920639Y1481457D01*
G01X920500Y1484803D02*
X920503Y1484765D01*
X920511Y1484728D01*
X920523Y1484694D01*
X920541Y1484664D01*
X920561Y1484639D01*
X920585Y1484621D01*
X920611Y1484610D01*
X920639Y1484606D01*
G01X919323Y1485197D02*
Y1484803D01*
G01Y1482047D02*
Y1481654D01*
G01Y1478898D02*
Y1478504D01*
G01Y1475748D02*
Y1475354D01*
G01Y1472598D02*
Y1472205D01*
G01Y1469449D02*
Y1469055D01*
G01Y1466299D02*
Y1465906D01*
G01X919420Y1475256D02*
Y1475650D01*
G01X919485Y1480256D02*
Y1480650D01*
G01Y1485256D02*
Y1485650D01*
G01X919626Y1467187D02*
Y1468171D01*
G01Y1470337D02*
Y1471321D01*
G01X920329Y1475256D02*
Y1475650D01*
G01Y1480256D02*
Y1480650D01*
G01Y1485256D02*
Y1485650D01*
G01X920500Y1485197D02*
Y1484803D01*
G01Y1482047D02*
Y1481654D01*
G01Y1478898D02*
Y1478504D01*
G01Y1475748D02*
Y1475354D01*
G01Y1472598D02*
Y1472205D01*
G01Y1469449D02*
Y1469055D01*
G01Y1466299D02*
Y1465906D01*
G01X920569Y1467187D02*
Y1468171D01*
G01Y1470337D02*
Y1471321D01*
G01X921013Y1469055D02*
Y1469449D01*
G01Y1465906D02*
Y1466299D01*
G01Y1472205D02*
Y1472598D01*
G01Y1478504D02*
Y1478898D01*
G01Y1475354D02*
Y1475748D01*
G01Y1481654D02*
Y1482047D01*
G01Y1484803D02*
Y1485197D01*
G01X921454Y1485650D02*
Y1485256D01*
G01Y1480650D02*
Y1480256D01*
G01Y1475650D02*
Y1475256D01*
G01X921720Y1467187D02*
Y1468171D01*
G01Y1470337D02*
Y1471321D01*
G01X923452Y1473878D02*
Y1472697D01*
G01X925935Y1469055D02*
Y1469449D01*
G01Y1465906D02*
Y1466299D01*
G01Y1472205D02*
Y1472598D01*
G01Y1478504D02*
Y1478898D01*
G01Y1475354D02*
Y1475748D01*
G01Y1481654D02*
Y1482047D01*
G01Y1484803D02*
Y1485197D01*
G01X925944Y1471321D02*
Y1470337D01*
G01Y1468171D02*
Y1467187D01*
G01X926071Y1485650D02*
Y1485256D01*
G01Y1480650D02*
Y1480256D01*
G01X926162Y1475650D02*
Y1475256D01*
G01X928740Y1550059D02*
Y1479154D01*
G01X928910D02*
Y1473674D01*
G01X921720Y1471321D02*
X921721Y1471359D01*
X921723Y1471396D01*
X921726Y1471430D01*
X921730Y1471460D01*
X921735Y1471485D01*
X921741Y1471503D01*
X921747Y1471514D01*
X921753Y1471518D01*
G01X921720Y1468171D02*
X921721Y1468209D01*
X921723Y1468246D01*
X921726Y1468280D01*
X921730Y1468311D01*
X921735Y1468335D01*
X921741Y1468353D01*
X921747Y1468364D01*
X921753Y1468368D01*
G01X920639Y1466496D02*
X920611Y1466492D01*
X920586Y1466481D01*
X920562Y1466463D01*
X920541Y1466438D01*
X920524Y1466409D01*
X920511Y1466375D01*
X920503Y1466338D01*
X920500Y1466299D01*
G01X920639Y1469646D02*
X920611Y1469642D01*
X920586Y1469631D01*
X920562Y1469613D01*
X920541Y1469588D01*
X920524Y1469558D01*
X920511Y1469524D01*
X920503Y1469488D01*
X920500Y1469449D01*
G01X920639Y1472795D02*
X920611Y1472791D01*
X920586Y1472780D01*
X920562Y1472762D01*
X920541Y1472737D01*
X920524Y1472708D01*
X920511Y1472674D01*
X920503Y1472637D01*
X920500Y1472598D01*
G01X920639Y1475945D02*
X920611Y1475941D01*
X920586Y1475930D01*
X920562Y1475912D01*
X920541Y1475887D01*
X920524Y1475857D01*
X920511Y1475824D01*
X920503Y1475787D01*
X920500Y1475748D01*
G01X920639Y1479094D02*
X920611Y1479091D01*
X920586Y1479080D01*
X920562Y1479061D01*
X920541Y1479037D01*
X920524Y1479007D01*
X920511Y1478973D01*
X920503Y1478937D01*
X920500Y1478898D01*
G01X920639Y1482244D02*
X920611Y1482240D01*
X920586Y1482229D01*
X920562Y1482211D01*
X920541Y1482186D01*
X920524Y1482157D01*
X920511Y1482123D01*
X920503Y1482086D01*
X920500Y1482047D01*
G01X920639Y1485394D02*
X920611Y1485390D01*
X920586Y1485379D01*
X920562Y1485361D01*
X920541Y1485336D01*
X920524Y1485306D01*
X920511Y1485272D01*
X920503Y1485236D01*
X920500Y1485197D01*
G01X925687Y1465709D02*
X919603D01*
G01X925935Y1465906D02*
X919323D01*
G01Y1466299D02*
X925935D01*
G01X925687Y1466496D02*
X919603D01*
G01X919889Y1466990D02*
X925697D01*
G01X919626Y1467187D02*
X925944D01*
G01Y1468171D02*
X919626D01*
G01X919889Y1468368D02*
X925697D01*
G01X925687Y1468858D02*
X919603D01*
G01X925935Y1469055D02*
X919323D01*
G01Y1469449D02*
X925935D01*
G01X925687Y1469646D02*
X919603D01*
G01X919889Y1470140D02*
X925697D01*
G01X919626Y1470337D02*
X925944D01*
G01Y1471321D02*
X919626D01*
G01X919889Y1471518D02*
X925697D01*
G01X925687Y1472008D02*
X919603D01*
G01X925935Y1472205D02*
X919323D01*
G01Y1472598D02*
X925935D01*
G01X925687Y1472795D02*
X919603D01*
G01X923452Y1473878D02*
X929921D01*
G01X925757Y1474665D02*
X919844D01*
G01X925687Y1475157D02*
X919603D01*
G01X919420Y1475256D02*
X926162D01*
G01X925935Y1475354D02*
X919323D01*
G01X919420Y1475650D02*
X926162D01*
G01X919323Y1475748D02*
X925935D01*
G01X925687Y1475945D02*
X919603D01*
G01X925757Y1476240D02*
X919844D01*
G01X925687Y1478307D02*
X919603D01*
G01X925935Y1478504D02*
X919323D01*
G01Y1478898D02*
X925935D01*
G01X925687Y1479094D02*
X919603D01*
G01X925657Y1479665D02*
X919912D01*
G01X919485Y1480256D02*
X926071D01*
G01X919485Y1480650D02*
X926071D01*
G01X925657Y1481240D02*
X919912D01*
G01X925687Y1481457D02*
X919603D01*
G01X925935Y1481654D02*
X919323D01*
G01Y1482047D02*
X925935D01*
G01X925687Y1482244D02*
X919603D01*
G01X925687Y1484606D02*
X919603D01*
G01X925657Y1484665D02*
X919912D01*
G01X925935Y1484803D02*
X919323D01*
G01Y1485197D02*
X925935D01*
G01X919485Y1485256D02*
X926071D01*
G01X920717Y1466990D02*
X920688Y1466994D01*
X920660Y1467005D01*
X920635Y1467023D01*
X920612Y1467048D01*
X920594Y1467078D01*
X920580Y1467111D01*
X920572Y1467148D01*
X920569Y1467187D01*
G01X920717Y1470140D02*
X920688Y1470144D01*
X920660Y1470155D01*
X920635Y1470173D01*
X920612Y1470198D01*
X920594Y1470227D01*
X920580Y1470261D01*
X920572Y1470298D01*
X920569Y1470337D01*
G01X925944Y1468171D02*
X925911Y1468270D01*
X925823Y1468341D01*
X925697Y1468368D01*
G01X925944Y1471321D02*
X925911Y1471420D01*
X925823Y1471491D01*
X925697Y1471518D01*
G01X925935Y1466299D02*
X925903Y1466396D01*
X925815Y1466468D01*
X925687Y1466496D01*
G01X925935Y1469449D02*
X925903Y1469546D01*
X925815Y1469618D01*
X925687Y1469646D01*
G01X925935Y1472598D02*
X925903Y1472695D01*
X925815Y1472767D01*
X925687Y1472795D01*
G01X925935Y1475748D02*
X925903Y1475845D01*
X925815Y1475917D01*
X925687Y1475945D01*
G01X925935Y1478898D02*
X925903Y1478994D01*
X925815Y1479067D01*
X925687Y1479094D01*
G01X925935Y1482047D02*
X925903Y1482144D01*
X925815Y1482216D01*
X925687Y1482244D01*
G01X921454Y1475256D02*
X921531Y1474665D01*
G01X921454Y1480256D02*
X921531Y1479665D01*
G01X921454Y1485256D02*
X921531Y1484665D01*
G01X921753Y1466990D02*
X921747Y1466994D01*
X921741Y1467005D01*
X921735Y1467023D01*
X921730Y1467048D01*
X921726Y1467078D01*
X921723Y1467111D01*
X921721Y1467148D01*
X921720Y1467187D01*
G01X921753Y1470140D02*
X921747Y1470144D01*
X921741Y1470155D01*
X921735Y1470173D01*
X921730Y1470198D01*
X921726Y1470227D01*
X921723Y1470261D01*
X921721Y1470298D01*
X921720Y1470337D01*
G01X921090Y1465709D02*
X921051Y1465735D01*
X921023Y1465807D01*
X921013Y1465906D01*
G01X921090Y1468858D02*
X921051Y1468885D01*
X921023Y1468957D01*
X921013Y1469055D01*
G01X919912Y1479665D02*
X919485Y1480256D01*
G01X919912Y1484665D02*
X919485Y1485256D01*
G01X919844Y1474665D02*
X919420Y1475256D01*
G01X926071Y1480650D02*
X925934Y1480847D01*
X925796Y1481044D01*
X925657Y1481240D01*
G01X926162Y1475650D02*
X926028Y1475847D01*
X925893Y1476044D01*
X925757Y1476240D01*
G01X920602Y1474665D02*
X920329Y1475256D01*
G01X920602Y1479665D02*
X920329Y1480256D01*
G01X920602Y1484665D02*
X920329Y1485256D01*
G01X925935Y1485197D02*
X925903Y1485294D01*
X925815Y1485366D01*
X925687Y1485394D01*
G01X921090Y1472008D02*
X921051Y1472034D01*
X921023Y1472106D01*
X921013Y1472205D01*
G01X921090Y1475157D02*
X921051Y1475184D01*
X921023Y1475256D01*
X921013Y1475354D01*
G01X921090Y1478307D02*
X921051Y1478333D01*
X921023Y1478406D01*
X921013Y1478504D01*
G01X921090Y1481457D02*
X921051Y1481483D01*
X921023Y1481555D01*
X921013Y1481654D01*
G01X921090Y1484606D02*
X921051Y1484633D01*
X921023Y1484705D01*
X921013Y1484803D01*
G01X933204Y1554193D02*
X936614Y1556161D01*
G01X927953Y1549272D02*
X929921Y1551240D01*
G01X919912Y1546240D02*
X919485Y1545650D01*
G01X920329D02*
X920602Y1546240D01*
G01X931947Y1561807D02*
X931984Y1562131D01*
X931978Y1562372D01*
X931921Y1562508D01*
G01X921454Y1545650D02*
X921531Y1546240D01*
G01X931948Y1561809D02*
X931894Y1561432D01*
G01X931890Y1554193D02*
Y1561358D01*
G01X936614Y1556161D02*
Y1557894D01*
G01X919485Y1545650D02*
X926071D01*
G01X925657Y1546240D02*
X919912D01*
G01X933204Y1554193D02*
X929921D01*
G01X931921Y1562508D02*
X931979Y1562368D01*
X931984Y1562128D01*
G01X931894Y1561432D02*
X936614Y1556790D01*
G01Y1557894D02*
X931890Y1562539D01*
G01X927953Y1554193D02*
X929921Y1552224D01*
G01X926071Y1545650D02*
X925934Y1545847D01*
X925796Y1546044D01*
X925657Y1546240D01*
G01Y1544665D02*
X925796Y1544861D01*
X925934Y1545058D01*
X926071Y1545256D01*
G01X925657Y1539665D02*
X925796Y1539861D01*
X925934Y1540058D01*
X926071Y1540256D01*
G01X925657Y1534665D02*
X925796Y1534861D01*
X925934Y1535058D01*
X926071Y1535256D01*
G01X927626Y1529665D02*
X927765Y1529861D01*
X927903Y1530058D01*
X928040Y1530256D01*
G01X925657Y1524665D02*
X925796Y1524861D01*
X925934Y1525058D01*
X926071Y1525256D01*
G01X925657Y1519665D02*
X925796Y1519861D01*
X925934Y1520058D01*
X926071Y1520256D01*
G01X925657Y1514665D02*
X925796Y1514861D01*
X925934Y1515058D01*
X926071Y1515256D01*
G01X925657Y1509665D02*
X925796Y1509861D01*
X925934Y1510058D01*
X926071Y1510256D01*
G01X925657Y1504665D02*
X925796Y1504861D01*
X925934Y1505058D01*
X926071Y1505256D01*
G01X919912Y1541240D02*
X919485Y1540650D01*
G01X919912Y1536240D02*
X919485Y1535650D01*
G01X921880Y1531240D02*
X921454Y1530650D01*
G01X919912Y1526240D02*
X919485Y1525650D01*
G01X919912Y1521240D02*
X919485Y1520650D01*
G01X919912Y1516240D02*
X919485Y1515650D01*
G01X919912Y1511240D02*
X919485Y1510650D01*
G01X919912Y1506240D02*
X919485Y1505650D01*
G01X920329Y1540650D02*
X920602Y1541240D01*
G01X920329Y1535650D02*
X920602Y1536240D01*
G01X922298Y1530650D02*
X922570Y1531240D01*
G01X920329Y1525650D02*
X920602Y1526240D01*
G01X920329Y1520650D02*
X920602Y1521240D01*
G01X920329Y1515650D02*
X920602Y1516240D01*
G01X920329Y1510650D02*
X920602Y1511240D01*
G01X920329Y1505650D02*
X920602Y1506240D01*
G01X925935Y1532047D02*
X925901Y1531948D01*
X925813Y1531877D01*
X925687Y1531850D01*
G01X925935Y1503701D02*
X925901Y1503602D01*
X925813Y1503531D01*
X925687Y1503504D01*
G01X921013Y1545039D02*
X921023Y1545138D01*
X921051Y1545210D01*
X921090Y1545236D01*
G01X921013Y1541890D02*
X921023Y1541988D01*
X921051Y1542060D01*
X921090Y1542087D01*
G01X921013Y1538740D02*
X921023Y1538839D01*
X921051Y1538911D01*
X921090Y1538937D01*
G01X921013Y1535591D02*
X921023Y1535689D01*
X921051Y1535761D01*
X921090Y1535787D01*
G01X921013Y1532441D02*
X921023Y1532539D01*
X921051Y1532611D01*
X921090Y1532638D01*
G01X921013Y1529291D02*
X921023Y1529390D01*
X921051Y1529462D01*
X921090Y1529488D01*
G01X921013Y1526142D02*
X921023Y1526240D01*
X921051Y1526312D01*
X921090Y1526339D01*
G01X921013Y1522992D02*
X921023Y1523091D01*
X921051Y1523163D01*
X921090Y1523189D01*
G01X921013Y1519843D02*
X921023Y1519941D01*
X921051Y1520013D01*
X921090Y1520039D01*
G01X921013Y1516693D02*
X921023Y1516791D01*
X921051Y1516863D01*
X921090Y1516890D01*
G01X921013Y1513543D02*
X921023Y1513642D01*
X921051Y1513714D01*
X921090Y1513740D01*
G01X921013Y1510394D02*
X921023Y1510492D01*
X921051Y1510564D01*
X921090Y1510591D01*
G01X921013Y1507244D02*
X921023Y1507343D01*
X921051Y1507415D01*
X921090Y1507441D01*
G01X921013Y1504094D02*
X921023Y1504193D01*
X921051Y1504265D01*
X921090Y1504291D01*
G01X921531Y1541240D02*
X921454Y1540650D01*
G01Y1535650D02*
X921531Y1536240D01*
G01X921454Y1525650D02*
X921531Y1526240D01*
G01X921454Y1520650D02*
X921531Y1521240D01*
G01X923422Y1530650D02*
X923500Y1531240D01*
G01X921454Y1515650D02*
X921531Y1516240D01*
G01X921454Y1510650D02*
X921531Y1511240D01*
G01X921454Y1505650D02*
X921531Y1506240D01*
G01X920500Y1503701D02*
X920503Y1503663D01*
X920511Y1503626D01*
X920523Y1503592D01*
X920541Y1503561D01*
X920561Y1503537D01*
X920585Y1503519D01*
X920611Y1503508D01*
X920639Y1503504D01*
G01X920500Y1506850D02*
X920503Y1506812D01*
X920511Y1506775D01*
X920523Y1506741D01*
X920541Y1506711D01*
X920561Y1506687D01*
X920585Y1506669D01*
X920611Y1506657D01*
X920639Y1506654D01*
G01X920500Y1510000D02*
X920503Y1509962D01*
X920511Y1509925D01*
X920523Y1509891D01*
X920541Y1509861D01*
X920561Y1509836D01*
X920585Y1509818D01*
X920611Y1509807D01*
X920639Y1509803D01*
G01X920500Y1513150D02*
X920503Y1513111D01*
X920511Y1513074D01*
X920523Y1513041D01*
X920541Y1513010D01*
X920561Y1512986D01*
X920585Y1512968D01*
X920611Y1512957D01*
X920639Y1512953D01*
G01X920500Y1516299D02*
X920503Y1516261D01*
X920511Y1516224D01*
X920523Y1516190D01*
X920541Y1516160D01*
X920561Y1516135D01*
X920585Y1516117D01*
X920611Y1516106D01*
X920639Y1516102D01*
G01X920500Y1519449D02*
X920503Y1519411D01*
X920511Y1519374D01*
X920523Y1519340D01*
X920541Y1519309D01*
X920561Y1519285D01*
X920585Y1519267D01*
X920611Y1519256D01*
X920639Y1519252D01*
G01X920500Y1522598D02*
X920503Y1522560D01*
X920511Y1522523D01*
X920523Y1522489D01*
X920541Y1522459D01*
X920561Y1522435D01*
X920585Y1522417D01*
X920611Y1522406D01*
X920639Y1522402D01*
G01X920500Y1525748D02*
X920503Y1525710D01*
X920511Y1525673D01*
X920523Y1525639D01*
X920541Y1525609D01*
X920561Y1525584D01*
X920585Y1525566D01*
X920611Y1525555D01*
X920639Y1525551D01*
G01X920500Y1528898D02*
X920503Y1528859D01*
X920511Y1528822D01*
X920523Y1528789D01*
X920541Y1528758D01*
X920561Y1528734D01*
X920585Y1528716D01*
X920611Y1528705D01*
X920639Y1528701D01*
G01X920500Y1532047D02*
X920503Y1532009D01*
X920511Y1531972D01*
X920523Y1531938D01*
X920541Y1531908D01*
X920561Y1531883D01*
X920585Y1531865D01*
X920611Y1531854D01*
X920639Y1531850D01*
G01X920500Y1535197D02*
X920503Y1535159D01*
X920511Y1535122D01*
X920523Y1535088D01*
X920541Y1535057D01*
X920561Y1535033D01*
X920585Y1535015D01*
X920611Y1535004D01*
X920639Y1535000D01*
G01X920500Y1538346D02*
X920503Y1538308D01*
X920511Y1538271D01*
X920523Y1538237D01*
X920541Y1538207D01*
X920561Y1538183D01*
X920585Y1538165D01*
X920611Y1538154D01*
X920639Y1538150D01*
G01X920500Y1541496D02*
X920503Y1541458D01*
X920511Y1541421D01*
X920523Y1541387D01*
X920541Y1541357D01*
X920561Y1541332D01*
X920585Y1541314D01*
X920611Y1541303D01*
X920639Y1541299D01*
G01X920500Y1544646D02*
X920503Y1544607D01*
X920511Y1544570D01*
X920523Y1544537D01*
X920541Y1544506D01*
X920561Y1544482D01*
X920585Y1544464D01*
X920611Y1544453D01*
X920639Y1544449D01*
G01X919323Y1545039D02*
Y1544646D01*
G01Y1541890D02*
Y1541496D01*
G01Y1538740D02*
Y1538346D01*
G01Y1532441D02*
Y1532047D01*
G01Y1535591D02*
Y1535197D01*
G01Y1529291D02*
Y1528898D01*
G01Y1522992D02*
Y1522598D01*
G01Y1526142D02*
Y1525748D01*
G01Y1519843D02*
Y1519449D01*
G01Y1513543D02*
Y1513150D01*
G01Y1516693D02*
Y1516299D01*
G01Y1510394D02*
Y1510000D01*
G01Y1507244D02*
Y1506850D01*
G01Y1504094D02*
Y1503701D01*
G01X919485Y1505256D02*
Y1505650D01*
G01Y1510256D02*
Y1510650D01*
G01Y1515256D02*
Y1515650D01*
G01Y1520256D02*
Y1520650D01*
G01Y1525256D02*
Y1525650D01*
G01Y1535256D02*
Y1535650D01*
G01Y1540256D02*
Y1540650D01*
G01Y1545256D02*
Y1545650D01*
G01X920329Y1505256D02*
Y1505650D01*
G01Y1510256D02*
Y1510650D01*
G01Y1515256D02*
Y1515650D01*
G01Y1520256D02*
Y1520650D01*
G01Y1525256D02*
Y1525650D01*
G01Y1535256D02*
Y1535650D01*
G01Y1540256D02*
Y1540650D01*
G01Y1545256D02*
Y1545650D01*
G01X920500Y1545039D02*
Y1544646D01*
G01Y1541890D02*
Y1541496D01*
G01Y1538740D02*
Y1538346D01*
G01Y1532441D02*
Y1532047D01*
G01Y1535591D02*
Y1535197D01*
G01Y1529291D02*
Y1528898D01*
G01Y1522992D02*
Y1522598D01*
G01Y1526142D02*
Y1525748D01*
G01Y1519843D02*
Y1519449D01*
G01Y1513543D02*
Y1513150D01*
G01Y1516693D02*
Y1516299D01*
G01Y1510394D02*
Y1510000D01*
G01Y1507244D02*
Y1506850D01*
G01Y1504094D02*
Y1503701D01*
G01X921013Y1506850D02*
Y1507244D01*
G01Y1503701D02*
Y1504094D01*
G01Y1510000D02*
Y1510394D01*
G01Y1513150D02*
Y1513543D01*
G01Y1516299D02*
Y1516693D01*
G01Y1519449D02*
Y1519843D01*
G01Y1522598D02*
Y1522992D01*
G01Y1525748D02*
Y1526142D01*
G01Y1528898D02*
Y1529291D01*
G01Y1532047D02*
Y1532441D01*
G01Y1535197D02*
Y1535591D01*
G01Y1538346D02*
Y1538740D01*
G01Y1544646D02*
Y1545039D01*
G01Y1541496D02*
Y1541890D01*
G01X921454Y1545650D02*
Y1545256D01*
G01Y1535650D02*
Y1535256D01*
G01Y1525650D02*
Y1525256D01*
G01Y1520650D02*
Y1520256D01*
G01Y1515650D02*
Y1515256D01*
G01Y1510650D02*
Y1510256D01*
G01Y1505650D02*
Y1505256D01*
G01Y1540256D02*
Y1540650D01*
G01Y1530256D02*
Y1530650D01*
G01X922298Y1530256D02*
Y1530650D01*
G01X923422D02*
Y1530256D01*
G01X925935Y1506850D02*
Y1507244D01*
G01Y1503701D02*
Y1504094D01*
G01Y1510000D02*
Y1510394D01*
G01Y1513150D02*
Y1513543D01*
G01Y1516299D02*
Y1516693D01*
G01Y1519449D02*
Y1519843D01*
G01Y1522598D02*
Y1522992D01*
G01Y1525748D02*
Y1526142D01*
G01Y1528898D02*
Y1529291D01*
G01Y1532047D02*
Y1532441D01*
G01Y1535197D02*
Y1535591D01*
G01Y1538346D02*
Y1538740D01*
G01Y1544646D02*
Y1545039D01*
G01Y1541496D02*
Y1541890D01*
G01X926071Y1545650D02*
Y1545256D01*
G01Y1540650D02*
Y1540256D01*
G01Y1535650D02*
Y1535256D01*
G01Y1525650D02*
Y1525256D01*
G01Y1520650D02*
Y1520256D01*
G01Y1515650D02*
Y1515256D01*
G01Y1510650D02*
Y1510256D01*
G01Y1505650D02*
Y1505256D01*
G01X928040Y1530650D02*
Y1530256D01*
G01X925687Y1506654D02*
X925815Y1506681D01*
X925904Y1506754D01*
X925935Y1506850D01*
G01X925687Y1509803D02*
X925815Y1509831D01*
X925904Y1509904D01*
X925935Y1510000D01*
G01X925687Y1512953D02*
X925815Y1512980D01*
X925904Y1513053D01*
X925935Y1513150D01*
G01X925687Y1516102D02*
X925815Y1516130D01*
X925904Y1516203D01*
X925935Y1516299D01*
G01X925687Y1519252D02*
X925815Y1519280D01*
X925904Y1519352D01*
X925935Y1519449D01*
G01X925687Y1522402D02*
X925815Y1522429D01*
X925904Y1522502D01*
X925935Y1522598D01*
G01X925687Y1525551D02*
X925815Y1525579D01*
X925904Y1525652D01*
X925935Y1525748D01*
G01X925687Y1528701D02*
X925815Y1528728D01*
X925904Y1528801D01*
X925935Y1528898D01*
G01X925687Y1535000D02*
X925815Y1535028D01*
X925904Y1535100D01*
X925935Y1535197D01*
G01X925687Y1538150D02*
X925815Y1538177D01*
X925904Y1538250D01*
X925935Y1538346D01*
G01X925687Y1541299D02*
X925815Y1541327D01*
X925904Y1541400D01*
X925935Y1541496D01*
G01X925687Y1544449D02*
X925815Y1544476D01*
X925904Y1544549D01*
X925935Y1544646D01*
G01X920639Y1504291D02*
X920611Y1504287D01*
X920586Y1504276D01*
X920562Y1504258D01*
X920541Y1504233D01*
X920524Y1504204D01*
X920511Y1504170D01*
X920503Y1504133D01*
X920500Y1504094D01*
G01X920639Y1507441D02*
X920611Y1507437D01*
X920586Y1507426D01*
X920562Y1507408D01*
X920541Y1507383D01*
X920524Y1507354D01*
X920511Y1507320D01*
X920503Y1507283D01*
X920500Y1507244D01*
G01X920639Y1510591D02*
X920611Y1510587D01*
X920586Y1510576D01*
X920562Y1510557D01*
X920541Y1510533D01*
X920524Y1510503D01*
X920511Y1510469D01*
X920503Y1510433D01*
X920500Y1510394D01*
G01X920639Y1513740D02*
X920611Y1513736D01*
X920586Y1513725D01*
X920562Y1513707D01*
X920541Y1513682D01*
X920524Y1513653D01*
X920511Y1513619D01*
X920503Y1513582D01*
X920500Y1513543D01*
G01X920639Y1516890D02*
X920611Y1516886D01*
X920586Y1516875D01*
X920562Y1516857D01*
X920541Y1516832D01*
X920524Y1516802D01*
X920511Y1516769D01*
X920503Y1516732D01*
X920500Y1516693D01*
G01X920639Y1520039D02*
X920611Y1520035D01*
X920586Y1520024D01*
X920562Y1520006D01*
X920541Y1519981D01*
X920524Y1519952D01*
X920511Y1519918D01*
X920503Y1519881D01*
X920500Y1519843D01*
G01X920639Y1523189D02*
X920611Y1523185D01*
X920586Y1523174D01*
X920562Y1523156D01*
X920541Y1523131D01*
X920524Y1523102D01*
X920511Y1523068D01*
X920503Y1523031D01*
X920500Y1522992D01*
G01X920639Y1526339D02*
X920611Y1526335D01*
X920586Y1526324D01*
X920562Y1526306D01*
X920541Y1526281D01*
X920524Y1526251D01*
X920511Y1526217D01*
X920503Y1526181D01*
X920500Y1526142D01*
G01X920639Y1529488D02*
X920611Y1529484D01*
X920586Y1529473D01*
X920562Y1529455D01*
X920541Y1529430D01*
X920524Y1529401D01*
X920511Y1529367D01*
X920503Y1529330D01*
X920500Y1529291D01*
G01X920639Y1532638D02*
X920611Y1532634D01*
X920586Y1532623D01*
X920562Y1532605D01*
X920541Y1532580D01*
X920524Y1532550D01*
X920511Y1532517D01*
X920503Y1532480D01*
X920500Y1532441D01*
G01X920639Y1535787D02*
X920611Y1535783D01*
X920586Y1535772D01*
X920562Y1535754D01*
X920541Y1535730D01*
X920524Y1535700D01*
X920511Y1535666D01*
X920503Y1535630D01*
X920500Y1535591D01*
G01X920639Y1538937D02*
X920611Y1538933D01*
X920586Y1538922D01*
X920562Y1538904D01*
X920541Y1538879D01*
X920524Y1538850D01*
X920511Y1538816D01*
X920503Y1538779D01*
X920500Y1538740D01*
G01X920639Y1542087D02*
X920611Y1542083D01*
X920586Y1542072D01*
X920562Y1542054D01*
X920541Y1542029D01*
X920524Y1541999D01*
X920511Y1541965D01*
X920503Y1541929D01*
X920500Y1541890D01*
G01X920639Y1545236D02*
X920611Y1545232D01*
X920586Y1545221D01*
X920562Y1545203D01*
X920541Y1545178D01*
X920524Y1545149D01*
X920511Y1545115D01*
X920503Y1545078D01*
X920500Y1545039D01*
G01X925687Y1503504D02*
X919603D01*
G01X925935Y1503701D02*
X919323D01*
G01Y1504094D02*
X925935D01*
G01X925687Y1504291D02*
X919603D01*
G01X925657Y1504665D02*
X919912D01*
G01X919485Y1505256D02*
X926071D01*
G01X919485Y1505650D02*
X926071D01*
G01X925657Y1506240D02*
X919912D01*
G01X925687Y1506654D02*
X919603D01*
G01X925935Y1506850D02*
X919323D01*
G01Y1507244D02*
X925935D01*
G01X925687Y1507441D02*
X919603D01*
G01X925657Y1509665D02*
X919912D01*
G01X925687Y1509803D02*
X919603D01*
G01X925935Y1510000D02*
X919323D01*
G01X919485Y1510256D02*
X926071D01*
G01X919323Y1510394D02*
X925935D01*
G01X925687Y1510591D02*
X919603D01*
G01X919485Y1510650D02*
X926071D01*
G01X925657Y1511240D02*
X919912D01*
G01X925687Y1512953D02*
X919603D01*
G01X925935Y1513150D02*
X919323D01*
G01Y1513543D02*
X925935D01*
G01X925687Y1513740D02*
X919603D01*
G01X925657Y1514665D02*
X919912D01*
G01X919485Y1515256D02*
X926071D01*
G01X919485Y1515650D02*
X926071D01*
G01X925687Y1516102D02*
X919603D01*
G01X925657Y1516240D02*
X919912D01*
G01X925935Y1516299D02*
X919323D01*
G01Y1516693D02*
X925935D01*
G01X925687Y1516890D02*
X919603D01*
G01X925687Y1519252D02*
X919603D01*
G01X925935Y1519449D02*
X919323D01*
G01X925657Y1519665D02*
X919912D01*
G01X919323Y1519843D02*
X925935D01*
G01X925687Y1520039D02*
X919603D01*
G01X919485Y1520256D02*
X926071D01*
G01X919485Y1520650D02*
X926071D01*
G01X925657Y1521240D02*
X919912D01*
G01X925687Y1522402D02*
X919603D01*
G01X925935Y1522598D02*
X919323D01*
G01Y1522992D02*
X925935D01*
G01X925687Y1523189D02*
X919603D01*
G01X925657Y1524665D02*
X919912D01*
G01X919485Y1525256D02*
X926071D01*
G01X925687Y1525551D02*
X919603D01*
G01X919485Y1525650D02*
X926071D01*
G01X925935Y1525748D02*
X919323D01*
G01Y1526142D02*
X925935D01*
G01X925657Y1526240D02*
X919912D01*
G01X925687Y1526339D02*
X919603D01*
G01X925687Y1528701D02*
X919603D01*
G01X925935Y1528898D02*
X919323D01*
G01Y1529291D02*
X925935D01*
G01X925687Y1529488D02*
X919603D01*
G01X927626Y1529665D02*
X921880D01*
G01X921454Y1530256D02*
X928040D01*
G01X921454Y1530650D02*
X928040D01*
G01X927626Y1531240D02*
X921880D01*
G01X925687Y1531850D02*
X919603D01*
G01X925935Y1532047D02*
X919323D01*
G01Y1532441D02*
X925935D01*
G01X925687Y1532638D02*
X919603D01*
G01X925657Y1534665D02*
X919912D01*
G01X925687Y1535000D02*
X919603D01*
G01X925935Y1535197D02*
X919323D01*
G01X919485Y1535256D02*
X926071D01*
G01X919323Y1535591D02*
X925935D01*
G01X919485Y1535650D02*
X926071D01*
G01X925687Y1535787D02*
X919603D01*
G01X925657Y1536240D02*
X919912D01*
G01X925687Y1538150D02*
X919603D01*
G01X925935Y1538346D02*
X919323D01*
G01Y1538740D02*
X925935D01*
G01X925687Y1538937D02*
X919603D01*
G01X925657Y1539665D02*
X919912D01*
G01X919485Y1540256D02*
X926071D01*
G01X919485Y1540650D02*
X926071D01*
G01X925657Y1541240D02*
X919912D01*
G01X925687Y1541299D02*
X919603D01*
G01X925935Y1541496D02*
X919323D01*
G01Y1541890D02*
X925935D01*
G01X925687Y1542087D02*
X919603D01*
G01X921454Y1505256D02*
X921531Y1504665D01*
G01X921454Y1510256D02*
X921531Y1509665D01*
G01X921454Y1515256D02*
X921531Y1514665D01*
G01X921454Y1520256D02*
X921531Y1519665D01*
G01X921454Y1525256D02*
X921531Y1524665D01*
G01X921454Y1535256D02*
X921531Y1534665D01*
G01Y1539665D02*
X921454Y1540256D01*
G01X923422Y1530256D02*
X923500Y1529665D01*
G01X921454Y1545256D02*
X921531Y1544665D01*
G01X925687Y1544449D02*
X919603D01*
G01X925935Y1544646D02*
X919323D01*
G01X925657Y1544665D02*
X919912D01*
G01X919323Y1545039D02*
X925935D01*
G01X925687Y1545236D02*
X919603D01*
G01X919485Y1545256D02*
X926071D01*
G01X925687Y1504291D02*
X925814Y1504264D01*
X925903Y1504191D01*
X925935Y1504094D01*
G01X925687Y1532638D02*
X925814Y1532610D01*
X925903Y1532537D01*
X925935Y1532441D01*
G01X920602Y1504665D02*
X920329Y1505256D01*
G01X920602Y1509665D02*
X920329Y1510256D01*
G01X920602Y1514665D02*
X920329Y1515256D01*
G01X920602Y1519665D02*
X920329Y1520256D01*
G01X920602Y1524665D02*
X920329Y1525256D01*
G01X922570Y1529665D02*
X922298Y1530256D01*
G01X920602Y1534665D02*
X920329Y1535256D01*
G01X920602Y1539665D02*
X920329Y1540256D01*
G01X920602Y1544665D02*
X920329Y1545256D01*
G01X925935Y1507244D02*
X925903Y1507341D01*
X925815Y1507413D01*
X925687Y1507441D01*
G01X925935Y1510394D02*
X925903Y1510491D01*
X925815Y1510563D01*
X925687Y1510591D01*
G01X925935Y1513543D02*
X925903Y1513640D01*
X925815Y1513712D01*
X925687Y1513740D01*
G01X925935Y1516693D02*
X925903Y1516790D01*
X925815Y1516862D01*
X925687Y1516890D01*
G01X925935Y1519843D02*
X925903Y1519939D01*
X925815Y1520011D01*
X925687Y1520039D01*
G01X925935Y1522992D02*
X925903Y1523089D01*
X925815Y1523161D01*
X925687Y1523189D01*
G01X925935Y1526142D02*
X925903Y1526239D01*
X925815Y1526311D01*
X925687Y1526339D01*
G01X925935Y1529291D02*
X925903Y1529388D01*
X925815Y1529460D01*
X925687Y1529488D01*
G01X925935Y1535591D02*
X925903Y1535687D01*
X925815Y1535759D01*
X925687Y1535787D01*
G01X925935Y1538740D02*
X925903Y1538837D01*
X925815Y1538909D01*
X925687Y1538937D01*
G01X925935Y1541890D02*
X925903Y1541987D01*
X925815Y1542059D01*
X925687Y1542087D01*
G01X925935Y1545039D02*
X925903Y1545136D01*
X925815Y1545208D01*
X925687Y1545236D01*
G01X921090Y1503504D02*
X921051Y1503530D01*
X921023Y1503602D01*
X921013Y1503701D01*
G01X921090Y1506654D02*
X921051Y1506680D01*
X921023Y1506752D01*
X921013Y1506850D01*
G01X921090Y1509803D02*
X921051Y1509830D01*
X921023Y1509902D01*
X921013Y1510000D01*
G01X921090Y1512953D02*
X921051Y1512979D01*
X921023Y1513051D01*
X921013Y1513150D01*
G01X921090Y1516102D02*
X921051Y1516129D01*
X921023Y1516201D01*
X921013Y1516299D01*
G01X921090Y1519252D02*
X921051Y1519278D01*
X921023Y1519350D01*
X921013Y1519449D01*
G01X921090Y1522402D02*
X921051Y1522428D01*
X921023Y1522500D01*
X921013Y1522598D01*
G01X921090Y1525551D02*
X921051Y1525578D01*
X921023Y1525650D01*
X921013Y1525748D01*
G01X921090Y1528701D02*
X921051Y1528727D01*
X921023Y1528799D01*
X921013Y1528898D01*
G01X921090Y1531850D02*
X921051Y1531877D01*
X921023Y1531949D01*
X921013Y1532047D01*
G01X921090Y1535000D02*
X921051Y1535026D01*
X921023Y1535098D01*
X921013Y1535197D01*
G01X921090Y1538150D02*
X921051Y1538176D01*
X921023Y1538248D01*
X921013Y1538346D01*
G01X921090Y1541299D02*
X921051Y1541326D01*
X921023Y1541398D01*
X921013Y1541496D01*
G01X921090Y1544449D02*
X921051Y1544475D01*
X921023Y1544547D01*
X921013Y1544646D01*
G01X919912Y1504665D02*
X919485Y1505256D01*
G01X919912Y1509665D02*
X919485Y1510256D01*
G01X919912Y1514665D02*
X919485Y1515256D01*
G01X919912Y1519665D02*
X919485Y1520256D01*
G01X919912Y1524665D02*
X919485Y1525256D01*
G01X921880Y1529665D02*
X921454Y1530256D01*
G01X919912Y1534665D02*
X919485Y1535256D01*
G01X919912Y1539665D02*
X919485Y1540256D01*
G01X919912Y1544665D02*
X919485Y1545256D01*
G01X926071Y1505650D02*
X925934Y1505847D01*
X925796Y1506044D01*
X925657Y1506240D01*
G01X926071Y1510650D02*
X925934Y1510847D01*
X925796Y1511044D01*
X925657Y1511240D01*
G01X926071Y1515650D02*
X925934Y1515847D01*
X925796Y1516044D01*
X925657Y1516240D01*
G01X926071Y1520650D02*
X925934Y1520847D01*
X925796Y1521044D01*
X925657Y1521240D01*
G01X926071Y1525650D02*
X925934Y1525847D01*
X925796Y1526044D01*
X925657Y1526240D01*
G01X928040Y1530650D02*
X927903Y1530847D01*
X927765Y1531044D01*
X927626Y1531240D01*
G01X926071Y1535650D02*
X925934Y1535847D01*
X925796Y1536044D01*
X925657Y1536240D01*
G01X926071Y1540650D02*
X925934Y1540847D01*
X925796Y1541044D01*
X925657Y1541240D01*
G01X921095Y1864916D02*
X921057Y1864943D01*
X921029Y1865015D01*
X921019Y1865113D01*
G01X921095Y1861767D02*
X921057Y1861793D01*
X921029Y1861865D01*
X921019Y1861964D01*
G01X921095Y1858617D02*
X921057Y1858644D01*
X921029Y1858716D01*
X921019Y1858814D01*
G01X921095Y1855468D02*
X921057Y1855494D01*
X921029Y1855566D01*
X921019Y1855664D01*
G01X921095Y1852318D02*
X921057Y1852344D01*
X921029Y1852416D01*
X921019Y1852515D01*
G01X921095Y1849168D02*
X921057Y1849195D01*
X921029Y1849267D01*
X921019Y1849365D01*
G01X921095Y1846019D02*
X921057Y1846045D01*
X921029Y1846117D01*
X921019Y1846216D01*
G01X921095Y1842869D02*
X921057Y1842896D01*
X921029Y1842968D01*
X921019Y1843066D01*
G01X921759Y1866198D02*
X921752Y1866202D01*
X921746Y1866213D01*
X921741Y1866231D01*
X921736Y1866256D01*
X921732Y1866285D01*
X921729Y1866319D01*
X921727Y1866356D01*
X921726Y1866395D01*
G01X921759Y1863048D02*
X921752Y1863052D01*
X921746Y1863063D01*
X921741Y1863081D01*
X921736Y1863106D01*
X921732Y1863136D01*
X921729Y1863170D01*
X921727Y1863206D01*
X921726Y1863245D01*
G01X921759Y1859899D02*
X921752Y1859903D01*
X921746Y1859914D01*
X921741Y1859932D01*
X921736Y1859956D01*
X921732Y1859986D01*
X921729Y1860020D01*
X921727Y1860057D01*
X921726Y1860096D01*
G01X927958Y1858696D02*
X929927Y1856727D01*
G01Y1820172D02*
X927958Y1822141D01*
G01X921095Y1839720D02*
X921057Y1839746D01*
X921029Y1839818D01*
X921019Y1839916D01*
G01X921095Y1836570D02*
X921057Y1836596D01*
X921029Y1836668D01*
X921019Y1836767D01*
G01X921095Y1833420D02*
X921057Y1833447D01*
X921029Y1833519D01*
X921019Y1833617D01*
G01X921095Y1830271D02*
X921057Y1830297D01*
X921029Y1830369D01*
X921019Y1830468D01*
G01X921095Y1827121D02*
X921057Y1827148D01*
X921029Y1827220D01*
X921019Y1827318D01*
G01X920722Y1866198D02*
X920693Y1866202D01*
X920666Y1866213D01*
X920640Y1866231D01*
X920617Y1866256D01*
X920599Y1866285D01*
X920585Y1866319D01*
X920577Y1866356D01*
X920574Y1866395D01*
G01X920722Y1863048D02*
X920693Y1863052D01*
X920666Y1863063D01*
X920640Y1863081D01*
X920617Y1863106D01*
X920599Y1863136D01*
X920585Y1863170D01*
X920577Y1863206D01*
X920574Y1863245D01*
G01X920722Y1859899D02*
X920693Y1859903D01*
X920666Y1859914D01*
X920640Y1859932D01*
X920617Y1859956D01*
X920599Y1859986D01*
X920585Y1860020D01*
X920577Y1860057D01*
X920574Y1860096D01*
G01X919632Y1866395D02*
X925950D01*
G01X919894Y1866198D02*
X925702D01*
G01X925693Y1865704D02*
X919608D01*
G01X919328Y1865507D02*
X925940D01*
G01Y1865113D02*
X919328D01*
G01X925693Y1864916D02*
X919608D01*
G01X919894Y1864426D02*
X925702D01*
G01X925950Y1864230D02*
X919632D01*
G01Y1863245D02*
X925950D01*
G01X919894Y1863048D02*
X925702D01*
G01X925693Y1862554D02*
X919608D01*
G01X919328Y1862357D02*
X925940D01*
G01Y1861964D02*
X919328D01*
G01X925693Y1861767D02*
X919608D01*
G01X919894Y1861277D02*
X925702D01*
G01X925950Y1861080D02*
X919632D01*
G01Y1860096D02*
X925950D01*
G01X919894Y1859899D02*
X925702D01*
G01X925693Y1859405D02*
X919608D01*
G01X919328Y1859208D02*
X925940D01*
G01Y1858814D02*
X919328D01*
G01X925693Y1858617D02*
X919608D01*
G01X929927Y1857534D02*
X923458D01*
G01X925762Y1856747D02*
X919849D01*
G01X925693Y1856255D02*
X919608D01*
G01X919425Y1856157D02*
X926168D01*
G01X919328Y1856058D02*
X925940D01*
G01X919425Y1855763D02*
X926168D01*
G01X925940Y1855664D02*
X919328D01*
G01X925693Y1855468D02*
X919608D01*
G01X925762Y1855172D02*
X919849D01*
G01X925693Y1853105D02*
X919608D01*
G01X919328Y1852908D02*
X925940D01*
G01Y1852515D02*
X919328D01*
G01X925693Y1852318D02*
X919608D01*
G01X925662Y1851747D02*
X919917D01*
G01X919491Y1851157D02*
X926077D01*
G01X919491Y1850763D02*
X926077D01*
G01X925662Y1850172D02*
X919917D01*
G01X925693Y1849956D02*
X919608D01*
G01X919328Y1849759D02*
X925940D01*
G01Y1849365D02*
X919328D01*
G01X925693Y1849168D02*
X919608D01*
G01X926168Y1856157D02*
X926034Y1856354D01*
X925898Y1856551D01*
X925762Y1856747D01*
G01X926077Y1851157D02*
X925940Y1851354D01*
X925802Y1851551D01*
X925662Y1851747D01*
G01X926077Y1846157D02*
X925940Y1846354D01*
X925802Y1846551D01*
X925662Y1846747D01*
G01X926077Y1841157D02*
X925940Y1841354D01*
X925802Y1841551D01*
X925662Y1841747D01*
G01X926077Y1836157D02*
X925940Y1836354D01*
X925802Y1836551D01*
X925662Y1836747D01*
G01X926077Y1831157D02*
X925940Y1831354D01*
X925802Y1831551D01*
X925662Y1831747D01*
G01X926077Y1826157D02*
X925940Y1826354D01*
X925802Y1826551D01*
X925662Y1826747D01*
G01X919849Y1855172D02*
X919425Y1855763D01*
G01X919917Y1850172D02*
X919491Y1850763D01*
G01X919917Y1845172D02*
X919491Y1845763D01*
G01X919917Y1840172D02*
X919491Y1840763D01*
G01X919917Y1835172D02*
X919491Y1835763D01*
G01X919917Y1830172D02*
X919491Y1830763D01*
G01X919917Y1825172D02*
X919491Y1825763D01*
G01X925693Y1846806D02*
X919608D01*
G01X925662Y1846747D02*
X919917D01*
G01X919328Y1846609D02*
X925940D01*
G01Y1846216D02*
X919328D01*
G01X919491Y1846157D02*
X926077D01*
G01X925693Y1846019D02*
X919608D01*
G01X919491Y1845763D02*
X926077D01*
G01X925662Y1845172D02*
X919917D01*
G01X925693Y1843657D02*
X919608D01*
G01X919328Y1843460D02*
X925940D01*
G01Y1843066D02*
X919328D01*
G01X925693Y1842869D02*
X919608D01*
G01X925662Y1841747D02*
X919917D01*
G01X919491Y1841157D02*
X926077D01*
G01X919491Y1840763D02*
X926077D01*
G01X925693Y1840507D02*
X919608D01*
G01X919328Y1840310D02*
X925940D01*
G01X925662Y1840172D02*
X919917D01*
G01X925940Y1839916D02*
X919328D01*
G01X925693Y1839720D02*
X919608D01*
G01X925693Y1837357D02*
X919608D01*
G01X919328Y1837160D02*
X925940D01*
G01Y1836767D02*
X919328D01*
G01X925662Y1836747D02*
X919917D01*
G01X925693Y1836570D02*
X919608D01*
G01X919491Y1836157D02*
X926077D01*
G01X919491Y1835763D02*
X926077D01*
G01X925662Y1835172D02*
X919917D01*
G01X925693Y1834208D02*
X919608D01*
G01X919328Y1834011D02*
X925940D01*
G01Y1833617D02*
X919328D01*
G01X925693Y1833420D02*
X919608D01*
G01X925662Y1831747D02*
X919917D01*
G01X919491Y1831157D02*
X926077D01*
G01X925693Y1831058D02*
X919608D01*
G01X919328Y1830861D02*
X925940D01*
G01X919491Y1830763D02*
X926077D01*
G01X925940Y1830468D02*
X919328D01*
G01X925693Y1830271D02*
X919608D01*
G01X925662Y1830172D02*
X919917D01*
G01X925693Y1827908D02*
X919608D01*
G01X919328Y1827712D02*
X925940D01*
G01Y1827318D02*
X919328D01*
G01X925693Y1827121D02*
X919608D01*
G01X925662Y1826747D02*
X919917D01*
G01X919491Y1826157D02*
X926077D01*
G01X919491Y1825763D02*
X926077D01*
G01X925662Y1825172D02*
X919917D01*
G01X933210Y1817220D02*
X929927D01*
G01X920644Y1865704D02*
X920617Y1865700D01*
X920591Y1865689D01*
X920567Y1865671D01*
X920546Y1865646D01*
X920529Y1865616D01*
X920516Y1865583D01*
X920508Y1865546D01*
X920506Y1865507D01*
G01X920644Y1862554D02*
X920617Y1862550D01*
X920591Y1862539D01*
X920567Y1862521D01*
X920546Y1862497D01*
X920529Y1862467D01*
X920516Y1862433D01*
X920508Y1862396D01*
X920506Y1862357D01*
G01X920644Y1859405D02*
X920617Y1859401D01*
X920591Y1859390D01*
X920567Y1859372D01*
X920546Y1859347D01*
X920529Y1859317D01*
X920516Y1859283D01*
X920508Y1859247D01*
X920506Y1859208D01*
G01X920644Y1856255D02*
X920617Y1856251D01*
X920591Y1856240D01*
X920567Y1856222D01*
X920546Y1856197D01*
X920529Y1856168D01*
X920516Y1856134D01*
X920508Y1856097D01*
X920506Y1856058D01*
G01X920644Y1853105D02*
X920617Y1853102D01*
X920591Y1853090D01*
X920567Y1853072D01*
X920546Y1853048D01*
X920529Y1853018D01*
X920516Y1852984D01*
X920508Y1852947D01*
X920506Y1852908D01*
G01X920644Y1849956D02*
X920617Y1849952D01*
X920591Y1849941D01*
X920567Y1849923D01*
X920546Y1849898D01*
X920529Y1849868D01*
X920516Y1849835D01*
X920508Y1849798D01*
X920506Y1849759D01*
G01X920644Y1846806D02*
X920617Y1846802D01*
X920591Y1846791D01*
X920567Y1846773D01*
X920546Y1846748D01*
X920529Y1846719D01*
X920516Y1846685D01*
X920508Y1846648D01*
X920506Y1846609D01*
G01X920644Y1843657D02*
X920617Y1843653D01*
X920591Y1843642D01*
X920567Y1843624D01*
X920546Y1843599D01*
X920529Y1843569D01*
X920516Y1843535D01*
X920508Y1843499D01*
X920506Y1843460D01*
G01X920644Y1840507D02*
X920617Y1840503D01*
X920591Y1840492D01*
X920567Y1840474D01*
X920546Y1840449D01*
X920529Y1840420D01*
X920516Y1840386D01*
X920508Y1840349D01*
X920506Y1840310D01*
G01X920644Y1837357D02*
X920617Y1837354D01*
X920591Y1837342D01*
X920567Y1837324D01*
X920546Y1837300D01*
X920529Y1837270D01*
X920516Y1837236D01*
X920508Y1837199D01*
X920506Y1837160D01*
G01X920607Y1855172D02*
X920334Y1855763D01*
G01X920607Y1850172D02*
X920334Y1850763D01*
G01X920607Y1845172D02*
X920334Y1845763D01*
G01X920607Y1840172D02*
X920334Y1840763D01*
G01X920607Y1835172D02*
X920334Y1835763D01*
G01X920607Y1830172D02*
X920334Y1830763D01*
G01X920607Y1825172D02*
X920334Y1825763D01*
G01X920644Y1834208D02*
X920617Y1834204D01*
X920591Y1834193D01*
X920567Y1834175D01*
X920546Y1834150D01*
X920529Y1834120D01*
X920516Y1834087D01*
X920508Y1834050D01*
X920506Y1834011D01*
G01X920644Y1831058D02*
X920617Y1831054D01*
X920591Y1831043D01*
X920567Y1831025D01*
X920546Y1831000D01*
X920529Y1830971D01*
X920516Y1830937D01*
X920508Y1830900D01*
X920506Y1830861D01*
G01X920644Y1827908D02*
X920617Y1827905D01*
X920591Y1827894D01*
X920567Y1827876D01*
X920546Y1827851D01*
X920529Y1827821D01*
X920516Y1827787D01*
X920508Y1827751D01*
X920506Y1827712D01*
G01X925702Y1866198D02*
X925829Y1866225D01*
X925918Y1866298D01*
X925950Y1866395D01*
G01X925702Y1863048D02*
X925829Y1863076D01*
X925918Y1863149D01*
X925950Y1863245D01*
G01X925702Y1859899D02*
X925829Y1859926D01*
X925918Y1859999D01*
X925950Y1860096D01*
G01X925693Y1864916D02*
X925820Y1864944D01*
X925909Y1865017D01*
X925940Y1865113D01*
G01X925693Y1861767D02*
X925820Y1861795D01*
X925909Y1861867D01*
X925940Y1861964D01*
G01X925693Y1858617D02*
X925820Y1858645D01*
X925909Y1858718D01*
X925940Y1858814D01*
G01X925693Y1855468D02*
X925820Y1855495D01*
X925909Y1855568D01*
X925940Y1855664D01*
G01X925693Y1852318D02*
X925820Y1852346D01*
X925909Y1852419D01*
X925940Y1852515D01*
G01X925693Y1849168D02*
X925820Y1849196D01*
X925909Y1849269D01*
X925940Y1849365D01*
G01X925693Y1846019D02*
X925820Y1846046D01*
X925909Y1846119D01*
X925940Y1846216D01*
G01X925693Y1842869D02*
X925820Y1842897D01*
X925909Y1842970D01*
X925940Y1843066D01*
G01X925693Y1839720D02*
X925820Y1839747D01*
X925909Y1839820D01*
X925940Y1839916D01*
G01X925693Y1836570D02*
X925820Y1836598D01*
X925909Y1836671D01*
X925940Y1836767D01*
G01X925693Y1833420D02*
X925820Y1833448D01*
X925909Y1833521D01*
X925940Y1833617D01*
G01X925693Y1830271D02*
X925820Y1830298D01*
X925909Y1830371D01*
X925940Y1830468D01*
G01X925693Y1827121D02*
X925820Y1827149D01*
X925909Y1827222D01*
X925940Y1827318D01*
G01Y1865507D02*
X925908Y1865604D01*
X925820Y1865676D01*
X925693Y1865704D01*
G01X925940Y1862357D02*
X925908Y1862454D01*
X925820Y1862527D01*
X925693Y1862554D01*
G01X925940Y1859208D02*
X925908Y1859305D01*
X925820Y1859377D01*
X925693Y1859405D01*
G01X925940Y1856058D02*
X925908Y1856155D01*
X925820Y1856227D01*
X925693Y1856255D01*
G01X925940Y1852908D02*
X925908Y1853006D01*
X925820Y1853078D01*
X925693Y1853105D01*
G01X925940Y1849759D02*
X925908Y1849856D01*
X925820Y1849928D01*
X925693Y1849956D01*
G01X925940Y1846609D02*
X925908Y1846706D01*
X925820Y1846778D01*
X925693Y1846806D01*
G01X925940Y1843460D02*
X925908Y1843557D01*
X925820Y1843629D01*
X925693Y1843657D01*
G01X925940Y1840310D02*
X925908Y1840407D01*
X925820Y1840479D01*
X925693Y1840507D01*
G01X925940Y1837160D02*
X925908Y1837257D01*
X925820Y1837330D01*
X925693Y1837357D01*
G01X925940Y1834011D02*
X925908Y1834108D01*
X925820Y1834180D01*
X925693Y1834208D01*
G01X925940Y1830861D02*
X925908Y1830958D01*
X925820Y1831030D01*
X925693Y1831058D01*
G01X925940Y1827712D02*
X925908Y1827809D01*
X925820Y1827881D01*
X925693Y1827908D01*
G01X925950Y1864230D02*
X925917Y1864329D01*
X925828Y1864399D01*
X925702Y1864426D01*
G01X925950Y1861080D02*
X925917Y1861179D01*
X925828Y1861250D01*
X925702Y1861277D01*
G01X921459Y1855763D02*
X921537Y1855172D01*
G01X921459Y1850763D02*
X921537Y1850172D01*
G01X921459Y1845763D02*
X921537Y1845172D01*
G01X921459Y1840763D02*
X921537Y1840172D01*
G01X921459Y1835763D02*
X921537Y1835172D01*
G01X921459Y1830763D02*
X921537Y1830172D01*
G01X921459Y1825763D02*
X921537Y1825172D01*
G01X921726Y1861080D02*
X921727Y1861118D01*
X921728Y1861155D01*
X921731Y1861189D01*
X921736Y1861219D01*
X921740Y1861244D01*
X921746Y1861262D01*
X921752Y1861273D01*
X921759Y1861277D01*
G01X921726Y1864230D02*
X921727Y1864268D01*
X921728Y1864305D01*
X921731Y1864338D01*
X921736Y1864369D01*
X921740Y1864393D01*
X921746Y1864411D01*
X921752Y1864423D01*
X921759Y1864426D01*
G01X929927Y1817220D02*
Y1959700D01*
G01X928915Y1857739D02*
Y1852357D01*
G01X928805Y1955172D02*
Y1821747D01*
G01X928746Y1857534D02*
Y1879385D01*
G01Y1852357D02*
Y1821353D01*
G01X927958Y1822141D02*
Y1954779D01*
G01X926168Y1856157D02*
Y1855763D01*
G01X926077Y1826157D02*
Y1825763D01*
G01Y1831157D02*
Y1830763D01*
G01Y1836157D02*
Y1835763D01*
G01Y1841157D02*
Y1840763D01*
G01Y1846157D02*
Y1845763D01*
G01Y1851157D02*
Y1850763D01*
G01X925950Y1861080D02*
Y1860096D01*
G01Y1864230D02*
Y1863245D01*
G01Y1867379D02*
Y1866395D01*
G01X925940Y1865113D02*
Y1865507D01*
G01Y1861964D02*
Y1862357D01*
G01Y1855664D02*
Y1856058D01*
G01Y1858814D02*
Y1859208D01*
G01Y1852515D02*
Y1852908D01*
G01Y1849365D02*
Y1849759D01*
G01Y1846216D02*
Y1846609D01*
G01Y1843066D02*
Y1843460D01*
G01Y1839916D02*
Y1840310D01*
G01Y1836767D02*
Y1837160D01*
G01Y1833617D02*
Y1834011D01*
G01Y1827318D02*
Y1827712D01*
G01Y1830468D02*
Y1830861D01*
G01X923458Y1858716D02*
Y1857534D01*
G01X921726Y1866395D02*
Y1867379D01*
G01Y1860096D02*
Y1861080D01*
G01Y1863245D02*
Y1864230D01*
G01X921459Y1826157D02*
Y1825763D01*
G01Y1831157D02*
Y1830763D01*
G01Y1836157D02*
Y1835763D01*
G01Y1841157D02*
Y1840763D01*
G01Y1846157D02*
Y1845763D01*
G01Y1851157D02*
Y1850763D01*
G01Y1856157D02*
Y1855763D01*
G01X921019Y1865113D02*
Y1865507D01*
G01Y1861964D02*
Y1862357D01*
G01Y1855664D02*
Y1856058D01*
G01Y1858814D02*
Y1859208D01*
G01Y1852515D02*
Y1852908D01*
G01Y1849365D02*
Y1849759D01*
G01Y1846216D02*
Y1846609D01*
G01Y1843066D02*
Y1843460D01*
G01Y1839916D02*
Y1840310D01*
G01Y1836767D02*
Y1837160D01*
G01Y1833617D02*
Y1834011D01*
G01Y1827318D02*
Y1827712D01*
G01Y1830468D02*
Y1830861D01*
G01X920574Y1866395D02*
Y1867379D01*
G01Y1860096D02*
Y1861080D01*
G01Y1863245D02*
Y1864230D01*
G01X920506Y1827712D02*
Y1827318D01*
G01Y1830861D02*
Y1830468D01*
G01Y1834011D02*
Y1833617D01*
G01Y1840310D02*
Y1839916D01*
G01Y1837160D02*
Y1836767D01*
G01Y1843460D02*
Y1843066D01*
G01Y1849759D02*
Y1849365D01*
G01Y1846609D02*
Y1846216D01*
G01Y1852908D02*
Y1852515D01*
G01Y1856058D02*
Y1855664D01*
G01Y1859208D02*
Y1858814D01*
G01Y1862357D02*
Y1861964D01*
G01Y1865507D02*
Y1865113D01*
G01X920334Y1855763D02*
Y1856157D01*
G01Y1850763D02*
Y1851157D01*
G01Y1845763D02*
Y1846157D01*
G01Y1840763D02*
Y1841157D01*
G01Y1835763D02*
Y1836157D01*
G01Y1830763D02*
Y1831157D01*
G01Y1825763D02*
Y1826157D01*
G01X919632Y1866395D02*
Y1867379D01*
G01Y1860096D02*
Y1861080D01*
G01Y1863245D02*
Y1864230D01*
G01X919491Y1850763D02*
Y1851157D01*
G01Y1845763D02*
Y1846157D01*
G01Y1840763D02*
Y1841157D01*
G01Y1835763D02*
Y1836157D01*
G01Y1830763D02*
Y1831157D01*
G01Y1825763D02*
Y1826157D01*
G01X919425Y1855763D02*
Y1856157D01*
G01X919328Y1827712D02*
Y1827318D01*
G01Y1830861D02*
Y1830468D01*
G01Y1834011D02*
Y1833617D01*
G01Y1840310D02*
Y1839916D01*
G01Y1837160D02*
Y1836767D01*
G01Y1843460D02*
Y1843066D01*
G01Y1849759D02*
Y1849365D01*
G01Y1846609D02*
Y1846216D01*
G01Y1852908D02*
Y1852515D01*
G01Y1856058D02*
Y1855664D01*
G01Y1859208D02*
Y1858814D01*
G01Y1862357D02*
Y1861964D01*
G01Y1865507D02*
Y1865113D01*
G01X920506D02*
X920508Y1865075D01*
X920516Y1865038D01*
X920529Y1865004D01*
X920546Y1864974D01*
X920567Y1864950D01*
X920591Y1864931D01*
X920617Y1864920D01*
X920644Y1864916D01*
G01X920506Y1861964D02*
X920508Y1861925D01*
X920516Y1861889D01*
X920529Y1861855D01*
X920546Y1861824D01*
X920567Y1861800D01*
X920591Y1861782D01*
X920617Y1861771D01*
X920644Y1861767D01*
G01X920506Y1858814D02*
X920508Y1858776D01*
X920516Y1858739D01*
X920529Y1858705D01*
X920546Y1858675D01*
X920567Y1858650D01*
X920591Y1858632D01*
X920617Y1858621D01*
X920644Y1858617D01*
G01X920506Y1855664D02*
X920508Y1855626D01*
X920516Y1855589D01*
X920529Y1855555D01*
X920546Y1855525D01*
X920567Y1855501D01*
X920591Y1855483D01*
X920617Y1855471D01*
X920644Y1855468D01*
G01X920506Y1852515D02*
X920508Y1852477D01*
X920516Y1852440D01*
X920529Y1852406D01*
X920546Y1852376D01*
X920567Y1852351D01*
X920591Y1852333D01*
X920617Y1852322D01*
X920644Y1852318D01*
G01X920506Y1849365D02*
X920508Y1849327D01*
X920516Y1849290D01*
X920529Y1849256D01*
X920546Y1849226D01*
X920567Y1849202D01*
X920591Y1849183D01*
X920617Y1849172D01*
X920644Y1849168D01*
G01X920506Y1846216D02*
X920508Y1846177D01*
X920516Y1846141D01*
X920529Y1846107D01*
X920546Y1846076D01*
X920567Y1846052D01*
X920591Y1846034D01*
X920617Y1846023D01*
X920644Y1846019D01*
G01X920506Y1843066D02*
X920508Y1843028D01*
X920516Y1842991D01*
X920529Y1842957D01*
X920546Y1842927D01*
X920567Y1842902D01*
X920591Y1842884D01*
X920617Y1842873D01*
X920644Y1842869D01*
G01X920506Y1839916D02*
X920508Y1839878D01*
X920516Y1839841D01*
X920529Y1839807D01*
X920546Y1839777D01*
X920567Y1839753D01*
X920591Y1839735D01*
X920617Y1839723D01*
X920644Y1839720D01*
G01X920506Y1836767D02*
X920508Y1836729D01*
X920516Y1836692D01*
X920529Y1836658D01*
X920546Y1836628D01*
X920567Y1836603D01*
X920591Y1836585D01*
X920617Y1836574D01*
X920644Y1836570D01*
G01X920506Y1833617D02*
X920508Y1833579D01*
X920516Y1833542D01*
X920529Y1833508D01*
X920546Y1833478D01*
X920567Y1833454D01*
X920591Y1833435D01*
X920617Y1833424D01*
X920644Y1833420D01*
G01X920506Y1830468D02*
X920508Y1830429D01*
X920516Y1830393D01*
X920529Y1830359D01*
X920546Y1830328D01*
X920567Y1830304D01*
X920591Y1830286D01*
X920617Y1830275D01*
X920644Y1830271D01*
G01X920506Y1827318D02*
X920508Y1827280D01*
X920516Y1827243D01*
X920529Y1827209D01*
X920546Y1827179D01*
X920567Y1827154D01*
X920591Y1827136D01*
X920617Y1827125D01*
X920644Y1827121D01*
G01X921019Y1830861D02*
X921029Y1830960D01*
X921057Y1831032D01*
X921095Y1831058D01*
G01X921019Y1834011D02*
X921029Y1834109D01*
X921057Y1834181D01*
X921095Y1834208D01*
G01X921019Y1846609D02*
X921029Y1846708D01*
X921057Y1846780D01*
X921095Y1846806D01*
G01X921019Y1849759D02*
X921029Y1849857D01*
X921057Y1849929D01*
X921095Y1849956D01*
G01X921019Y1859208D02*
X921029Y1859306D01*
X921057Y1859378D01*
X921095Y1859405D01*
G01X921019Y1862357D02*
X921029Y1862456D01*
X921057Y1862528D01*
X921095Y1862554D01*
G01X921019Y1865507D02*
X921029Y1865605D01*
X921057Y1865677D01*
X921095Y1865704D01*
G01X920574Y1861080D02*
X920577Y1861118D01*
X920585Y1861155D01*
X920599Y1861189D01*
X920617Y1861219D01*
X920640Y1861244D01*
X920665Y1861262D01*
X920693Y1861273D01*
X920722Y1861277D01*
G01X920574Y1864230D02*
X920577Y1864268D01*
X920585Y1864305D01*
X920599Y1864338D01*
X920617Y1864369D01*
X920640Y1864393D01*
X920665Y1864411D01*
X920693Y1864423D01*
X920722Y1864426D01*
G01X921459Y1826157D02*
X921537Y1826747D01*
G01X921459Y1831157D02*
X921537Y1831747D01*
G01X921459Y1836157D02*
X921537Y1836747D01*
G01X921459Y1841157D02*
X921537Y1841747D01*
G01X921459Y1846157D02*
X921537Y1846747D01*
G01X921459Y1851157D02*
X921537Y1851747D01*
G01X921459Y1856157D02*
X921537Y1856747D01*
G01X920334Y1826157D02*
X920607Y1826747D01*
G01X920334Y1831157D02*
X920607Y1831747D01*
G01X920334Y1836157D02*
X920607Y1836747D01*
G01X920334Y1841157D02*
X920607Y1841747D01*
G01X920334Y1846157D02*
X920607Y1846747D01*
G01X920334Y1851157D02*
X920607Y1851747D01*
G01X920334Y1856157D02*
X920607Y1856747D01*
G01X919917Y1826747D02*
X919491Y1826157D01*
G01X919917Y1831747D02*
X919491Y1831157D01*
G01X919917Y1836747D02*
X919491Y1836157D01*
G01X919917Y1841747D02*
X919491Y1841157D01*
G01X919917Y1846747D02*
X919491Y1846157D01*
G01X919917Y1851747D02*
X919491Y1851157D01*
G01X919849Y1856747D02*
X919425Y1856157D01*
G01X925662Y1825172D02*
X925802Y1825368D01*
X925940Y1825565D01*
X926077Y1825763D01*
G01X925662Y1830172D02*
X925802Y1830368D01*
X925940Y1830565D01*
X926077Y1830763D01*
G01X925662Y1835172D02*
X925802Y1835368D01*
X925940Y1835565D01*
X926077Y1835763D01*
G01X925662Y1840172D02*
X925802Y1840368D01*
X925940Y1840565D01*
X926077Y1840763D01*
G01X925662Y1845172D02*
X925802Y1845368D01*
X925940Y1845565D01*
X926077Y1845763D01*
G01X925662Y1850172D02*
X925802Y1850368D01*
X925940Y1850565D01*
X926077Y1850763D01*
G01X925762Y1855172D02*
X925898Y1855368D01*
X926034Y1855565D01*
X926168Y1855763D01*
G01X929927Y1819188D02*
X927958Y1817220D01*
G01X921095Y1827908D02*
X921057Y1827882D01*
X921029Y1827810D01*
X921019Y1827712D01*
G01X921095Y1837357D02*
X921057Y1837331D01*
X921029Y1837259D01*
X921019Y1837160D01*
G01X921095Y1840507D02*
X921057Y1840480D01*
X921029Y1840408D01*
X921019Y1840310D01*
G01X921095Y1843657D02*
X921057Y1843630D01*
X921029Y1843558D01*
X921019Y1843460D01*
G01X921095Y1853105D02*
X921057Y1853079D01*
X921029Y1853007D01*
X921019Y1852908D01*
G01X921095Y1856255D02*
X921057Y1856229D01*
X921029Y1856156D01*
X921019Y1856058D01*
G01X931954Y1809595D02*
X931899Y1809981D01*
G01X936620Y1815251D02*
Y1813519D01*
G01X931895Y1810054D02*
Y1817220D01*
G01X931927Y1808904D02*
X931983Y1809039D01*
X931990Y1809274D01*
X931953Y1809603D01*
G01X931927Y1808904D02*
X931984Y1809044D01*
X931989Y1809284D01*
G01X936620Y1813519D02*
X931895Y1808873D01*
G01X936620Y1814622D02*
X931899Y1809981D01*
G01X933210Y1817220D02*
X936620Y1815251D01*
G01X982289Y1889749D02*
G03X1013785I15748J0D01*
G01X982289D02*
G03X1013785I15748J0D01*
G01X982289D02*
G03X1013785I15748J0D01*
G01X1011816Y1903529D02*
G03X984257I-13779J0D01*
G01X1013785D02*
G03X982289I-15748J0D01*
G01X1013785D02*
G03X982289I-15748J0D01*
G01X1013785D02*
G03X982289I-15748J0D01*
G01X984257Y1901166D02*
X992131D01*
G01X984257Y1903529D02*
Y1901166D01*
G01X982289Y1889749D02*
Y1903529D01*
G01Y1889749D02*
Y1903529D01*
G01Y1889749D02*
Y1903529D01*
G01X921095Y1886964D02*
X921057Y1886990D01*
X921029Y1887062D01*
X921019Y1887160D01*
G01X921095Y1883814D02*
X921057Y1883840D01*
X921029Y1883912D01*
X921019Y1884011D01*
G01X921095Y1880664D02*
X921057Y1880691D01*
X921029Y1880763D01*
X921019Y1880861D01*
G01X921095Y1877515D02*
X921057Y1877541D01*
X921029Y1877613D01*
X921019Y1877712D01*
G01X921095Y1874365D02*
X921057Y1874392D01*
X921029Y1874464D01*
X921019Y1874562D01*
G01X921095Y1871216D02*
X921057Y1871242D01*
X921029Y1871314D01*
X921019Y1871412D01*
G01X921095Y1868066D02*
X921057Y1868092D01*
X921029Y1868164D01*
X921019Y1868263D01*
G01X921759Y1875647D02*
X921752Y1875651D01*
X921746Y1875662D01*
X921741Y1875680D01*
X921736Y1875705D01*
X921732Y1875734D01*
X921729Y1875768D01*
X921727Y1875805D01*
X921726Y1875844D01*
G01X921759Y1872497D02*
X921752Y1872501D01*
X921746Y1872512D01*
X921741Y1872530D01*
X921736Y1872555D01*
X921732Y1872585D01*
X921729Y1872618D01*
X921727Y1872655D01*
X921726Y1872694D01*
G01X921759Y1869348D02*
X921752Y1869351D01*
X921746Y1869363D01*
X921741Y1869381D01*
X921736Y1869405D01*
X921732Y1869435D01*
X921729Y1869469D01*
X921727Y1869506D01*
X921726Y1869545D01*
G01X920722Y1875647D02*
X920693Y1875651D01*
X920666Y1875662D01*
X920640Y1875680D01*
X920617Y1875705D01*
X920599Y1875734D01*
X920585Y1875768D01*
X920577Y1875805D01*
X920574Y1875844D01*
G01X920722Y1872497D02*
X920693Y1872501D01*
X920666Y1872512D01*
X920640Y1872530D01*
X920617Y1872555D01*
X920599Y1872585D01*
X920585Y1872618D01*
X920577Y1872655D01*
X920574Y1872694D01*
G01X920722Y1869348D02*
X920693Y1869351D01*
X920666Y1869363D01*
X920640Y1869381D01*
X920617Y1869405D01*
X920599Y1869435D01*
X920585Y1869469D01*
X920577Y1869506D01*
X920574Y1869545D01*
G01X925693Y1887751D02*
X919608D01*
G01X919328Y1887554D02*
X925940D01*
G01Y1887160D02*
X919328D01*
G01X925693Y1886964D02*
X919608D01*
G01X925662Y1886747D02*
X919917D01*
G01X919491Y1886157D02*
X926077D01*
G01X919491Y1885763D02*
X926077D01*
G01X925662Y1885172D02*
X919917D01*
G01X925693Y1884601D02*
X919608D01*
G01X919328Y1884405D02*
X925940D01*
G01Y1884011D02*
X919328D01*
G01X925693Y1883814D02*
X919608D01*
G01X925762Y1881747D02*
X919849D01*
G01X925693Y1881452D02*
X919608D01*
G01X919328Y1881255D02*
X925940D01*
G01X919425Y1881157D02*
X926168D01*
G01X925940Y1880861D02*
X919328D01*
G01X919425Y1880763D02*
X926168D01*
G01X925693Y1880664D02*
X919608D01*
G01X925762Y1880172D02*
X919849D01*
G01X923458Y1879385D02*
X929927D01*
G01X925693Y1878302D02*
X919608D01*
G01X919328Y1878105D02*
X925940D01*
G01Y1877712D02*
X919328D01*
G01X925693Y1877515D02*
X919608D01*
G01X919894Y1877025D02*
X925702D01*
G01X925950Y1876828D02*
X919632D01*
G01Y1875844D02*
X925950D01*
G01X919894Y1875647D02*
X925702D01*
G01X925693Y1875153D02*
X919608D01*
G01X919328Y1874956D02*
X925940D01*
G01Y1874562D02*
X919328D01*
G01X925693Y1874365D02*
X919608D01*
G01X919894Y1873875D02*
X925702D01*
G01X925950Y1873678D02*
X919632D01*
G01Y1872694D02*
X925950D01*
G01X919894Y1872497D02*
X925702D01*
G01X925693Y1872003D02*
X919608D01*
G01X919328Y1871806D02*
X925940D01*
G01Y1871412D02*
X919328D01*
G01X925693Y1871216D02*
X919608D01*
G01X919894Y1870726D02*
X925702D01*
G01X925950Y1870529D02*
X919632D01*
G01Y1869545D02*
X925950D01*
G01X919894Y1869348D02*
X925702D01*
G01X925693Y1868853D02*
X919608D01*
G01X919328Y1868657D02*
X925940D01*
G01Y1868263D02*
X919328D01*
G01X925693Y1868066D02*
X919608D01*
G01X919894Y1867576D02*
X925702D01*
G01X925950Y1867379D02*
X919632D01*
G01X926168Y1881157D02*
X926034Y1881354D01*
X925898Y1881551D01*
X925762Y1881747D01*
G01X926077Y1886157D02*
X925940Y1886354D01*
X925802Y1886551D01*
X925662Y1886747D01*
G01X919849Y1880172D02*
X919425Y1880763D01*
G01X919917Y1885172D02*
X919491Y1885763D01*
G01X920644Y1887751D02*
X920617Y1887747D01*
X920591Y1887736D01*
X920567Y1887718D01*
X920546Y1887693D01*
X920529Y1887664D01*
X920516Y1887630D01*
X920508Y1887593D01*
X920506Y1887554D01*
G01X920644Y1884601D02*
X920617Y1884598D01*
X920591Y1884587D01*
X920567Y1884569D01*
X920546Y1884544D01*
X920529Y1884514D01*
X920516Y1884480D01*
X920508Y1884443D01*
X920506Y1884405D01*
G01X920644Y1881452D02*
X920617Y1881448D01*
X920591Y1881437D01*
X920567Y1881419D01*
X920546Y1881394D01*
X920529Y1881364D01*
X920516Y1881331D01*
X920508Y1881294D01*
X920506Y1881255D01*
G01X920644Y1878302D02*
X920617Y1878298D01*
X920591Y1878287D01*
X920567Y1878269D01*
X920546Y1878245D01*
X920529Y1878215D01*
X920516Y1878181D01*
X920508Y1878144D01*
X920506Y1878105D01*
G01X920644Y1875153D02*
X920617Y1875149D01*
X920591Y1875138D01*
X920567Y1875120D01*
X920546Y1875095D01*
X920529Y1875065D01*
X920516Y1875031D01*
X920508Y1874995D01*
X920506Y1874956D01*
G01X920644Y1872003D02*
X920617Y1871999D01*
X920591Y1871988D01*
X920567Y1871970D01*
X920546Y1871945D01*
X920529Y1871916D01*
X920516Y1871882D01*
X920508Y1871845D01*
X920506Y1871806D01*
G01X920644Y1868853D02*
X920617Y1868850D01*
X920591Y1868839D01*
X920567Y1868820D01*
X920546Y1868796D01*
X920529Y1868766D01*
X920516Y1868732D01*
X920508Y1868695D01*
X920506Y1868657D01*
G01X925693Y1886964D02*
X925820Y1886991D01*
X925909Y1887064D01*
X925940Y1887160D01*
G01X925693Y1883814D02*
X925820Y1883842D01*
X925909Y1883915D01*
X925940Y1884011D01*
G01X925693Y1880664D02*
X925820Y1880692D01*
X925909Y1880765D01*
X925940Y1880861D01*
G01X920607Y1885172D02*
X920334Y1885763D01*
G01X920607Y1880172D02*
X920334Y1880763D01*
G01X925702Y1875647D02*
X925829Y1875674D01*
X925918Y1875747D01*
X925950Y1875844D01*
G01X925702Y1872497D02*
X925829Y1872525D01*
X925918Y1872597D01*
X925950Y1872694D01*
G01X925702Y1869348D02*
X925829Y1869375D01*
X925918Y1869448D01*
X925950Y1869545D01*
G01X925693Y1877515D02*
X925820Y1877543D01*
X925909Y1877615D01*
X925940Y1877712D01*
G01X925693Y1874365D02*
X925820Y1874393D01*
X925909Y1874466D01*
X925940Y1874562D01*
G01X925693Y1871216D02*
X925820Y1871243D01*
X925909Y1871316D01*
X925940Y1871412D01*
G01X925693Y1868066D02*
X925820Y1868094D01*
X925909Y1868167D01*
X925940Y1868263D01*
G01Y1887554D02*
X925908Y1887651D01*
X925820Y1887723D01*
X925693Y1887751D01*
G01X925940Y1884405D02*
X925908Y1884502D01*
X925820Y1884574D01*
X925693Y1884601D01*
G01X925940Y1881255D02*
X925908Y1881352D01*
X925820Y1881424D01*
X925693Y1881452D01*
G01X925940Y1878105D02*
X925908Y1878202D01*
X925820Y1878275D01*
X925693Y1878302D01*
G01X925940Y1874956D02*
X925908Y1875053D01*
X925820Y1875125D01*
X925693Y1875153D01*
G01X925940Y1871806D02*
X925908Y1871903D01*
X925820Y1871975D01*
X925693Y1872003D01*
G01X925940Y1868657D02*
X925908Y1868754D01*
X925820Y1868826D01*
X925693Y1868853D01*
G01X925950Y1876828D02*
X925917Y1876927D01*
X925828Y1876998D01*
X925702Y1877025D01*
G01X925950Y1873678D02*
X925917Y1873777D01*
X925828Y1873848D01*
X925702Y1873875D01*
G01X925950Y1870529D02*
X925917Y1870628D01*
X925828Y1870699D01*
X925702Y1870726D01*
G01X925950Y1867379D02*
X925917Y1867478D01*
X925828Y1867549D01*
X925702Y1867576D01*
G01X921459Y1885763D02*
X921537Y1885172D01*
G01X921459Y1880763D02*
X921537Y1880172D01*
G01X921726Y1867379D02*
X921727Y1867417D01*
X921728Y1867454D01*
X921731Y1867488D01*
X921736Y1867518D01*
X921740Y1867543D01*
X921746Y1867561D01*
X921752Y1867572D01*
X921759Y1867576D01*
G01X921726Y1870529D02*
X921727Y1870567D01*
X921728Y1870604D01*
X921731Y1870638D01*
X921736Y1870668D01*
X921740Y1870692D01*
X921746Y1870710D01*
X921752Y1870722D01*
X921759Y1870726D01*
G01X921726Y1873678D02*
X921727Y1873717D01*
X921728Y1873753D01*
X921731Y1873787D01*
X921736Y1873818D01*
X921740Y1873842D01*
X921746Y1873860D01*
X921752Y1873871D01*
X921759Y1873875D01*
G01X921726Y1876828D02*
X921727Y1876866D01*
X921728Y1876903D01*
X921731Y1876937D01*
X921736Y1876967D01*
X921740Y1876992D01*
X921746Y1877010D01*
X921752Y1877021D01*
X921759Y1877025D01*
G01X928915Y1884660D02*
Y1879181D01*
G01X928746Y1955566D02*
Y1884660D01*
G01X926168Y1881157D02*
Y1880763D01*
G01X926077Y1886157D02*
Y1885763D01*
G01X925950Y1870529D02*
Y1869545D01*
G01Y1873678D02*
Y1872694D01*
G01Y1876828D02*
Y1875844D01*
G01X925940Y1887160D02*
Y1887554D01*
G01Y1884011D02*
Y1884405D01*
G01Y1880861D02*
Y1881255D01*
G01Y1877712D02*
Y1878105D01*
G01Y1874562D02*
Y1874956D01*
G01Y1871412D02*
Y1871806D01*
G01Y1868263D02*
Y1868657D01*
G01X923458Y1879385D02*
Y1878204D01*
G01X921726Y1875844D02*
Y1876828D01*
G01Y1869545D02*
Y1870529D01*
G01Y1872694D02*
Y1873678D01*
G01X921459Y1881157D02*
Y1880763D01*
G01Y1886157D02*
Y1885763D01*
G01X921019Y1887160D02*
Y1887554D01*
G01Y1884011D02*
Y1884405D01*
G01Y1880861D02*
Y1881255D01*
G01Y1877712D02*
Y1878105D01*
G01Y1874562D02*
Y1874956D01*
G01Y1871412D02*
Y1871806D01*
G01Y1868263D02*
Y1868657D01*
G01X920574Y1875844D02*
Y1876828D01*
G01Y1869545D02*
Y1870529D01*
G01Y1872694D02*
Y1873678D01*
G01X920506Y1868657D02*
Y1868263D01*
G01Y1871806D02*
Y1871412D01*
G01Y1878105D02*
Y1877712D01*
G01Y1874956D02*
Y1874562D01*
G01Y1881255D02*
Y1880861D01*
G01Y1887554D02*
Y1887160D01*
G01Y1884405D02*
Y1884011D01*
G01X920334Y1885763D02*
Y1886157D01*
G01Y1880763D02*
Y1881157D01*
G01X919632Y1875844D02*
Y1876828D01*
G01Y1869545D02*
Y1870529D01*
G01Y1872694D02*
Y1873678D01*
G01X919491Y1885763D02*
Y1886157D01*
G01X919425Y1880763D02*
Y1881157D01*
G01X919328Y1868657D02*
Y1868263D01*
G01Y1871806D02*
Y1871412D01*
G01Y1878105D02*
Y1877712D01*
G01Y1874956D02*
Y1874562D01*
G01Y1881255D02*
Y1880861D01*
G01Y1887554D02*
Y1887160D01*
G01Y1884405D02*
Y1884011D01*
G01X920506Y1887160D02*
X920508Y1887122D01*
X920516Y1887085D01*
X920529Y1887052D01*
X920546Y1887021D01*
X920567Y1886997D01*
X920591Y1886979D01*
X920617Y1886968D01*
X920644Y1886964D01*
G01X920506Y1884011D02*
X920508Y1883973D01*
X920516Y1883936D01*
X920529Y1883902D01*
X920546Y1883872D01*
X920567Y1883847D01*
X920591Y1883829D01*
X920617Y1883818D01*
X920644Y1883814D01*
G01X920506Y1880861D02*
X920508Y1880823D01*
X920516Y1880786D01*
X920529Y1880752D01*
X920546Y1880722D01*
X920567Y1880698D01*
X920591Y1880680D01*
X920617Y1880668D01*
X920644Y1880664D01*
G01X920506Y1877712D02*
X920508Y1877673D01*
X920516Y1877637D01*
X920529Y1877603D01*
X920546Y1877572D01*
X920567Y1877548D01*
X920591Y1877530D01*
X920617Y1877519D01*
X920644Y1877515D01*
G01X920506Y1874562D02*
X920508Y1874524D01*
X920516Y1874487D01*
X920529Y1874453D01*
X920546Y1874423D01*
X920567Y1874398D01*
X920591Y1874380D01*
X920617Y1874369D01*
X920644Y1874365D01*
G01X920506Y1871412D02*
X920508Y1871374D01*
X920516Y1871337D01*
X920529Y1871304D01*
X920546Y1871273D01*
X920567Y1871249D01*
X920591Y1871231D01*
X920617Y1871219D01*
X920644Y1871216D01*
G01X920506Y1868263D02*
X920508Y1868225D01*
X920516Y1868188D01*
X920529Y1868154D01*
X920546Y1868124D01*
X920567Y1868099D01*
X920591Y1868081D01*
X920617Y1868070D01*
X920644Y1868066D01*
G01X920574Y1867379D02*
X920577Y1867417D01*
X920585Y1867454D01*
X920599Y1867488D01*
X920617Y1867518D01*
X920640Y1867543D01*
X920665Y1867561D01*
X920693Y1867572D01*
X920722Y1867576D01*
G01X920574Y1870529D02*
X920577Y1870567D01*
X920585Y1870604D01*
X920599Y1870638D01*
X920617Y1870668D01*
X920640Y1870692D01*
X920665Y1870710D01*
X920693Y1870722D01*
X920722Y1870726D01*
G01X920574Y1873678D02*
X920577Y1873717D01*
X920585Y1873753D01*
X920599Y1873787D01*
X920617Y1873818D01*
X920640Y1873842D01*
X920665Y1873860D01*
X920693Y1873871D01*
X920722Y1873875D01*
G01X920574Y1876828D02*
X920577Y1876866D01*
X920585Y1876903D01*
X920599Y1876937D01*
X920617Y1876967D01*
X920640Y1876992D01*
X920665Y1877010D01*
X920693Y1877021D01*
X920722Y1877025D01*
G01X921459Y1881157D02*
X921537Y1881747D01*
G01X921459Y1886157D02*
X921537Y1886747D01*
G01X921019Y1868657D02*
X921029Y1868755D01*
X921057Y1868827D01*
X921095Y1868853D01*
G01X921019Y1874956D02*
X921029Y1875054D01*
X921057Y1875126D01*
X921095Y1875153D01*
G01X921019Y1878105D02*
X921029Y1878204D01*
X921057Y1878276D01*
X921095Y1878302D01*
G01X921019Y1881255D02*
X921029Y1881353D01*
X921057Y1881425D01*
X921095Y1881452D01*
G01X921019Y1884405D02*
X921029Y1884503D01*
X921057Y1884575D01*
X921095Y1884601D01*
G01X921019Y1887554D02*
X921029Y1887653D01*
X921057Y1887725D01*
X921095Y1887751D01*
G01X920334Y1881157D02*
X920607Y1881747D01*
G01X920334Y1886157D02*
X920607Y1886747D01*
G01X919917D02*
X919491Y1886157D01*
G01X919849Y1881747D02*
X919425Y1881157D01*
G01X925662Y1885172D02*
X925802Y1885368D01*
X925940Y1885565D01*
X926077Y1885763D01*
G01X925762Y1880172D02*
X925898Y1880368D01*
X926034Y1880565D01*
X926168Y1880763D01*
G01X929927Y1880192D02*
X927958Y1878223D01*
G01X921095Y1872003D02*
X921057Y1871977D01*
X921029Y1871904D01*
X921019Y1871806D01*
G01X921095Y1937357D02*
X921057Y1937384D01*
X921029Y1937456D01*
X921019Y1937554D01*
G01X925693Y1938145D02*
X925819Y1938117D01*
X925909Y1938045D01*
X925940Y1937948D01*
G01X921095Y1934208D02*
X921057Y1934234D01*
X921029Y1934306D01*
X921019Y1934405D01*
G01X921095Y1931058D02*
X921057Y1931085D01*
X921029Y1931157D01*
X921019Y1931255D01*
G01X921095Y1927908D02*
X921057Y1927935D01*
X921029Y1928007D01*
X921019Y1928105D01*
G01X921095Y1924759D02*
X921057Y1924785D01*
X921029Y1924857D01*
X921019Y1924956D01*
G01X921095Y1921609D02*
X921057Y1921636D01*
X921029Y1921708D01*
X921019Y1921806D01*
G01X921095Y1918460D02*
X921057Y1918486D01*
X921029Y1918558D01*
X921019Y1918657D01*
G01X921095Y1915310D02*
X921057Y1915336D01*
X921029Y1915409D01*
X921019Y1915507D01*
G01X921095Y1912160D02*
X921057Y1912187D01*
X921029Y1912259D01*
X921019Y1912357D01*
G01X921095Y1909011D02*
X921057Y1909037D01*
X921029Y1909109D01*
X921019Y1909208D01*
G01X921095Y1905861D02*
X921057Y1905888D01*
X921029Y1905960D01*
X921019Y1906058D01*
G01X921095Y1902712D02*
X921057Y1902738D01*
X921029Y1902810D01*
X921019Y1902908D01*
G01X921095Y1899562D02*
X921057Y1899588D01*
X921029Y1899661D01*
X921019Y1899759D01*
G01X921095Y1896412D02*
X921057Y1896439D01*
X921029Y1896511D01*
X921019Y1896609D01*
G01X921095Y1893263D02*
X921057Y1893289D01*
X921029Y1893361D01*
X921019Y1893460D01*
G01X921095Y1890113D02*
X921057Y1890140D01*
X921029Y1890212D01*
X921019Y1890310D01*
G01X925693Y1909798D02*
X925819Y1909771D01*
X925909Y1909698D01*
X925940Y1909601D01*
G01X925693Y1938145D02*
X919608D01*
G01X919328Y1937948D02*
X925940D01*
G01Y1937554D02*
X919328D01*
G01X925693Y1937357D02*
X919608D01*
G01X927631Y1936747D02*
X921886D01*
G01X921459Y1936157D02*
X928045D01*
G01X921459Y1935763D02*
X928045D01*
G01X927631Y1935172D02*
X921886D01*
G01X925693Y1934995D02*
X919608D01*
G01X919328Y1934798D02*
X925940D01*
G01Y1934405D02*
X919328D01*
G01X925693Y1934208D02*
X919608D01*
G01X925693Y1931846D02*
X919608D01*
G01X925662Y1931747D02*
X919917D01*
G01X919328Y1931649D02*
X925940D01*
G01Y1931255D02*
X919328D01*
G01X919491Y1931157D02*
X926077D01*
G01X925693Y1931058D02*
X919608D01*
G01X919491Y1930763D02*
X926077D01*
G01X925662Y1930172D02*
X919917D01*
G01X925693Y1928696D02*
X919608D01*
G01X919328Y1928499D02*
X925940D01*
G01Y1928105D02*
X919328D01*
G01X925693Y1927908D02*
X919608D01*
G01X925662Y1926747D02*
X919917D01*
G01X919491Y1926157D02*
X926077D01*
G01X919491Y1925763D02*
X926077D01*
G01X925693Y1925546D02*
X919608D01*
G01X919328Y1925349D02*
X925940D01*
G01X925662Y1925172D02*
X919917D01*
G01X925940Y1924956D02*
X919328D01*
G01X925693Y1924759D02*
X919608D01*
G01X928045Y1936157D02*
X927908Y1936354D01*
X927770Y1936551D01*
X927631Y1936747D01*
G01X926077Y1931157D02*
X925940Y1931354D01*
X925802Y1931551D01*
X925662Y1931747D01*
G01X926077Y1926157D02*
X925940Y1926354D01*
X925802Y1926551D01*
X925662Y1926747D01*
G01X926077Y1921157D02*
X925940Y1921354D01*
X925802Y1921551D01*
X925662Y1921747D01*
G01X926077Y1916157D02*
X925940Y1916354D01*
X925802Y1916551D01*
X925662Y1916747D01*
G01X926077Y1911157D02*
X925940Y1911354D01*
X925802Y1911551D01*
X925662Y1911747D01*
G01X926077Y1906157D02*
X925940Y1906354D01*
X925802Y1906551D01*
X925662Y1906747D01*
G01X926077Y1901157D02*
X925940Y1901354D01*
X925802Y1901551D01*
X925662Y1901747D01*
G01X928045Y1896157D02*
X927908Y1896354D01*
X927770Y1896551D01*
X927631Y1896747D01*
G01X921886Y1935172D02*
X921459Y1935763D01*
G01X919917Y1930172D02*
X919491Y1930763D01*
G01X919917Y1925172D02*
X919491Y1925763D01*
G01X919917Y1920172D02*
X919491Y1920763D01*
G01X919917Y1915172D02*
X919491Y1915763D01*
G01X919917Y1910172D02*
X919491Y1910763D01*
G01X919917Y1905172D02*
X919491Y1905763D01*
G01X919917Y1900172D02*
X919491Y1900763D01*
G01X921886Y1895172D02*
X921459Y1895763D01*
G01X919917Y1890172D02*
X919491Y1890763D01*
G01X925693Y1922397D02*
X919608D01*
G01X919328Y1922200D02*
X925940D01*
G01Y1921806D02*
X919328D01*
G01X925662Y1921747D02*
X919917D01*
G01X925693Y1921609D02*
X919608D01*
G01X919491Y1921157D02*
X926077D01*
G01X919491Y1920763D02*
X926077D01*
G01X925662Y1920172D02*
X919917D01*
G01X925693Y1919247D02*
X919608D01*
G01X919328Y1919050D02*
X925940D01*
G01Y1918657D02*
X919328D01*
G01X925693Y1918460D02*
X919608D01*
G01X925662Y1916747D02*
X919917D01*
G01X919491Y1916157D02*
X926077D01*
G01X925693Y1916097D02*
X919608D01*
G01X919328Y1915901D02*
X925940D01*
G01X919491Y1915763D02*
X926077D01*
G01X925940Y1915507D02*
X919328D01*
G01X925693Y1915310D02*
X919608D01*
G01X925662Y1915172D02*
X919917D01*
G01X925693Y1912948D02*
X919608D01*
G01X919328Y1912751D02*
X925940D01*
G01Y1912357D02*
X919328D01*
G01X925693Y1912160D02*
X919608D01*
G01X925662Y1911747D02*
X919917D01*
G01X919491Y1911157D02*
X926077D01*
G01X919491Y1910763D02*
X926077D01*
G01X925662Y1910172D02*
X919917D01*
G01X925693Y1909798D02*
X919608D01*
G01X919328Y1909601D02*
X925940D01*
G01Y1909208D02*
X919328D01*
G01X925693Y1909011D02*
X919608D01*
G01X925662Y1906747D02*
X919917D01*
G01X925693Y1906649D02*
X919608D01*
G01X919328Y1906452D02*
X925940D01*
G01X919491Y1906157D02*
X926077D01*
G01X925940Y1906058D02*
X919328D01*
G01X925693Y1905861D02*
X919608D01*
G01X919491Y1905763D02*
X926077D01*
G01X925662Y1905172D02*
X919917D01*
G01X925693Y1903499D02*
X919608D01*
G01X919328Y1903302D02*
X925940D01*
G01Y1902908D02*
X919328D01*
G01X925693Y1902712D02*
X919608D01*
G01X925662Y1901747D02*
X919917D01*
G01X919491Y1901157D02*
X926077D01*
G01X919491Y1900763D02*
X926077D01*
G01X925693Y1900349D02*
X919608D01*
G01X925662Y1900172D02*
X919917D01*
G01X919328Y1900153D02*
X925940D01*
G01Y1899759D02*
X919328D01*
G01X925693Y1899562D02*
X919608D01*
G01X925693Y1897200D02*
X919608D01*
G01X919328Y1897003D02*
X925940D01*
G01X927631Y1896747D02*
X921886D01*
G01X925940Y1896609D02*
X919328D01*
G01X925693Y1896412D02*
X919608D01*
G01X921459Y1896157D02*
X928045D01*
G01X921459Y1895763D02*
X928045D01*
G01X927631Y1895172D02*
X921886D01*
G01X925693Y1894050D02*
X919608D01*
G01X919328Y1893853D02*
X925940D01*
G01Y1893460D02*
X919328D01*
G01X925693Y1893263D02*
X919608D01*
G01X925662Y1891747D02*
X919917D01*
G01X919491Y1891157D02*
X926077D01*
G01X925693Y1890901D02*
X919608D01*
G01X919491Y1890763D02*
X926077D01*
G01X919328Y1890704D02*
X925940D01*
G01Y1890310D02*
X919328D01*
G01X925662Y1890172D02*
X919917D01*
G01X925693Y1890113D02*
X919608D01*
G01X920644Y1938145D02*
X920617Y1938141D01*
X920591Y1938130D01*
X920567Y1938112D01*
X920546Y1938087D01*
X920529Y1938057D01*
X920516Y1938024D01*
X920508Y1937987D01*
X920506Y1937948D01*
G01X920644Y1934995D02*
X920617Y1934991D01*
X920591Y1934980D01*
X920567Y1934962D01*
X920546Y1934937D01*
X920529Y1934908D01*
X920516Y1934874D01*
X920508Y1934837D01*
X920506Y1934798D01*
G01X920644Y1931846D02*
X920617Y1931842D01*
X920591Y1931831D01*
X920567Y1931813D01*
X920546Y1931788D01*
X920529Y1931758D01*
X920516Y1931724D01*
X920508Y1931688D01*
X920506Y1931649D01*
G01X920644Y1928696D02*
X920617Y1928692D01*
X920591Y1928681D01*
X920567Y1928663D01*
X920546Y1928638D01*
X920529Y1928609D01*
X920516Y1928575D01*
X920508Y1928538D01*
X920506Y1928499D01*
G01X920644Y1925546D02*
X920617Y1925543D01*
X920591Y1925531D01*
X920567Y1925513D01*
X920546Y1925489D01*
X920529Y1925459D01*
X920516Y1925425D01*
X920508Y1925388D01*
X920506Y1925349D01*
G01X920644Y1922397D02*
X920617Y1922393D01*
X920591Y1922382D01*
X920567Y1922364D01*
X920546Y1922339D01*
X920529Y1922309D01*
X920516Y1922275D01*
X920508Y1922239D01*
X920506Y1922200D01*
G01X920644Y1919247D02*
X920617Y1919243D01*
X920591Y1919232D01*
X920567Y1919214D01*
X920546Y1919189D01*
X920529Y1919160D01*
X920516Y1919126D01*
X920508Y1919089D01*
X920506Y1919050D01*
G01X920644Y1916097D02*
X920617Y1916094D01*
X920591Y1916083D01*
X920567Y1916065D01*
X920546Y1916040D01*
X920529Y1916010D01*
X920516Y1915976D01*
X920508Y1915940D01*
X920506Y1915901D01*
G01X920644Y1912948D02*
X920617Y1912944D01*
X920591Y1912933D01*
X920567Y1912915D01*
X920546Y1912890D01*
X920529Y1912861D01*
X920516Y1912827D01*
X920508Y1912790D01*
X920506Y1912751D01*
G01X926077Y1891157D02*
X925940Y1891354D01*
X925802Y1891551D01*
X925662Y1891747D01*
G01X920644Y1909798D02*
X920617Y1909795D01*
X920591Y1909783D01*
X920567Y1909765D01*
X920546Y1909741D01*
X920529Y1909711D01*
X920516Y1909677D01*
X920508Y1909640D01*
X920506Y1909601D01*
G01X920644Y1906649D02*
X920617Y1906645D01*
X920591Y1906634D01*
X920567Y1906616D01*
X920546Y1906591D01*
X920529Y1906561D01*
X920516Y1906527D01*
X920508Y1906491D01*
X920506Y1906452D01*
G01X920644Y1903499D02*
X920617Y1903495D01*
X920591Y1903484D01*
X920567Y1903466D01*
X920546Y1903441D01*
X920529Y1903412D01*
X920516Y1903378D01*
X920508Y1903341D01*
X920506Y1903302D01*
G01X920644Y1900349D02*
X920617Y1900346D01*
X920591Y1900335D01*
X920567Y1900317D01*
X920546Y1900292D01*
X920529Y1900262D01*
X920516Y1900228D01*
X920508Y1900192D01*
X920506Y1900153D01*
G01X920644Y1897200D02*
X920617Y1897196D01*
X920591Y1897185D01*
X920567Y1897167D01*
X920546Y1897142D01*
X920529Y1897112D01*
X920516Y1897079D01*
X920508Y1897042D01*
X920506Y1897003D01*
G01X920644Y1894050D02*
X920617Y1894046D01*
X920591Y1894035D01*
X920567Y1894017D01*
X920546Y1893993D01*
X920529Y1893963D01*
X920516Y1893929D01*
X920508Y1893892D01*
X920506Y1893853D01*
G01X920644Y1890901D02*
X920617Y1890897D01*
X920591Y1890886D01*
X920567Y1890868D01*
X920546Y1890843D01*
X920529Y1890813D01*
X920516Y1890779D01*
X920508Y1890743D01*
X920506Y1890704D01*
G01X925693Y1934208D02*
X925820Y1934235D01*
X925909Y1934308D01*
X925940Y1934405D01*
G01X925693Y1931058D02*
X925820Y1931086D01*
X925909Y1931159D01*
X925940Y1931255D01*
G01X925693Y1927908D02*
X925820Y1927936D01*
X925909Y1928009D01*
X925940Y1928105D01*
G01X925693Y1924759D02*
X925820Y1924787D01*
X925909Y1924860D01*
X925940Y1924956D01*
G01X925693Y1921609D02*
X925820Y1921637D01*
X925909Y1921710D01*
X925940Y1921806D01*
G01X925693Y1918460D02*
X925820Y1918487D01*
X925909Y1918560D01*
X925940Y1918657D01*
G01X925693Y1915310D02*
X925820Y1915338D01*
X925909Y1915411D01*
X925940Y1915507D01*
G01X925693Y1912160D02*
X925820Y1912188D01*
X925909Y1912261D01*
X925940Y1912357D01*
G01X925693Y1905861D02*
X925820Y1905889D01*
X925909Y1905962D01*
X925940Y1906058D01*
G01X925693Y1902712D02*
X925820Y1902739D01*
X925909Y1902812D01*
X925940Y1902908D01*
G01X925693Y1899562D02*
X925820Y1899590D01*
X925909Y1899663D01*
X925940Y1899759D01*
G01X925693Y1896412D02*
X925820Y1896440D01*
X925909Y1896513D01*
X925940Y1896609D01*
G01X925693Y1893263D02*
X925820Y1893291D01*
X925909Y1893363D01*
X925940Y1893460D01*
G01X925693Y1890113D02*
X925820Y1890141D01*
X925909Y1890214D01*
X925940Y1890310D01*
G01X922576Y1935172D02*
X922303Y1935763D01*
G01X920607Y1930172D02*
X920334Y1930763D01*
G01X920607Y1925172D02*
X920334Y1925763D01*
G01X920607Y1920172D02*
X920334Y1920763D01*
G01X920607Y1915172D02*
X920334Y1915763D01*
G01X920607Y1910172D02*
X920334Y1910763D01*
G01X920607Y1905172D02*
X920334Y1905763D01*
G01X920607Y1900172D02*
X920334Y1900763D01*
G01X922576Y1895172D02*
X922303Y1895763D01*
G01X920607Y1890172D02*
X920334Y1890763D01*
G01X925940Y1934798D02*
X925908Y1934895D01*
X925820Y1934967D01*
X925693Y1934995D01*
G01X925940Y1931649D02*
X925908Y1931746D01*
X925820Y1931818D01*
X925693Y1931846D01*
G01X925940Y1928499D02*
X925908Y1928596D01*
X925820Y1928668D01*
X925693Y1928696D01*
G01X925940Y1925349D02*
X925908Y1925446D01*
X925820Y1925519D01*
X925693Y1925546D01*
G01X925940Y1922200D02*
X925908Y1922297D01*
X925820Y1922369D01*
X925693Y1922397D01*
G01X925940Y1919050D02*
X925908Y1919147D01*
X925820Y1919219D01*
X925693Y1919247D01*
G01X925940Y1915901D02*
X925908Y1915998D01*
X925820Y1916070D01*
X925693Y1916097D01*
G01X925940Y1912751D02*
X925908Y1912848D01*
X925820Y1912920D01*
X925693Y1912948D01*
G01X925940Y1906452D02*
X925908Y1906549D01*
X925820Y1906621D01*
X925693Y1906649D01*
G01X925940Y1903302D02*
X925908Y1903399D01*
X925820Y1903471D01*
X925693Y1903499D01*
G01X925940Y1900153D02*
X925908Y1900250D01*
X925820Y1900322D01*
X925693Y1900349D01*
G01X925940Y1897003D02*
X925908Y1897100D01*
X925820Y1897172D01*
X925693Y1897200D01*
G01X925940Y1893853D02*
X925908Y1893950D01*
X925820Y1894023D01*
X925693Y1894050D01*
G01X925940Y1890704D02*
X925908Y1890801D01*
X925820Y1890873D01*
X925693Y1890901D01*
G01X923428Y1935763D02*
X923505Y1935172D01*
G01X921459Y1930763D02*
X921537Y1930172D01*
G01X921459Y1925763D02*
X921537Y1925172D01*
G01X921459Y1920763D02*
X921537Y1920172D01*
G01X921459Y1915763D02*
X921537Y1915172D01*
G01X921459Y1910763D02*
X921537Y1910172D01*
G01X923428Y1895763D02*
X923505Y1895172D01*
G01X921459Y1905763D02*
X921537Y1905172D01*
G01X921459Y1900763D02*
X921537Y1900172D01*
G01X921459Y1890763D02*
X921537Y1890172D01*
G01X920506Y1937554D02*
X920508Y1937516D01*
X920516Y1937479D01*
X920529Y1937445D01*
X920546Y1937415D01*
X920567Y1937391D01*
X920591Y1937372D01*
X920617Y1937361D01*
X920644Y1937357D01*
G01X920506Y1934405D02*
X920508Y1934366D01*
X920516Y1934330D01*
X920529Y1934296D01*
X920546Y1934265D01*
X920567Y1934241D01*
X920591Y1934223D01*
X920617Y1934212D01*
X920644Y1934208D01*
G01X920506Y1931255D02*
X920508Y1931217D01*
X920516Y1931180D01*
X920529Y1931146D01*
X920546Y1931116D01*
X920567Y1931091D01*
X920591Y1931073D01*
X920617Y1931062D01*
X920644Y1931058D01*
G01X920506Y1928105D02*
X920508Y1928067D01*
X920516Y1928030D01*
X920529Y1927996D01*
X920546Y1927966D01*
X920567Y1927942D01*
X920591Y1927924D01*
X920617Y1927912D01*
X920644Y1927908D01*
G01X920506Y1924956D02*
X920508Y1924918D01*
X920516Y1924881D01*
X920529Y1924847D01*
X920546Y1924817D01*
X920567Y1924792D01*
X920591Y1924774D01*
X920617Y1924763D01*
X920644Y1924759D01*
G01X920506Y1921806D02*
X920508Y1921768D01*
X920516Y1921731D01*
X920529Y1921697D01*
X920546Y1921667D01*
X920567Y1921643D01*
X920591Y1921624D01*
X920617Y1921613D01*
X920644Y1921609D01*
G01X920506Y1918657D02*
X920508Y1918618D01*
X920516Y1918582D01*
X920529Y1918548D01*
X920546Y1918517D01*
X920567Y1918493D01*
X920591Y1918475D01*
X920617Y1918464D01*
X920644Y1918460D01*
G01X920506Y1915507D02*
X920508Y1915469D01*
X920516Y1915432D01*
X920529Y1915398D01*
X920546Y1915368D01*
X920567Y1915343D01*
X920591Y1915325D01*
X920617Y1915314D01*
X920644Y1915310D01*
G01X920506Y1912357D02*
X920508Y1912319D01*
X920516Y1912282D01*
X920529Y1912248D01*
X920546Y1912218D01*
X920567Y1912194D01*
X920591Y1912176D01*
X920617Y1912164D01*
X920644Y1912160D01*
G01X920506Y1909208D02*
X920508Y1909169D01*
X920516Y1909133D01*
X920529Y1909099D01*
X920546Y1909069D01*
X920567Y1909044D01*
X920591Y1909026D01*
X920617Y1909015D01*
X920644Y1909011D01*
G01X920506Y1906058D02*
X920508Y1906020D01*
X920516Y1905983D01*
X920529Y1905949D01*
X920546Y1905919D01*
X920567Y1905895D01*
X920591Y1905876D01*
X920617Y1905865D01*
X920644Y1905861D01*
G01X928045Y1896157D02*
Y1895763D01*
G01Y1936157D02*
Y1935763D01*
G01X926077Y1891157D02*
Y1890763D01*
G01Y1901157D02*
Y1900763D01*
G01Y1906157D02*
Y1905763D01*
G01Y1911157D02*
Y1910763D01*
G01Y1916157D02*
Y1915763D01*
G01Y1921157D02*
Y1920763D01*
G01Y1926157D02*
Y1925763D01*
G01Y1931157D02*
Y1930763D01*
G01X925940Y1934405D02*
Y1934798D01*
G01Y1937554D02*
Y1937948D01*
G01Y1931255D02*
Y1931649D01*
G01Y1928105D02*
Y1928499D01*
G01Y1924956D02*
Y1925349D01*
G01Y1921806D02*
Y1922200D01*
G01Y1918657D02*
Y1919050D01*
G01Y1915507D02*
Y1915901D01*
G01Y1912357D02*
Y1912751D01*
G01Y1909208D02*
Y1909601D01*
G01Y1902908D02*
Y1903302D01*
G01Y1906058D02*
Y1906452D01*
G01Y1899759D02*
Y1900153D01*
G01Y1896609D02*
Y1897003D01*
G01Y1893460D02*
Y1893853D01*
G01Y1890310D02*
Y1890704D01*
G01X923428Y1896157D02*
Y1895763D01*
G01Y1936157D02*
Y1935763D01*
G01X922303D02*
Y1936157D01*
G01Y1895763D02*
Y1896157D01*
G01X921459Y1935763D02*
Y1936157D01*
G01Y1895763D02*
Y1896157D01*
G01Y1891157D02*
Y1890763D01*
G01Y1901157D02*
Y1900763D01*
G01Y1906157D02*
Y1905763D01*
G01Y1911157D02*
Y1910763D01*
G01Y1916157D02*
Y1915763D01*
G01Y1921157D02*
Y1920763D01*
G01Y1926157D02*
Y1925763D01*
G01Y1931157D02*
Y1930763D01*
G01X921019Y1934405D02*
Y1934798D01*
G01Y1937554D02*
Y1937948D01*
G01Y1931255D02*
Y1931649D01*
G01Y1928105D02*
Y1928499D01*
G01Y1924956D02*
Y1925349D01*
G01Y1921806D02*
Y1922200D01*
G01Y1918657D02*
Y1919050D01*
G01Y1915507D02*
Y1915901D01*
G01Y1912357D02*
Y1912751D01*
G01Y1909208D02*
Y1909601D01*
G01Y1902908D02*
Y1903302D01*
G01Y1906058D02*
Y1906452D01*
G01Y1899759D02*
Y1900153D01*
G01Y1896609D02*
Y1897003D01*
G01Y1893460D02*
Y1893853D01*
G01Y1890310D02*
Y1890704D01*
G01X920506D02*
Y1890310D01*
G01Y1897003D02*
Y1896609D01*
G01Y1893853D02*
Y1893460D01*
G01Y1900153D02*
Y1899759D01*
G01Y1903302D02*
Y1902908D01*
G01Y1906452D02*
Y1906058D01*
G01Y1909601D02*
Y1909208D01*
G01Y1915901D02*
Y1915507D01*
G01Y1912751D02*
Y1912357D01*
G01Y1919050D02*
Y1918657D01*
G01Y1922200D02*
Y1921806D01*
G01Y1928499D02*
Y1928105D01*
G01Y1925349D02*
Y1924956D01*
G01Y1931649D02*
Y1931255D01*
G01Y1934798D02*
Y1934405D01*
G01Y1937948D02*
Y1937554D01*
G01X920334Y1930763D02*
Y1931157D01*
G01Y1925763D02*
Y1926157D01*
G01Y1920763D02*
Y1921157D01*
G01Y1915763D02*
Y1916157D01*
G01Y1910763D02*
Y1911157D01*
G01Y1905763D02*
Y1906157D01*
G01Y1900763D02*
Y1901157D01*
G01Y1890763D02*
Y1891157D01*
G01X919491Y1930763D02*
Y1931157D01*
G01Y1925763D02*
Y1926157D01*
G01Y1920763D02*
Y1921157D01*
G01Y1915763D02*
Y1916157D01*
G01Y1910763D02*
Y1911157D01*
G01Y1905763D02*
Y1906157D01*
G01Y1900763D02*
Y1901157D01*
G01Y1890763D02*
Y1891157D01*
G01X919328Y1890704D02*
Y1890310D01*
G01Y1897003D02*
Y1896609D01*
G01Y1893853D02*
Y1893460D01*
G01Y1900153D02*
Y1899759D01*
G01Y1903302D02*
Y1902908D01*
G01Y1906452D02*
Y1906058D01*
G01Y1909601D02*
Y1909208D01*
G01Y1915901D02*
Y1915507D01*
G01Y1912751D02*
Y1912357D01*
G01Y1919050D02*
Y1918657D01*
G01Y1922200D02*
Y1921806D01*
G01Y1928499D02*
Y1928105D01*
G01Y1925349D02*
Y1924956D01*
G01Y1931649D02*
Y1931255D01*
G01Y1934798D02*
Y1934405D01*
G01Y1937948D02*
Y1937554D01*
G01X920506Y1902908D02*
X920508Y1902870D01*
X920516Y1902833D01*
X920529Y1902800D01*
X920546Y1902769D01*
X920567Y1902745D01*
X920591Y1902727D01*
X920617Y1902716D01*
X920644Y1902712D01*
G01X920506Y1899759D02*
X920508Y1899721D01*
X920516Y1899684D01*
X920529Y1899650D01*
X920546Y1899620D01*
X920567Y1899595D01*
X920591Y1899577D01*
X920617Y1899566D01*
X920644Y1899562D01*
G01X920506Y1896609D02*
X920508Y1896571D01*
X920516Y1896534D01*
X920529Y1896500D01*
X920546Y1896470D01*
X920567Y1896446D01*
X920591Y1896428D01*
X920617Y1896416D01*
X920644Y1896412D01*
G01X920506Y1893460D02*
X920508Y1893421D01*
X920516Y1893385D01*
X920529Y1893351D01*
X920546Y1893320D01*
X920567Y1893296D01*
X920591Y1893278D01*
X920617Y1893267D01*
X920644Y1893263D01*
G01X920506Y1890310D02*
X920508Y1890272D01*
X920516Y1890235D01*
X920529Y1890201D01*
X920546Y1890171D01*
X920567Y1890146D01*
X920591Y1890128D01*
X920617Y1890117D01*
X920644Y1890113D01*
G01X923428Y1896157D02*
X923505Y1896747D01*
G01X921459Y1891157D02*
X921537Y1891747D01*
G01X921459Y1901157D02*
X921537Y1901747D01*
G01X921459Y1906157D02*
X921537Y1906747D01*
G01X921459Y1911157D02*
X921537Y1911747D01*
G01X921459Y1916157D02*
X921537Y1916747D01*
G01X921459Y1921157D02*
X921537Y1921747D01*
G01X923428Y1936157D02*
X923505Y1936747D01*
G01X921459Y1926157D02*
X921537Y1926747D01*
G01X921459Y1931157D02*
X921537Y1931747D01*
G01X921019Y1890704D02*
X921029Y1890802D01*
X921057Y1890874D01*
X921095Y1890901D01*
G01X921019Y1893853D02*
X921029Y1893952D01*
X921057Y1894024D01*
X921095Y1894050D01*
G01X921019Y1897003D02*
X921029Y1897101D01*
X921057Y1897173D01*
X921095Y1897200D01*
G01X921019Y1900153D02*
X921029Y1900251D01*
X921057Y1900323D01*
X921095Y1900349D01*
G01X921019Y1903302D02*
X921029Y1903401D01*
X921057Y1903473D01*
X921095Y1903499D01*
G01X921019Y1906452D02*
X921029Y1906550D01*
X921057Y1906622D01*
X921095Y1906649D01*
G01X921019Y1909601D02*
X921029Y1909700D01*
X921057Y1909772D01*
X921095Y1909798D01*
G01X921019Y1912751D02*
X921029Y1912849D01*
X921057Y1912921D01*
X921095Y1912948D01*
G01X921019Y1915901D02*
X921029Y1915999D01*
X921057Y1916071D01*
X921095Y1916097D01*
G01X921019Y1919050D02*
X921029Y1919149D01*
X921057Y1919221D01*
X921095Y1919247D01*
G01X921019Y1922200D02*
X921029Y1922298D01*
X921057Y1922370D01*
X921095Y1922397D01*
G01X921019Y1925349D02*
X921029Y1925448D01*
X921057Y1925520D01*
X921095Y1925546D01*
G01X921019Y1928499D02*
X921029Y1928597D01*
X921057Y1928669D01*
X921095Y1928696D01*
G01X921019Y1931649D02*
X921029Y1931747D01*
X921057Y1931819D01*
X921095Y1931846D01*
G01X921019Y1934798D02*
X921029Y1934897D01*
X921057Y1934969D01*
X921095Y1934995D01*
G01X921019Y1937948D02*
X921029Y1938046D01*
X921057Y1938118D01*
X921095Y1938145D01*
G01X925940Y1909208D02*
X925907Y1909109D01*
X925819Y1909038D01*
X925693Y1909011D01*
G01X925940Y1937554D02*
X925907Y1937455D01*
X925819Y1937384D01*
X925693Y1937357D01*
G01X920334Y1891157D02*
X920607Y1891747D01*
G01X922303Y1896157D02*
X922576Y1896747D01*
G01X920334Y1901157D02*
X920607Y1901747D01*
G01X920334Y1906157D02*
X920607Y1906747D01*
G01X920334Y1911157D02*
X920607Y1911747D01*
G01X920334Y1916157D02*
X920607Y1916747D01*
G01X920334Y1921157D02*
X920607Y1921747D01*
G01X920334Y1926157D02*
X920607Y1926747D01*
G01X920334Y1931157D02*
X920607Y1931747D01*
G01X922303Y1936157D02*
X922576Y1936747D01*
G01X919917Y1891747D02*
X919491Y1891157D01*
G01X921886Y1896747D02*
X921459Y1896157D01*
G01X919917Y1901747D02*
X919491Y1901157D01*
G01X919917Y1906747D02*
X919491Y1906157D01*
G01X919917Y1911747D02*
X919491Y1911157D01*
G01X919917Y1916747D02*
X919491Y1916157D01*
G01X919917Y1921747D02*
X919491Y1921157D01*
G01X919917Y1926747D02*
X919491Y1926157D01*
G01X919917Y1931747D02*
X919491Y1931157D01*
G01X925662Y1890172D02*
X925802Y1890368D01*
X925940Y1890565D01*
X926077Y1890763D01*
G01X927631Y1895172D02*
X927770Y1895368D01*
X927908Y1895565D01*
X928045Y1895763D01*
G01X925662Y1900172D02*
X925802Y1900368D01*
X925940Y1900565D01*
X926077Y1900763D01*
G01X925662Y1905172D02*
X925802Y1905368D01*
X925940Y1905565D01*
X926077Y1905763D01*
G01X925662Y1910172D02*
X925802Y1910368D01*
X925940Y1910565D01*
X926077Y1910763D01*
G01X925662Y1915172D02*
X925802Y1915368D01*
X925940Y1915565D01*
X926077Y1915763D01*
G01X925662Y1920172D02*
X925802Y1920368D01*
X925940Y1920565D01*
X926077Y1920763D01*
G01X925662Y1925172D02*
X925802Y1925368D01*
X925940Y1925565D01*
X926077Y1925763D01*
G01X925662Y1930172D02*
X925802Y1930368D01*
X925940Y1930565D01*
X926077Y1930763D01*
G01X927631Y1935172D02*
X927770Y1935368D01*
X927908Y1935565D01*
X928045Y1935763D01*
G01X921886Y1936747D02*
X921459Y1936157D01*
G01X921095Y1949956D02*
X921057Y1949982D01*
X921029Y1950054D01*
X921019Y1950153D01*
G01X921095Y1946806D02*
X921057Y1946833D01*
X921029Y1946905D01*
X921019Y1947003D01*
G01X921095Y1943657D02*
X921057Y1943683D01*
X921029Y1943755D01*
X921019Y1943853D01*
G01X921095Y1940507D02*
X921057Y1940533D01*
X921029Y1940605D01*
X921019Y1940704D01*
G01X927958Y1959700D02*
X929927Y1957731D01*
G01X933210Y1959700D02*
X929927D01*
G01X925662Y1951747D02*
X919917D01*
G01X919491Y1951157D02*
X926077D01*
G01X919491Y1950763D02*
X926077D01*
G01X925693Y1950743D02*
X919608D01*
G01X919328Y1950546D02*
X925940D01*
G01X925662Y1950172D02*
X919917D01*
G01X925940Y1950153D02*
X919328D01*
G01X925693Y1949956D02*
X919608D01*
G01X925693Y1947594D02*
X919608D01*
G01X919328Y1947397D02*
X925940D01*
G01Y1947003D02*
X919328D01*
G01X925693Y1946806D02*
X919608D01*
G01X925662Y1946747D02*
X919917D01*
G01X919491Y1946157D02*
X926077D01*
G01X919491Y1945763D02*
X926077D01*
G01X925662Y1945172D02*
X919917D01*
G01X925693Y1944444D02*
X919608D01*
G01X919328Y1944247D02*
X925940D01*
G01Y1943853D02*
X919328D01*
G01X925693Y1943657D02*
X919608D01*
G01X925662Y1941747D02*
X919917D01*
G01X925693Y1941294D02*
X919608D01*
G01X919491Y1941157D02*
X926077D01*
G01X919328Y1941097D02*
X925940D01*
G01X919491Y1940763D02*
X926077D01*
G01X925940Y1940704D02*
X919328D01*
G01X925693Y1940507D02*
X919608D01*
G01X925662Y1940172D02*
X919917D01*
G01X926077Y1951157D02*
X925940Y1951354D01*
X925802Y1951551D01*
X925662Y1951747D01*
G01X926077Y1946157D02*
X925940Y1946354D01*
X925802Y1946551D01*
X925662Y1946747D01*
G01X926077Y1941157D02*
X925940Y1941354D01*
X925802Y1941551D01*
X925662Y1941747D01*
G01X919917Y1950172D02*
X919491Y1950763D01*
G01X919917Y1945172D02*
X919491Y1945763D01*
G01X919917Y1940172D02*
X919491Y1940763D01*
G01X920644Y1950743D02*
X920617Y1950739D01*
X920591Y1950728D01*
X920567Y1950710D01*
X920546Y1950685D01*
X920529Y1950656D01*
X920516Y1950622D01*
X920508Y1950585D01*
X920506Y1950546D01*
G01X920644Y1947594D02*
X920617Y1947590D01*
X920591Y1947579D01*
X920567Y1947561D01*
X920546Y1947536D01*
X920529Y1947506D01*
X920516Y1947472D01*
X920508Y1947436D01*
X920506Y1947397D01*
G01X920644Y1944444D02*
X920617Y1944440D01*
X920591Y1944429D01*
X920567Y1944411D01*
X920546Y1944386D01*
X920529Y1944357D01*
X920516Y1944323D01*
X920508Y1944286D01*
X920506Y1944247D01*
G01X920644Y1941294D02*
X920617Y1941291D01*
X920591Y1941279D01*
X920567Y1941261D01*
X920546Y1941237D01*
X920529Y1941207D01*
X920516Y1941173D01*
X920508Y1941136D01*
X920506Y1941097D01*
G01X925693Y1949956D02*
X925820Y1949983D01*
X925909Y1950056D01*
X925940Y1950153D01*
G01X925693Y1946806D02*
X925820Y1946834D01*
X925909Y1946907D01*
X925940Y1947003D01*
G01X925693Y1943657D02*
X925820Y1943684D01*
X925909Y1943757D01*
X925940Y1943853D01*
G01X925693Y1940507D02*
X925820Y1940535D01*
X925909Y1940608D01*
X925940Y1940704D01*
G01X920607Y1950172D02*
X920334Y1950763D01*
G01X920607Y1945172D02*
X920334Y1945763D01*
G01X920607Y1940172D02*
X920334Y1940763D01*
G01X925940Y1950546D02*
X925908Y1950643D01*
X925820Y1950715D01*
X925693Y1950743D01*
G01X925940Y1947397D02*
X925908Y1947494D01*
X925820Y1947566D01*
X925693Y1947594D01*
G01X925940Y1944247D02*
X925908Y1944344D01*
X925820Y1944416D01*
X925693Y1944444D01*
G01X925940Y1941097D02*
X925908Y1941194D01*
X925820Y1941267D01*
X925693Y1941294D01*
G01X921459Y1950763D02*
X921537Y1950172D01*
G01Y1945172D02*
X921459Y1945763D01*
G01Y1940763D02*
X921537Y1940172D01*
G01X920506Y1950153D02*
X920508Y1950114D01*
X920516Y1950078D01*
X920529Y1950044D01*
X920546Y1950013D01*
X920567Y1949989D01*
X920591Y1949971D01*
X920617Y1949960D01*
X920644Y1949956D01*
G01X920506Y1947003D02*
X920508Y1946965D01*
X920516Y1946928D01*
X920529Y1946894D01*
X920546Y1946864D01*
X920567Y1946839D01*
X920591Y1946821D01*
X920617Y1946810D01*
X920644Y1946806D01*
G01X920506Y1943853D02*
X920508Y1943815D01*
X920516Y1943778D01*
X920529Y1943744D01*
X920546Y1943714D01*
X920567Y1943690D01*
X920591Y1943672D01*
X920617Y1943660D01*
X920644Y1943657D01*
G01X920506Y1940704D02*
X920508Y1940666D01*
X920516Y1940629D01*
X920529Y1940595D01*
X920546Y1940565D01*
X920567Y1940540D01*
X920591Y1940522D01*
X920617Y1940511D01*
X920644Y1940507D01*
G01X926077Y1941157D02*
Y1940763D01*
G01Y1946157D02*
Y1945763D01*
G01Y1951157D02*
Y1950763D01*
G01X925940Y1950153D02*
Y1950546D01*
G01Y1947003D02*
Y1947397D01*
G01Y1943853D02*
Y1944247D01*
G01Y1940704D02*
Y1941097D01*
G01X921459Y1945763D02*
Y1946157D01*
G01Y1941157D02*
Y1940763D01*
G01Y1951157D02*
Y1950763D01*
G01X921019Y1950153D02*
Y1950546D01*
G01Y1947003D02*
Y1947397D01*
G01Y1943853D02*
Y1944247D01*
G01Y1940704D02*
Y1941097D01*
G01X920506D02*
Y1940704D01*
G01Y1947397D02*
Y1947003D01*
G01Y1944247D02*
Y1943853D01*
G01Y1950546D02*
Y1950153D01*
G01X920334Y1950763D02*
Y1951157D01*
G01Y1945763D02*
Y1946157D01*
G01Y1940763D02*
Y1941157D01*
G01X919491Y1950763D02*
Y1951157D01*
G01Y1945763D02*
Y1946157D01*
G01Y1940763D02*
Y1941157D01*
G01X919328Y1941097D02*
Y1940704D01*
G01Y1947397D02*
Y1947003D01*
G01Y1944247D02*
Y1943853D01*
G01Y1950546D02*
Y1950153D01*
G01X921459Y1941157D02*
X921537Y1941747D01*
G01Y1946747D02*
X921459Y1946157D01*
G01Y1951157D02*
X921537Y1951747D01*
G01X921019Y1941097D02*
X921029Y1941196D01*
X921057Y1941268D01*
X921095Y1941294D01*
G01X921019Y1944247D02*
X921029Y1944345D01*
X921057Y1944418D01*
X921095Y1944444D01*
G01X921019Y1947397D02*
X921029Y1947495D01*
X921057Y1947567D01*
X921095Y1947594D01*
G01X921019Y1950546D02*
X921029Y1950645D01*
X921057Y1950717D01*
X921095Y1950743D01*
G01X920334Y1941157D02*
X920607Y1941747D01*
G01X920334Y1946157D02*
X920607Y1946747D01*
G01X920334Y1951157D02*
X920607Y1951747D01*
G01X925662Y1940172D02*
X925802Y1940368D01*
X925940Y1940565D01*
X926077Y1940763D01*
G01X925662Y1945172D02*
X925802Y1945368D01*
X925940Y1945565D01*
X926077Y1945763D01*
G01X925662Y1950172D02*
X925802Y1950368D01*
X925940Y1950565D01*
X926077Y1950763D01*
G01X919917Y1941747D02*
X919491Y1941157D01*
G01X919917Y1946747D02*
X919491Y1946157D01*
G01X919917Y1951747D02*
X919491Y1951157D01*
G01X927958Y1954779D02*
X929927Y1956747D01*
G01X931895Y1959700D02*
Y1966865D01*
G01X933210Y1959700D02*
X936620Y1961668D01*
G01Y1963401D02*
X931895Y1968046D01*
G01X931899Y1966939D02*
X936620Y1962297D01*
G01X931927Y1968015D02*
X931984Y1967875D01*
X931989Y1967635D01*
G01X936620Y1961668D02*
Y1963401D01*
G01X931953Y1967316D02*
X931899Y1966939D01*
G01X931953Y1967314D02*
X931990Y1967638D01*
X931984Y1967879D01*
X931927Y1968015D01*
G01X1054991Y-172119D02*
Y-191056D01*
G01X1015299Y44000D02*
G03I-4299J0D01*
G01X1045276Y0D02*
X1112953D01*
G03X1127953Y15000I0J15000D01*
G01Y493259D01*
G01X1045276Y25827D02*
G03X1037402I-3937J0D01*
G01X1045276Y0D02*
Y25827D01*
G01X1037402Y56535D02*
G03X1045276I3937J0D01*
G01D02*
Y284882D01*
G01X1004041Y172066D02*
G03I-984J0D01*
G01X1003940Y163371D02*
G03X992134I-5903J0D01*
G01X1003942D02*
G03X992131I-5905J0D01*
G01X1005911D02*
G03X990163I-7874J0D01*
G01X1003940Y159238D02*
G03X1005066Y156482I3937J0D01*
G01X991008D02*
G03X1005066I7029J-6890D01*
G01X988982Y163371D02*
G03I-985J0D01*
G01X994001Y172066D02*
G03I-984J0D01*
G01X990327Y168391D02*
G03I-984J0D01*
G01X991008Y156482D02*
G03X992134Y159238I-2811J2757D01*
G01X1003942Y163371D02*
Y161009D01*
G01X1003940Y159238D02*
Y163371D01*
G01X992134D02*
Y159238D01*
G01X992131Y161009D02*
Y163371D01*
G01X990163D02*
Y161009D01*
G01X1003942D02*
X1011816D01*
G01X1007715Y168391D02*
G03I-984J0D01*
G01X1009060Y163371D02*
G03I-984J0D01*
G01X1013785Y149592D02*
Y163371D01*
G01Y149592D02*
Y163371D01*
G01Y149592D02*
Y163371D01*
G01X1011816Y161009D02*
Y163371D01*
G01X1005911Y161009D02*
Y163371D01*
G01X1037402Y315591D02*
G03X1045276I3937J0D01*
G01Y284882D02*
G03X1037402I-3937J0D01*
G01X1045276Y315591D02*
Y543937D01*
G01D02*
G03X1037402I-3937J0D01*
G01Y574646D02*
G03X1045276I3937J0D01*
G01D02*
Y802992D01*
G01X1004041Y695688D02*
G03I-984J0D01*
G01X1003940Y686993D02*
G03X992134I-5903J0D01*
G01X1003942D02*
G03X992131I-5905J0D01*
G01X1005911D02*
G03X990163I-7874J0D01*
G01X1003940Y682860D02*
G03X1005066Y680104I3937J0D01*
G01X991008D02*
G03X1005066I7029J-6890D01*
G01X988982Y686993D02*
G03I-985J0D01*
G01X994001Y695688D02*
G03I-984J0D01*
G01X990327Y692013D02*
G03I-984J0D01*
G01X991008Y680104D02*
G03X992134Y682860I-2811J2757D01*
G01X1003942Y686993D02*
Y684631D01*
G01X1003940Y682860D02*
Y686993D01*
G01X992134D02*
Y682860D01*
G01X992131Y684631D02*
Y686993D01*
G01X990163D02*
Y684631D01*
G01X1003942D02*
X1011816D01*
G01X1007715Y692013D02*
G03I-984J0D01*
G01X1009060Y686993D02*
G03I-984J0D01*
G01X1013785Y673214D02*
Y686993D01*
G01Y673214D02*
Y686993D01*
G01Y673214D02*
Y686993D01*
G01X1011816Y684631D02*
Y686993D01*
G01X1005911Y684631D02*
Y686993D01*
G01X1037402Y833701D02*
G03X1045276I3937J0D01*
G01Y802992D02*
G03X1037402I-3937J0D01*
G01X1045276Y833701D02*
Y1062047D01*
G01X991008Y1075773D02*
G03X1005066I7029J-6890D01*
G01X1045276Y1062047D02*
G03X1037402I-3937J0D01*
G01X1003940Y1082663D02*
G03X992134I-5903J0D01*
G01X1003942D02*
G03X992131I-5905J0D01*
G01X1005911D02*
G03X990163I-7874J0D01*
G01X1003940Y1078529D02*
G03X1005066Y1075773I3937J0D01*
G01X988982Y1082663D02*
G03I-985J0D01*
G01X991008Y1075773D02*
G03X992134Y1078529I-2811J2757D01*
G01X1003942Y1082663D02*
Y1080300D01*
G01X1003940Y1078529D02*
Y1082663D01*
G01X992134D02*
Y1078529D01*
G01X992131Y1080300D02*
Y1082663D01*
G01X990163D02*
Y1080300D01*
G01X1003942D02*
X1011816D01*
G01X1004041Y1091357D02*
G03I-984J0D01*
G01X994001D02*
G03I-984J0D01*
G01X990327Y1087682D02*
G03I-984J0D01*
G01X1009060Y1082663D02*
G03I-984J0D01*
G01X1013785Y1068883D02*
Y1082663D01*
G01Y1068883D02*
Y1082663D01*
G01Y1068883D02*
Y1082663D01*
G01X1011816Y1080300D02*
Y1082663D01*
G01X1005911Y1080300D02*
Y1082663D01*
G01X1007715Y1087682D02*
G03I-984J0D01*
G01X1037402Y1092756D02*
G03X1045276I3937J0D01*
G01D02*
Y1321102D01*
G01D02*
G03X1037402I-3937J0D01*
G01Y1351811D02*
G03X1045276I3937J0D01*
G01D02*
Y1377638D01*
G01X991742Y1429857D02*
X991994Y1429447D01*
G01X992161Y1429939D02*
X992329Y1429693D01*
G01X991994Y1429447D02*
X992329Y1429201D01*
G01Y1429693D02*
X992580Y1429530D01*
G01X991658Y1430268D02*
X991742Y1429857D01*
G01X992077Y1430185D02*
X992161Y1429939D01*
G01X992329Y1429201D02*
X992747Y1429037D01*
G01X992580Y1429530D02*
X992831Y1429447D01*
G01X994674Y1429611D02*
Y1429201D01*
G01X992831Y1429447D02*
X993082D01*
G01X992747Y1429037D02*
X993166D01*
G01X995177Y1430268D02*
X995093Y1430022D01*
G01X993669Y1429939D02*
X993753Y1430185D01*
G01X995512Y1429939D02*
X995595Y1430350D01*
G01X994088Y1429857D02*
X994171Y1430268D01*
G01X995260Y1429530D02*
X995512Y1429939D01*
G01X993836Y1429447D02*
X994088Y1429857D01*
G01X995093Y1430022D02*
X994925Y1429776D01*
G01X993501Y1429693D02*
X993669Y1429939D01*
G01X993585Y1429201D02*
X993836Y1429447D01*
G01X993334Y1429530D02*
X993501Y1429693D01*
G01X994925Y1429283D02*
X995260Y1429530D01*
G01X994925Y1429776D02*
X994674Y1429611D01*
G01Y1429201D02*
X994925Y1429283D01*
G01X993082Y1429447D02*
X993334Y1429530D01*
G01X993166Y1429037D02*
X993585Y1429201D01*
G01X1078504Y1429213D02*
X1043858D01*
G01Y1685433D02*
Y1429213D01*
G01X1010394Y1430787D02*
G03X1008425Y1428819I-1J-1968D01*
G01X1083228Y1421339D02*
X1037953D01*
G01X1083228Y1423307D02*
X1037953D01*
G01X1012362Y1401260D02*
Y1430787D01*
G01X1037953D02*
Y1403228D01*
G01X1030906Y1416023D02*
G03I-7678J0D01*
G01X1030512D02*
G03I-7284J0D01*
G01D02*
G03I-7284J0D01*
G01X1035984Y1401260D02*
G03X1037953Y1403228I0J1969D01*
G01X1010394Y1401260D02*
X1035984D01*
G01X1008425Y1428819D02*
Y1403228D01*
G01D02*
G03X1010394Y1401260I1968J0D01*
G01X1045276Y1377638D02*
X1112953D01*
G02X1127953Y1362638I0J-15000D01*
G01Y501133D01*
G01X995344Y1435107D02*
X995512Y1434779D01*
G01X992161Y1433467D02*
X992245Y1433302D01*
G01X991910Y1433138D02*
X991742Y1433467D01*
G01X995512Y1431088D02*
X995260Y1431498D01*
G01X995093Y1434697D02*
X994925Y1434943D01*
G01Y1431252D02*
X995093Y1431006D01*
G01X994088Y1431088D02*
X993753Y1431580D01*
G01X993669Y1431006D02*
X993501Y1431252D01*
G01X992077Y1432892D02*
X991910Y1433138D01*
G01X993753Y1436583D02*
X993501Y1436911D01*
G01X993920Y1432974D02*
X993669Y1433302D01*
G01X994004Y1436993D02*
X994171Y1436829D01*
G01X995009Y1435435D02*
X995344Y1435107D01*
G01X994004Y1433467D02*
X994171Y1433302D01*
G01X992245D02*
X992412Y1433138D01*
G01X993501Y1431252D02*
X993334Y1431416D01*
G01X994088Y1436337D02*
X993753Y1436583D01*
G01X995260Y1431498D02*
X994925Y1431744D01*
G01Y1434943D02*
X994674Y1435107D01*
G01X994171Y1432810D02*
X993920Y1432974D01*
G01X994674Y1431416D02*
X994925Y1431252D01*
G01X992329Y1432728D02*
X992077Y1432892D01*
G01X995177Y1434287D02*
X995093Y1434697D01*
G01X995595Y1430678D02*
X995512Y1431088D01*
G01X993501Y1436911D02*
X993418Y1437321D01*
G01X994171Y1430678D02*
X994088Y1431088D01*
G01X992077Y1433876D02*
X992161Y1433467D01*
G01X991742D02*
X991658Y1433794D01*
G01X993920Y1437239D02*
X994004Y1436993D01*
G01X995093Y1431006D02*
X995177Y1430760D01*
G01X993836Y1433959D02*
X994004Y1433467D01*
G01X993753Y1430760D02*
X993669Y1431006D01*
G01X994171Y1433302D02*
X994507Y1433138D01*
G01X992412D02*
X992580Y1433056D01*
G01X994925Y1431744D02*
X994507Y1431908D01*
G01X994171Y1436829D02*
X994423Y1436747D01*
G01X994339Y1436255D02*
X994088Y1436337D01*
G01X992580Y1432646D02*
X992329Y1432728D01*
G01X994423Y1431498D02*
X994674Y1431416D01*
G01X993334D02*
X993082Y1431498D01*
G01X995512Y1434779D02*
X995595Y1434205D01*
G01X994674Y1435517D02*
X995009Y1435435D01*
G01X994507Y1432728D02*
X994171Y1432810D01*
G01X993920Y1431580D02*
X994423Y1431498D01*
G01X994507Y1431908D02*
X993920Y1431990D01*
G01X995595Y1430350D02*
Y1430678D01*
G01Y1434205D02*
Y1434041D01*
G01Y1439290D02*
Y1437321D01*
G01X995177Y1437239D02*
Y1438798D01*
G01Y1433959D02*
Y1434287D01*
G01Y1430760D02*
Y1430268D01*
G01X994674Y1435107D02*
Y1435517D01*
G01X994171Y1430268D02*
Y1430678D01*
G01X993920Y1438798D02*
Y1437239D01*
G01X993836Y1434287D02*
Y1433959D01*
G01X993753Y1430185D02*
Y1430760D01*
G01X993501Y1433959D02*
Y1434287D01*
G01X993418Y1437321D02*
Y1438798D01*
G01X992580Y1435599D02*
Y1435189D01*
G01X992077Y1430760D02*
Y1430185D01*
G01Y1434369D02*
Y1433876D01*
G01X991658Y1438798D02*
Y1439290D01*
G01Y1433794D02*
Y1434451D01*
G01Y1430678D02*
Y1430268D01*
G01Y1439290D02*
X995595D01*
G01X995177Y1438798D02*
X993920D01*
G01X993418D02*
X991658D01*
G01X994423Y1436747D02*
X994674D01*
G01Y1436255D02*
X994339D01*
G01X993501Y1434287D02*
X993836D01*
G01X994507Y1433138D02*
X994674D01*
G01X992580Y1433056D02*
X992915D01*
G01X994674Y1432728D02*
X994507D01*
G01X992915Y1432646D02*
X992580D01*
G01X993920Y1431990D02*
X993334D01*
G01X993753Y1431580D02*
X993920D01*
G01X993082Y1431498D02*
X992831D01*
G01X993418Y1433467D02*
X993501Y1433959D01*
G01X995595Y1434041D02*
X995512Y1433467D01*
G01X993334Y1431990D02*
X992747Y1431908D01*
G01X991658Y1434451D02*
X991742Y1434779D01*
G01X995093Y1433548D02*
X995177Y1433959D01*
G01X995595Y1437321D02*
X995512Y1436911D01*
G01X991742Y1431088D02*
X991658Y1430678D01*
G01X992161Y1434779D02*
X992077Y1434369D01*
G01X993250Y1432728D02*
X992915Y1432646D01*
G01X995009Y1432810D02*
X994674Y1432728D01*
G01X993669Y1433302D02*
X993501Y1432892D01*
G01X995093Y1436993D02*
X995177Y1437239D01*
G01X992161Y1431006D02*
X992077Y1430760D01*
G01X991994Y1431498D02*
X991742Y1431088D01*
G01X995512Y1433467D02*
X995344Y1433138D01*
G01X992245Y1434943D02*
X992161Y1434779D01*
G01X991742D02*
X991910Y1435107D01*
G01X995512Y1436911D02*
X995260Y1436583D01*
G01X994925Y1433302D02*
X995093Y1433548D01*
G01X992329Y1431252D02*
X992161Y1431006D01*
G01X993250Y1433220D02*
X993418Y1433467D01*
G01X991910Y1435107D02*
X992077Y1435353D01*
G01X995344Y1433138D02*
X995009Y1432810D01*
G01X994925Y1436829D02*
X995093Y1436993D01*
G01X992412Y1435107D02*
X992245Y1434943D01*
G01X992329Y1431744D02*
X991994Y1431498D01*
G01X992580Y1431416D02*
X992329Y1431252D01*
G01X994674Y1433138D02*
X994925Y1433302D01*
G01X993501Y1432892D02*
X993250Y1432728D01*
G01X992077Y1435353D02*
X992329Y1435517D01*
G01X995260Y1436583D02*
X994925Y1436337D01*
G01X992915Y1433056D02*
X993250Y1433220D01*
G01X992580Y1435189D02*
X992412Y1435107D01*
G01X992831Y1431498D02*
X992580Y1431416D01*
G01X994925Y1436337D02*
X994674Y1436255D01*
G01X992329Y1435517D02*
X992580Y1435599D01*
G01X994674Y1436747D02*
X994925Y1436829D01*
G01X992747Y1431908D02*
X992329Y1431744D01*
G01X1040889Y1463658D02*
X1040810Y1463629D01*
G01X1040889Y1453658D02*
X1040810Y1453629D01*
G01X1040889Y1443658D02*
X1040810Y1443629D01*
G01X1041090Y1463670D02*
X1040978Y1463636D01*
G01X1041090Y1453670D02*
X1040978Y1453636D01*
G01X1040812Y1463630D02*
X1040737Y1463590D01*
G01X1040980Y1463637D02*
X1040876Y1463581D01*
G01X1040812Y1453630D02*
X1040737Y1453590D01*
G01X1040980Y1453637D02*
X1040876Y1453581D01*
G01X1040812Y1443630D02*
X1040737Y1443590D01*
G01X1040980Y1443637D02*
X1040876Y1443581D01*
G01X1040878Y1463582D02*
X1040787Y1463508D01*
G01X1040878Y1453582D02*
X1040787Y1453508D01*
G01X1040878Y1443582D02*
X1040787Y1443508D01*
G01X1040739Y1463591D02*
X1040671Y1463541D01*
G01X1040739Y1453591D02*
X1040671Y1453541D01*
G01X1040739Y1443591D02*
X1040671Y1443541D01*
G01X1023622Y1433287D02*
X1023228Y1432894D01*
G01X1040672Y1463543D02*
X1040612Y1463484D01*
G01X1040672Y1453543D02*
X1040612Y1453484D01*
G01X1040672Y1443543D02*
X1040612Y1443484D01*
G01X1040615Y1463484D02*
X1040531Y1463366D01*
X1040481Y1463234D01*
X1040464Y1463091D01*
G01X1040713Y1463417D02*
X1040787Y1463508D01*
G01X1040713Y1453417D02*
X1040787Y1453508D01*
G01X1040713Y1443417D02*
X1040787Y1443508D01*
G01X1040615Y1453484D02*
X1040531Y1453366D01*
X1040481Y1453234D01*
X1040464Y1453091D01*
G01X1040615Y1443484D02*
X1040531Y1443366D01*
X1040481Y1443234D01*
X1040464Y1443091D01*
G01X1040714Y1463419D02*
X1040659Y1463315D01*
G01X1040714Y1453419D02*
X1040659Y1453315D01*
G01X1040714Y1443419D02*
X1040659Y1443315D01*
G01X1040660Y1463317D02*
X1040626Y1463205D01*
G01X1040660Y1453317D02*
X1040626Y1453205D01*
G01X1040660Y1443317D02*
X1040626Y1443205D01*
G01X1040969Y1443675D02*
X1040887Y1443657D01*
G01X1040969Y1453675D02*
X1040887Y1453657D01*
G01X1040969Y1463675D02*
X1040887Y1463657D01*
G01X1039921Y1433681D02*
X1035984Y1433287D01*
G01X1041087Y1443669D02*
X1041204Y1443681D01*
G01X1041087Y1453669D02*
X1041204Y1453681D01*
G01X1041087Y1463669D02*
X1041204Y1463681D01*
G01Y1443681D02*
X1041090Y1443670D01*
X1040978Y1443636D01*
G01X1040967Y1443675D02*
X1041052Y1443681D01*
G01X1040967Y1453675D02*
X1041052Y1453681D01*
G01X1040967Y1463675D02*
X1041052Y1463681D01*
G01X1037953Y1430787D02*
X1025197D01*
G01X1083228Y1433248D02*
X1043858D01*
G01Y1433287D02*
X1023622D01*
G01X1076791Y1433681D02*
X1023228D01*
G01X1043858Y1434449D02*
X1023228D01*
G01X1039724Y1437402D02*
X1023228D01*
G01X1043858Y1439370D02*
X1040709D01*
G01X1023228D02*
X1034858D01*
G01X1076791Y1440965D02*
X1041052D01*
G01X1043858Y1441161D02*
X1023228D01*
G01X1083228Y1441398D02*
X1041102D01*
G01X1040615Y1441555D02*
X1040464D01*
G01X1040615Y1443091D02*
X1040464D01*
G01X1083228Y1443248D02*
X1041102D01*
G01X1043858Y1443484D02*
X1023228D01*
G01X1076791Y1443681D02*
X1041052D01*
G01X1043858Y1445276D02*
X1040709D01*
G01X1023228D02*
X1034858D01*
G01X1039724Y1447244D02*
X1023228D01*
G01X1043858Y1450197D02*
X1023228D01*
G01X1076791Y1450965D02*
X1041052D01*
G01X1043858Y1451161D02*
X1023228D01*
G01X1083228Y1451398D02*
X1041102D01*
G01X1040615Y1451555D02*
X1040464D01*
G01X1040615Y1453091D02*
X1040464D01*
G01X1083228Y1453248D02*
X1041102D01*
G01X1043858Y1453484D02*
X1023228D01*
G01X1076791Y1453681D02*
X1041052D01*
G01X1043858Y1454449D02*
X1023228D01*
G01X1039724Y1457402D02*
X1023228D01*
G01X1043858Y1459370D02*
X1040709D01*
G01X1023228D02*
X1034858D01*
G01X1076791Y1460965D02*
X1041052D01*
G01X1043858Y1461161D02*
X1023228D01*
G01X1083228Y1461398D02*
X1041102D01*
G01X1040615Y1461555D02*
X1040464D01*
G01X1040615Y1463091D02*
X1040464D01*
G01X1083228Y1463248D02*
X1041102D01*
G01X1043858Y1463484D02*
X1023228D01*
G01X1076791Y1463681D02*
X1041052D01*
G01X1014457Y1469449D02*
Y1465197D01*
G01Y1459449D02*
Y1455197D01*
G01Y1449449D02*
Y1445197D01*
G01Y1439449D02*
Y1435197D01*
G01X1015060Y1469449D02*
Y1465197D01*
G01Y1459449D02*
Y1455197D01*
G01Y1449449D02*
Y1445197D01*
G01Y1439449D02*
Y1435197D01*
G01X1015663Y1469449D02*
Y1465197D01*
G01Y1459449D02*
Y1455197D01*
G01Y1449449D02*
Y1445197D01*
G01Y1439449D02*
Y1435197D01*
G01X1019600Y1469449D02*
Y1465197D01*
G01Y1459449D02*
Y1455197D01*
G01Y1449449D02*
Y1445197D01*
G01Y1439449D02*
Y1435197D01*
G01X1020781Y1469449D02*
Y1465197D01*
G01Y1459449D02*
Y1455197D01*
G01Y1449449D02*
Y1445197D01*
G01Y1439449D02*
Y1435197D01*
G01X1021962Y1469449D02*
Y1465197D01*
G01Y1459449D02*
Y1455197D01*
G01Y1449449D02*
Y1445197D01*
G01Y1439449D02*
Y1435197D01*
G01X1023228Y1612165D02*
Y1430787D01*
G01Y1434291D02*
Y1610886D01*
G01X1023622Y1433287D02*
Y1434449D01*
G01X1024409Y1469449D02*
Y1465197D01*
G01Y1459449D02*
Y1455197D01*
G01Y1449449D02*
Y1445197D01*
G01Y1439449D02*
Y1435197D01*
G01X1025591Y1469449D02*
Y1465197D01*
G01Y1459449D02*
Y1455197D01*
G01Y1449449D02*
Y1445197D01*
G01Y1439449D02*
Y1435197D01*
G01X1026378Y1465197D02*
Y1459449D01*
G01Y1455197D02*
Y1449449D01*
G01Y1445197D02*
Y1439449D01*
G01Y1435197D02*
Y1433287D01*
G01X1027165Y1463484D02*
Y1461161D01*
G01Y1453484D02*
Y1451161D01*
G01Y1443484D02*
Y1441161D01*
G01X1029134Y1465276D02*
Y1459370D01*
G01Y1445276D02*
Y1439370D01*
G01X1031102Y1466260D02*
Y1458386D01*
G01Y1446260D02*
Y1438386D01*
G01X1031496Y1465276D02*
Y1459370D01*
G01Y1445276D02*
Y1439370D01*
G01X1032299Y1465276D02*
Y1459370D01*
G01Y1439370D02*
Y1445276D01*
G01X1034055Y1465276D02*
Y1459370D01*
G01Y1445276D02*
Y1439370D01*
G01X1034858Y1465276D02*
Y1459370D01*
G01Y1445276D02*
Y1439370D01*
G01X1039921Y1470965D02*
Y1433681D01*
G01X1040048Y1470965D02*
Y1463484D01*
G01Y1461161D02*
Y1453484D01*
G01Y1451161D02*
Y1443484D01*
G01Y1441161D02*
Y1433681D01*
G01X1040201Y1470965D02*
Y1433681D01*
G01X1040464Y1463091D02*
Y1461555D01*
G01Y1453091D02*
Y1451555D01*
G01Y1443091D02*
Y1441555D01*
G01X1040615Y1463091D02*
Y1461555D01*
G01Y1453091D02*
Y1451555D01*
G01Y1441555D02*
Y1443091D01*
G01X1040709Y1466260D02*
Y1458386D01*
G01Y1452854D02*
Y1451791D01*
G01Y1446260D02*
Y1438386D01*
G01X1044646Y1453248D02*
Y1451398D01*
G01Y1441398D02*
Y1443248D01*
G01Y1461398D02*
Y1463248D01*
G01X1040626Y1463207D02*
X1040615Y1463091D01*
G01X1040626Y1453207D02*
X1040615Y1453091D01*
G01X1040626Y1443207D02*
X1040615Y1443091D01*
G01X1040967Y1450970D02*
X1041052Y1450965D01*
G01X1040967Y1460970D02*
X1041052Y1460965D01*
G01X1041087Y1440976D02*
X1041204Y1440965D01*
G01X1041087Y1450976D02*
X1041204Y1450965D01*
G01X1041087Y1460976D02*
X1041204Y1460965D01*
G01X1040969Y1440970D02*
X1040889Y1440987D01*
G01X1040626Y1441438D02*
X1040615Y1441555D01*
G01X1040626Y1451438D02*
X1040615Y1451555D01*
G01X1040626Y1461438D02*
X1040615Y1461555D01*
G01X1040887Y1440988D02*
X1040967Y1440970D01*
X1041052Y1440965D01*
G01X1040887Y1450988D02*
X1040969Y1450970D01*
G01X1040887Y1460988D02*
X1040969Y1460970D01*
G01X1040978Y1441010D02*
X1041090Y1440976D01*
G01X1040978Y1451010D02*
X1041090Y1450976D01*
G01X1040978Y1461010D02*
X1041090Y1460976D01*
G01X1040810Y1441016D02*
X1040889Y1440987D01*
G01X1040810Y1451016D02*
X1040889Y1450987D01*
G01X1040810Y1461016D02*
X1040889Y1460987D01*
G01X1040464Y1441555D02*
X1040481Y1441411D01*
X1040531Y1441280D01*
X1040615Y1441161D01*
G01X1040464Y1451555D02*
X1040481Y1451411D01*
X1040531Y1451280D01*
X1040615Y1451161D01*
G01X1040464Y1461555D02*
X1040481Y1461411D01*
X1040531Y1461280D01*
X1040615Y1461161D01*
G01X1040737Y1441055D02*
X1040812Y1441015D01*
G01X1040876Y1441064D02*
X1040980Y1441009D01*
G01X1040737Y1451055D02*
X1040812Y1451015D01*
G01X1040876Y1451064D02*
X1040980Y1451009D01*
G01X1040737Y1461055D02*
X1040812Y1461015D01*
G01X1040876Y1461064D02*
X1040980Y1461009D01*
G01X1040671Y1441104D02*
X1040739Y1441054D01*
G01X1040671Y1451104D02*
X1040739Y1451054D01*
G01X1040671Y1461104D02*
X1040739Y1461054D01*
G01X1040878Y1441063D02*
X1040787Y1441137D01*
G01X1040878Y1451063D02*
X1040787Y1451137D01*
G01X1040878Y1461063D02*
X1040787Y1461137D01*
G01X1040672Y1441103D02*
X1040612Y1441161D01*
G01X1040672Y1451103D02*
X1040612Y1451161D01*
G01X1023228Y1432756D02*
X1025197Y1430787D01*
G01X1040713Y1441228D02*
X1040787Y1441137D01*
G01X1040713Y1451228D02*
X1040787Y1451137D01*
G01X1040659Y1441330D02*
X1040714Y1441226D01*
G01X1040659Y1451330D02*
X1040714Y1451226D01*
G01X1040659Y1461330D02*
X1040714Y1461226D01*
G01X1040626Y1441440D02*
X1040660Y1441328D01*
G01X1040626Y1451440D02*
X1040660Y1451328D01*
G01X1040626Y1461440D02*
X1040660Y1461328D01*
G01X1040672Y1461103D02*
X1040612Y1461161D01*
G01X1040713Y1461228D02*
X1040787Y1461137D01*
G01X1031102Y1438386D02*
G03X1032087Y1437402I984J0D01*
G01Y1447244D02*
G03X1031102Y1446260I-1J-984D01*
G01Y1458386D02*
G03X1032087Y1457402I984J0D01*
G01X1040709Y1446260D02*
G03X1039724Y1447244I-984J0D01*
G01Y1437402D02*
G03X1040709Y1438386I1J984D01*
G01X1041102Y1443248D02*
G03X1040709Y1442854I1J-394D01*
G01Y1441791D02*
G03X1041102Y1441398I393J0D01*
G01X1039724Y1457402D02*
G03X1040709Y1458386I1J984D01*
G01Y1451791D02*
G03X1041102Y1451398I393J0D01*
G01Y1453248D02*
G03X1040709Y1452854I1J-394D01*
G01Y1461791D02*
G03X1041102Y1461398I393J0D01*
G01Y1463248D02*
G03X1040709Y1462854I1J-394D01*
G01X997340Y1459430D02*
X997178Y1459373D01*
G01X998521Y1459430D02*
X998359Y1459373D01*
G01X997340Y1449430D02*
X997178Y1449373D01*
G01X998521Y1449430D02*
X998359Y1449373D01*
G01X997340Y1439430D02*
X997178Y1439373D01*
G01X998521Y1439430D02*
X998359Y1439373D01*
G01X997181Y1459374D02*
X997031Y1459282D01*
G01X998362Y1459374D02*
X998213Y1459282D01*
G01X997181Y1449374D02*
X997031Y1449282D01*
G01X998362Y1449374D02*
X998213Y1449282D01*
G01X997181Y1439374D02*
X997031Y1439282D01*
G01X998362Y1439374D02*
X998213Y1439282D01*
G01X997034Y1459284D02*
X996903Y1459160D01*
G01X998215Y1459284D02*
X998084Y1459160D01*
G01X997034Y1449284D02*
X996903Y1449160D01*
G01X998215Y1449284D02*
X998084Y1449160D01*
G01X997034Y1439284D02*
X996903Y1439160D01*
G01X998215Y1439284D02*
X998084Y1439160D01*
G01X996796Y1459009D02*
X996903Y1459160D01*
G01X997977Y1459009D02*
X998084Y1459160D01*
G01X996796Y1449009D02*
X996903Y1449160D01*
G01X997977Y1449009D02*
X998084Y1449160D01*
G01X996796Y1439009D02*
X996903Y1439160D01*
G01X997977Y1439009D02*
X998084Y1439160D01*
G01X996798Y1459012D02*
X996718Y1458839D01*
G01X997979Y1459012D02*
X997899Y1458839D01*
G01X996798Y1449012D02*
X996718Y1448839D01*
G01X997979Y1449012D02*
X997899Y1448839D01*
G01X996798Y1439012D02*
X996718Y1438839D01*
G01X997979Y1439012D02*
X997899Y1438839D01*
G01X996719Y1458843D02*
X996670Y1458656D01*
G01X997900Y1458843D02*
X997851Y1458656D01*
G01X996719Y1448843D02*
X996670Y1448656D01*
G01X997900Y1448843D02*
X997851Y1448656D01*
G01X996719Y1438843D02*
X996670Y1438656D01*
G01X997900Y1438843D02*
X997851Y1438656D01*
G01X998519Y1439429D02*
X998687Y1439449D01*
G01X997337Y1439429D02*
X997506Y1439449D01*
G01X996670Y1458659D02*
X996654Y1458465D01*
G01X996670Y1448659D02*
X996654Y1448465D01*
G01X997851Y1458659D02*
X997835Y1458465D01*
G01X996670Y1438659D02*
X996654Y1438465D01*
G01X997851Y1448659D02*
X997835Y1448465D01*
G01X997851Y1438659D02*
X997835Y1438465D01*
G01X998519Y1449429D02*
X998687Y1449449D01*
G01X997337Y1449429D02*
X997506Y1449449D01*
G01X998519Y1459429D02*
X998687Y1459449D01*
G01X997337Y1459429D02*
X997506Y1459449D01*
G01X1023228Y1430787D02*
X1010394D01*
G01X1026378Y1435197D02*
X997506D01*
G01X997835Y1436181D02*
X996654D01*
G01X997835Y1438465D02*
X996654D01*
G01X1026378Y1439449D02*
X997506D01*
G01X1026378Y1445197D02*
X997506D01*
G01X997835Y1446181D02*
X996654D01*
G01X997835Y1448465D02*
X996654D01*
G01X1026378Y1449449D02*
X997506D01*
G01X1026378Y1455197D02*
X997506D01*
G01X997835Y1456181D02*
X996654D01*
G01X997835Y1458465D02*
X996654D01*
G01X1026378Y1459449D02*
X997506D01*
G01X1026378Y1465197D02*
X997506D01*
G01X996670Y1435987D02*
X996654Y1436181D01*
G01X996670Y1445987D02*
X996654Y1446181D01*
G01X997851Y1435987D02*
X997835Y1436181D01*
G01X996670Y1455987D02*
X996654Y1456181D01*
G01X997851Y1445987D02*
X997835Y1446181D01*
G01X997851Y1455987D02*
X997835Y1456181D01*
G01X996654Y1458465D02*
Y1456181D01*
G01Y1448465D02*
Y1446181D01*
G01Y1438465D02*
Y1436181D01*
G01X997835Y1458465D02*
Y1456181D01*
G01Y1448465D02*
Y1446181D01*
G01Y1438465D02*
Y1436181D01*
G01X1002362Y1469449D02*
Y1465197D01*
G01Y1459449D02*
Y1455197D01*
G01Y1449449D02*
Y1445197D01*
G01Y1439449D02*
Y1435197D01*
G01X1003543Y1469449D02*
Y1465197D01*
G01Y1459449D02*
Y1455197D01*
G01Y1449449D02*
Y1445197D01*
G01Y1439449D02*
Y1435197D01*
G01X1004733Y1469449D02*
Y1465197D01*
G01Y1459449D02*
Y1455197D01*
G01Y1449449D02*
Y1445197D01*
G01Y1439449D02*
Y1435197D01*
G01X1005335Y1469449D02*
Y1465197D01*
G01Y1459449D02*
Y1455197D01*
G01Y1449449D02*
Y1445197D01*
G01Y1439449D02*
Y1435197D01*
G01X997337Y1435216D02*
X997506Y1435197D01*
G01X998519Y1435216D02*
X998687Y1435197D01*
G01X997337Y1445216D02*
X997506Y1445197D01*
G01X998519Y1445216D02*
X998687Y1445197D01*
G01X997337Y1455216D02*
X997506Y1455197D01*
G01X998519Y1455216D02*
X998687Y1455197D01*
G01X997337Y1465216D02*
X997506Y1465197D01*
G01X998519Y1465216D02*
X998687Y1465197D01*
G01X997178Y1435272D02*
X997340Y1435215D01*
G01X998359Y1435272D02*
X998521Y1435215D01*
G01X997178Y1445272D02*
X997340Y1445215D01*
G01X998359Y1445272D02*
X998521Y1445215D01*
G01X997178Y1455272D02*
X997340Y1455215D01*
G01X998359Y1455272D02*
X998521Y1455215D01*
G01X997178Y1465272D02*
X997340Y1465215D01*
G01X998359Y1465272D02*
X998521Y1465215D01*
G01X996670Y1435990D02*
X996719Y1435803D01*
G01X997851Y1435990D02*
X997900Y1435803D01*
G01X996670Y1445990D02*
X996719Y1445803D01*
G01X997851Y1445990D02*
X997900Y1445803D01*
G01X996670Y1455990D02*
X996719Y1455803D01*
G01X997851Y1455990D02*
X997900Y1455803D01*
G01X997031Y1435363D02*
X997181Y1435271D01*
G01X998213Y1435363D02*
X998362Y1435271D01*
G01X997031Y1445363D02*
X997181Y1445271D01*
G01X998213Y1445363D02*
X998362Y1445271D01*
G01X997031Y1455363D02*
X997181Y1455271D01*
G01X998213Y1455363D02*
X998362Y1455271D01*
G01X997034Y1435361D02*
X996903Y1435485D01*
G01X998215Y1435361D02*
X998084Y1435485D01*
G01X997034Y1445361D02*
X996903Y1445485D01*
G01X998215Y1445361D02*
X998084Y1445485D01*
G01X997034Y1455361D02*
X996903Y1455485D01*
G01X998215Y1455361D02*
X998084Y1455485D01*
G01X996796Y1435636D02*
X996903Y1435485D01*
G01X997977Y1435636D02*
X998084Y1435485D01*
G01X996796Y1445636D02*
X996903Y1445485D01*
G01X997977Y1445636D02*
X998084Y1445485D01*
G01X996796Y1455636D02*
X996903Y1455485D01*
G01X997977Y1455636D02*
X998084Y1455485D01*
G01X996718Y1435806D02*
X996798Y1435633D01*
G01X997899Y1435806D02*
X997979Y1435633D01*
G01X996718Y1445806D02*
X996798Y1445633D01*
G01X997899Y1445806D02*
X997979Y1445633D01*
G01X996718Y1455806D02*
X996798Y1455633D01*
G01X997899Y1455806D02*
X997979Y1455633D01*
G01X1041090Y1493670D02*
X1040978Y1493636D01*
G01X1040889Y1493658D02*
X1040810Y1493629D01*
G01X1040812Y1493630D02*
X1040737Y1493590D01*
G01X1040980Y1493637D02*
X1040876Y1493581D01*
G01X1040739Y1493591D02*
X1040671Y1493541D01*
G01X1040878Y1493582D02*
X1040787Y1493508D01*
G01X1040672Y1493543D02*
X1040612Y1493484D01*
G01X1040713Y1493417D02*
X1040787Y1493508D01*
G01X1040714Y1493419D02*
X1040659Y1493315D01*
G01X1040660Y1493317D02*
X1040626Y1493205D01*
G01X1040969Y1493675D02*
X1040887Y1493657D01*
G01X1040464Y1493091D02*
X1040481Y1493234D01*
X1040531Y1493366D01*
X1040615Y1493484D01*
G01X1040464Y1493091D02*
X1040482Y1493234D01*
X1040532Y1493365D01*
X1040615Y1493484D01*
G01X1041087Y1493669D02*
X1041204Y1493681D01*
G01X1040967Y1493675D02*
X1041052Y1493681D01*
G01X1014457Y1499449D02*
Y1495197D01*
G01X1015060Y1499449D02*
Y1495197D01*
G01X1015663Y1499449D02*
Y1495197D01*
G01X1019600Y1499449D02*
Y1495197D01*
G01X1020781Y1499449D02*
Y1495197D01*
G01X1021962Y1499449D02*
Y1495197D01*
G01X1024409Y1499449D02*
Y1495197D01*
G01X1025591Y1499449D02*
Y1495197D01*
G01X1026378Y1505197D02*
Y1499449D01*
G01Y1495197D02*
Y1489449D01*
G01X1027165Y1503484D02*
Y1501161D01*
G01Y1493484D02*
Y1491161D01*
G01X1029134Y1505276D02*
Y1499370D01*
G01X1031102Y1506260D02*
Y1498386D01*
G01X1031496Y1505276D02*
Y1499370D01*
G01X1032299Y1505276D02*
Y1499370D01*
G01X1034055Y1505276D02*
Y1499370D01*
G01X1034858Y1505276D02*
Y1499370D01*
G01X1040048Y1501161D02*
Y1493484D01*
G01X1040464Y1503091D02*
Y1501555D01*
G01Y1491555D02*
Y1493091D01*
G01X1040615Y1503091D02*
Y1501555D01*
G01Y1493091D02*
Y1491555D01*
G01X1040709Y1506260D02*
Y1498386D01*
G01Y1492854D02*
Y1491791D01*
G01X1044646Y1493248D02*
Y1491398D01*
G01Y1501398D02*
Y1503248D01*
G01X1040626Y1493207D02*
X1040615Y1493091D01*
G01X1043858Y1485276D02*
X1040709D01*
G01X1023228D02*
X1034858D01*
G01X1039724Y1487244D02*
X1023228D01*
G01X1043858Y1490197D02*
X1023228D01*
G01X1076791Y1490965D02*
X1041052D01*
G01X1043858Y1491161D02*
X1023228D01*
G01X1083228Y1491398D02*
X1041102D01*
G01X1040615Y1491555D02*
X1040464D01*
G01X1040615Y1493091D02*
X1040464D01*
G01X1083228Y1493248D02*
X1041102D01*
G01X1043858Y1493484D02*
X1023228D01*
G01X1076791Y1493681D02*
X1041052D01*
G01X1043858Y1494449D02*
X1023228D01*
G01X1039724Y1497402D02*
X1023228D01*
G01X1043858Y1499370D02*
X1040709D01*
G01X1023228D02*
X1034858D01*
G01X1076791Y1500965D02*
X1041052D01*
G01X1043858Y1501161D02*
X1023228D01*
G01X1083228Y1501398D02*
X1041102D01*
G01X1040615Y1501555D02*
X1040464D01*
G01X1040967Y1490970D02*
X1041052Y1490965D01*
G01X1040967Y1500970D02*
X1041052Y1500965D01*
G01X1041087Y1490976D02*
X1041204Y1490965D01*
G01X1040626Y1491438D02*
X1040615Y1491555D01*
G01X1040626Y1501438D02*
X1040615Y1501555D01*
G01X1041087Y1500976D02*
X1041204Y1500965D01*
G01X1040887Y1490988D02*
X1040969Y1490970D01*
G01X1040887Y1500988D02*
X1040969Y1500970D01*
G01X1040464Y1491555D02*
X1040481Y1491411D01*
X1040531Y1491280D01*
X1040615Y1491161D01*
G01X1040464Y1501555D02*
X1040481Y1501411D01*
X1040531Y1501280D01*
X1040615Y1501161D01*
G01X1040978Y1491010D02*
X1041090Y1490976D01*
G01X1040978Y1501010D02*
X1041090Y1500976D01*
G01X1040810Y1491016D02*
X1040889Y1490987D01*
G01X1040810Y1501016D02*
X1040889Y1500987D01*
G01X1040737Y1491055D02*
X1040812Y1491015D01*
G01X1040876Y1491064D02*
X1040980Y1491009D01*
G01X1040737Y1501055D02*
X1040812Y1501015D01*
G01X1040876Y1501064D02*
X1040980Y1501009D01*
G01X1040626Y1491440D02*
X1040660Y1491328D01*
G01X1040626Y1501440D02*
X1040660Y1501328D01*
G01X1040671Y1491104D02*
X1040739Y1491054D01*
G01X1040671Y1501104D02*
X1040739Y1501054D01*
G01X1040878Y1491063D02*
X1040787Y1491137D01*
G01X1040878Y1501063D02*
X1040787Y1501137D01*
G01X1040672Y1491103D02*
X1040612Y1491161D01*
G01X1040672Y1501103D02*
X1040612Y1501161D01*
G01X1040713Y1491228D02*
X1040787Y1491137D01*
G01X1040713Y1501228D02*
X1040787Y1501137D01*
G01X1040659Y1491330D02*
X1040714Y1491226D01*
G01X1040659Y1501330D02*
X1040714Y1501226D01*
G01X1032087Y1487244D02*
G03X1031102Y1486260I-1J-984D01*
G01X1040709D02*
G03X1039724Y1487244I-984J0D01*
G01X1040709Y1491791D02*
G03X1041102Y1491398I393J0D01*
G01Y1493248D02*
G03X1040709Y1492854I1J-394D01*
G01X1031102Y1498386D02*
G03X1032087Y1497402I984J0D01*
G01X1039724D02*
G03X1040709Y1498386I1J984D01*
G01Y1501791D02*
G03X1041102Y1501398I393J0D01*
G01X1041090Y1483670D02*
X1040978Y1483636D01*
G01X1040889Y1483658D02*
X1040810Y1483629D01*
G01X1040812Y1483630D02*
X1040737Y1483590D01*
G01X1040980Y1483637D02*
X1040876Y1483581D01*
G01X1040739Y1483591D02*
X1040671Y1483541D01*
G01X1040878Y1483582D02*
X1040787Y1483508D01*
G01X1023622Y1473287D02*
X1023228Y1472894D01*
G01X1040672Y1483543D02*
X1040612Y1483484D01*
G01X1040615D02*
X1040531Y1483366D01*
X1040481Y1483234D01*
X1040464Y1483091D01*
G01X1040713Y1483417D02*
X1040787Y1483508D01*
G01X1040714Y1483419D02*
X1040659Y1483315D01*
G01X1040660Y1483317D02*
X1040626Y1483205D01*
G01X1040969Y1483675D02*
X1040887Y1483657D01*
G01X1039921Y1473681D02*
X1035984Y1473287D01*
G01X1041087Y1483669D02*
X1041204Y1483681D01*
G01X1040967Y1483675D02*
X1041052Y1483681D01*
G01X1043858Y1465276D02*
X1040709D01*
G01X1023228D02*
X1034858D01*
G01X1014457Y1489449D02*
Y1485197D01*
G01Y1479449D02*
Y1475197D01*
G01X1015060Y1489449D02*
Y1485197D01*
G01Y1479449D02*
Y1475197D01*
G01X1015663Y1489449D02*
Y1485197D01*
G01Y1479449D02*
Y1475197D01*
G01X1019600Y1489449D02*
Y1485197D01*
G01Y1479449D02*
Y1475197D01*
G01X1020781Y1489449D02*
Y1485197D01*
G01Y1479449D02*
Y1475197D01*
G01X1021962Y1489449D02*
Y1485197D01*
G01Y1479449D02*
Y1475197D01*
G01X1023622Y1471358D02*
Y1470197D01*
G01Y1473287D02*
Y1474449D01*
G01X1024409Y1489449D02*
Y1485197D01*
G01Y1479449D02*
Y1475197D01*
G01X1025591Y1489449D02*
Y1485197D01*
G01Y1479449D02*
Y1475197D01*
G01X1026378Y1485197D02*
Y1479449D01*
G01Y1475197D02*
Y1473287D01*
G01Y1471358D02*
Y1469449D01*
G01X1027165Y1483484D02*
Y1481161D01*
G01X1029134Y1485276D02*
Y1479370D01*
G01X1031102Y1486260D02*
Y1478386D01*
G01X1031496Y1485276D02*
Y1479370D01*
G01X1032299D02*
Y1485276D01*
G01X1034055D02*
Y1479370D01*
G01X1034858Y1485276D02*
Y1479370D01*
G01X1039921Y1510965D02*
Y1473681D01*
G01X1040048Y1491161D02*
Y1483484D01*
G01Y1481161D02*
Y1473681D01*
G01X1040201Y1510965D02*
Y1473681D01*
G01X1040464Y1483091D02*
Y1481555D01*
G01X1040615Y1483091D02*
Y1481555D01*
G01X1040709Y1486260D02*
Y1478386D01*
G01X1044646Y1481398D02*
Y1483248D01*
G01X1040626Y1483207D02*
X1040615Y1483091D01*
G01X1039724Y1467244D02*
X1023228D01*
G01X1043858Y1470197D02*
X1023228D01*
G01X1076791Y1470965D02*
X1023228D01*
G01X1043858Y1471358D02*
X1023622D01*
G01X1083228Y1471398D02*
X1043858D01*
G01X1083228Y1473248D02*
X1043858D01*
G01Y1473287D02*
X1023622D01*
G01X1076791Y1473681D02*
X1023228D01*
G01X1043858Y1474449D02*
X1023228D01*
G01X1039724Y1477402D02*
X1023228D01*
G01X1043858Y1479370D02*
X1040709D01*
G01X1023228D02*
X1034858D01*
G01X1076791Y1480965D02*
X1041052D01*
G01X1043858Y1481161D02*
X1023228D01*
G01X1083228Y1481398D02*
X1041102D01*
G01X1040615Y1481555D02*
X1040464D01*
G01X1040615Y1483091D02*
X1040464D01*
G01X1083228Y1483248D02*
X1041102D01*
G01X1043858Y1483484D02*
X1023228D01*
G01X1076791Y1483681D02*
X1041052D01*
G01X1040967Y1480970D02*
X1041052Y1480965D01*
G01X1039921Y1470965D02*
X1035984Y1471358D01*
G01X1041087Y1480976D02*
X1041204Y1480965D01*
G01X1040626Y1481438D02*
X1040615Y1481555D01*
G01X1040887Y1480988D02*
X1040969Y1480970D01*
G01X1040978Y1481010D02*
X1041090Y1480976D01*
G01X1040464Y1481555D02*
X1040481Y1481411D01*
X1040531Y1481280D01*
X1040615Y1481161D01*
G01X1040810Y1481016D02*
X1040889Y1480987D01*
G01X1040737Y1481055D02*
X1040812Y1481015D01*
G01X1040876Y1481064D02*
X1040980Y1481009D01*
G01X1023228Y1471752D02*
X1023622Y1471358D01*
G01X1040659Y1481330D02*
X1040714Y1481226D01*
G01X1040626Y1481440D02*
X1040660Y1481328D01*
G01X1040671Y1481104D02*
X1040739Y1481054D01*
G01X1040878Y1481063D02*
X1040787Y1481137D01*
G01X1040672Y1481103D02*
X1040612Y1481161D01*
G01X1040713Y1481228D02*
X1040787Y1481137D01*
G01X1031102Y1478386D02*
G03X1032087Y1477402I984J0D01*
G01Y1467244D02*
G03X1031102Y1466260I-1J-984D01*
G01X1040709D02*
G03X1039724Y1467244I-984J0D01*
G01Y1477402D02*
G03X1040709Y1478386I1J984D01*
G01X1041102Y1483248D02*
G03X1040709Y1482854I1J-394D01*
G01Y1481791D02*
G03X1041102Y1481398I393J0D01*
G01X997340Y1499430D02*
X997178Y1499373D01*
G01X998521Y1499430D02*
X998359Y1499373D01*
G01X997340Y1489430D02*
X997178Y1489373D01*
G01X998521Y1489430D02*
X998359Y1489373D01*
G01X997181Y1499374D02*
X997031Y1499282D01*
G01X998362Y1499374D02*
X998213Y1499282D01*
G01X997181Y1489374D02*
X997031Y1489282D01*
G01X998362Y1489374D02*
X998213Y1489282D01*
G01X997034Y1499284D02*
X996903Y1499160D01*
G01X998215Y1499284D02*
X998084Y1499160D01*
G01X997034Y1489284D02*
X996903Y1489160D01*
G01X998215Y1489284D02*
X998084Y1489160D01*
G01X996796Y1499009D02*
X996903Y1499160D01*
G01X997977Y1499009D02*
X998084Y1499160D01*
G01X996796Y1489009D02*
X996903Y1489160D01*
G01X997977Y1489009D02*
X998084Y1489160D01*
G01X996798Y1499012D02*
X996718Y1498839D01*
G01X997979Y1499012D02*
X997899Y1498839D01*
G01X996798Y1489012D02*
X996718Y1488839D01*
G01X997979Y1489012D02*
X997899Y1488839D01*
G01X996719Y1498843D02*
X996670Y1498656D01*
G01X997900Y1498843D02*
X997851Y1498656D01*
G01X996719Y1488843D02*
X996670Y1488656D01*
G01X997900Y1488843D02*
X997851Y1488656D01*
G01X996670Y1498659D02*
X996654Y1498465D01*
G01X996670Y1488659D02*
X996654Y1488465D01*
G01X997851Y1498659D02*
X997835Y1498465D01*
G01X997851Y1488659D02*
X997835Y1488465D01*
G01X998519Y1489429D02*
X998687Y1489449D01*
G01X997337Y1489429D02*
X997506Y1489449D01*
G01X998519Y1499429D02*
X998687Y1499449D01*
G01X997337Y1499429D02*
X997506Y1499449D01*
G01X996670Y1485987D02*
X996654Y1486181D01*
G01X996670Y1495987D02*
X996654Y1496181D01*
G01X997851Y1485987D02*
X997835Y1486181D01*
G01X997851Y1495987D02*
X997835Y1496181D01*
G01X996654Y1498465D02*
Y1496181D01*
G01Y1488465D02*
Y1486181D01*
G01X997835Y1498465D02*
Y1496181D01*
G01Y1488465D02*
Y1486181D01*
G01X1002362Y1499449D02*
Y1495197D01*
G01X1003543Y1499449D02*
Y1495197D01*
G01X1004733Y1499449D02*
Y1495197D01*
G01X1005335Y1499449D02*
Y1495197D01*
G01X997835Y1486181D02*
X996654D01*
G01X997835Y1488465D02*
X996654D01*
G01X1026378Y1489449D02*
X997506D01*
G01X1026378Y1495197D02*
X997506D01*
G01X997835Y1496181D02*
X996654D01*
G01X997835Y1498465D02*
X996654D01*
G01X1026378Y1499449D02*
X997506D01*
G01X997337Y1495216D02*
X997506Y1495197D01*
G01X998519Y1495216D02*
X998687Y1495197D01*
G01X996670Y1485990D02*
X996719Y1485803D01*
G01X997851Y1485990D02*
X997900Y1485803D01*
G01X996670Y1495990D02*
X996719Y1495803D01*
G01X997851Y1495990D02*
X997900Y1495803D01*
G01X997178Y1495272D02*
X997340Y1495215D01*
G01X998359Y1495272D02*
X998521Y1495215D01*
G01X997031Y1485363D02*
X997181Y1485271D01*
G01X998213Y1485363D02*
X998362Y1485271D01*
G01X997031Y1495363D02*
X997181Y1495271D01*
G01X998213Y1495363D02*
X998362Y1495271D01*
G01X997034Y1485361D02*
X996903Y1485485D01*
G01X998215Y1485361D02*
X998084Y1485485D01*
G01X997034Y1495361D02*
X996903Y1495485D01*
G01X998215Y1495361D02*
X998084Y1495485D01*
G01X996796Y1485636D02*
X996903Y1485485D01*
G01X997977Y1485636D02*
X998084Y1485485D01*
G01X996796Y1495636D02*
X996903Y1495485D01*
G01X997977Y1495636D02*
X998084Y1495485D01*
G01X996718Y1485806D02*
X996798Y1485633D01*
G01X997899Y1485806D02*
X997979Y1485633D01*
G01X996718Y1495806D02*
X996798Y1495633D01*
G01X997899Y1495806D02*
X997979Y1495633D01*
G01X997340Y1479430D02*
X997181Y1479374D01*
X997031Y1479282D01*
G01X997178Y1479373D02*
X997337Y1479429D01*
X997506Y1479449D01*
G01X998521Y1479430D02*
X998359Y1479373D01*
G01X997340Y1469430D02*
X997178Y1469373D01*
G01X998521Y1469430D02*
X998359Y1469373D01*
G01X998362Y1479374D02*
X998213Y1479282D01*
G01X997181Y1469374D02*
X997031Y1469282D01*
G01X998362Y1469374D02*
X998213Y1469282D01*
G01X997034Y1479284D02*
X996903Y1479160D01*
G01X998215Y1479284D02*
X998084Y1479160D01*
G01X997034Y1469284D02*
X996903Y1469160D01*
G01X998215Y1469284D02*
X998084Y1469160D01*
G01X996796Y1479009D02*
X996903Y1479160D01*
G01X996796Y1469009D02*
X996903Y1469160D01*
G01X997977Y1469009D02*
X998084Y1469160D01*
G01X996798Y1479012D02*
X996718Y1478839D01*
G01X997979Y1479012D02*
X997900Y1478843D01*
X997851Y1478656D01*
G01X997899Y1478839D02*
X997977Y1479009D01*
X998084Y1479160D01*
G01X996798Y1469012D02*
X996718Y1468839D01*
G01X997979Y1469012D02*
X997899Y1468839D01*
G01X996719Y1478843D02*
X996670Y1478656D01*
G01X996719Y1468843D02*
X996670Y1468656D01*
G01X997900Y1468843D02*
X997851Y1468656D01*
G01X996670Y1478659D02*
X996654Y1478465D01*
G01X996670Y1468659D02*
X996654Y1468465D01*
G01X997851Y1478659D02*
X997835Y1478465D01*
G01X997851Y1468659D02*
X997835Y1468465D01*
G01X998519Y1469429D02*
X998687Y1469449D01*
G01X997337Y1469429D02*
X997506Y1469449D01*
G01X998519Y1479429D02*
X998687Y1479449D01*
G01X996670Y1465987D02*
X996654Y1466181D01*
G01X996670Y1475987D02*
X996654Y1476181D01*
G01X997851Y1465987D02*
X997835Y1466181D01*
G01X997851Y1475987D02*
X997835Y1476181D01*
G01X996654Y1478465D02*
Y1476181D01*
G01Y1468465D02*
Y1466181D01*
G01X997835Y1478465D02*
Y1476181D01*
G01Y1468465D02*
Y1466181D01*
G01X1002362Y1489449D02*
Y1485197D01*
G01Y1479449D02*
Y1475197D01*
G01X1003543Y1489449D02*
Y1485197D01*
G01Y1479449D02*
Y1475197D01*
G01X1004733Y1489449D02*
Y1485197D01*
G01Y1479449D02*
Y1475197D01*
G01X1005335Y1489449D02*
Y1485197D01*
G01Y1479449D02*
Y1475197D01*
G01X997835Y1466181D02*
X996654D01*
G01X997835Y1468465D02*
X996654D01*
G01X1026378Y1469449D02*
X997506D01*
G01X1026378Y1475197D02*
X997506D01*
G01X997835Y1476181D02*
X996654D01*
G01X997835Y1478465D02*
X996654D01*
G01X1026378Y1479449D02*
X997506D01*
G01X1026378Y1485197D02*
X997506D01*
G01X997337Y1475216D02*
X997506Y1475197D01*
G01X998519Y1475216D02*
X998687Y1475197D01*
G01X997340Y1485215D02*
X997181Y1485271D01*
G01X998521Y1485215D02*
X998362Y1485271D01*
G01X997178Y1475272D02*
X997340Y1475215D01*
G01X998359Y1475272D02*
X998521Y1475215D01*
G01X996670Y1465990D02*
X996719Y1465803D01*
G01X997851Y1465990D02*
X997900Y1465803D01*
G01X996670Y1475990D02*
X996719Y1475803D01*
G01X997851Y1475990D02*
X997900Y1475803D01*
G01X997178Y1485272D02*
X997337Y1485216D01*
X997506Y1485197D01*
G01X998359Y1485272D02*
X998519Y1485216D01*
X998687Y1485197D01*
G01X997031Y1465363D02*
X997181Y1465271D01*
G01X998213Y1465363D02*
X998362Y1465271D01*
G01X997031Y1475363D02*
X997181Y1475271D01*
G01X998213Y1475363D02*
X998362Y1475271D01*
G01X997034Y1465361D02*
X996903Y1465485D01*
G01X998215Y1465361D02*
X998084Y1465485D01*
G01X997034Y1475361D02*
X996903Y1475485D01*
G01X998215Y1475361D02*
X998084Y1475485D01*
G01X996796Y1465636D02*
X996903Y1465485D01*
G01X997977Y1465636D02*
X998084Y1465485D01*
G01X996796Y1475636D02*
X996903Y1475485D01*
G01X997977Y1475636D02*
X998084Y1475485D01*
G01X996718Y1465806D02*
X996798Y1465633D01*
G01X997899Y1465806D02*
X997979Y1465633D01*
G01X996718Y1475806D02*
X996798Y1475633D01*
G01X997899Y1475806D02*
X997979Y1475633D01*
G01X1041090Y1573670D02*
X1040978Y1573636D01*
G01X1041090Y1563670D02*
X1040978Y1563636D01*
G01X1040889Y1573658D02*
X1040810Y1573629D01*
G01X1040889Y1563658D02*
X1040810Y1563629D01*
G01X1040812Y1573630D02*
X1040737Y1573590D01*
G01X1040980Y1573637D02*
X1040876Y1573581D01*
G01X1040812Y1563630D02*
X1040737Y1563590D01*
G01X1040980Y1563637D02*
X1040876Y1563581D01*
G01X1040739Y1573591D02*
X1040671Y1573541D01*
G01X1040739Y1563591D02*
X1040671Y1563541D01*
G01X1040878Y1573582D02*
X1040787Y1573508D01*
G01X1040878Y1563582D02*
X1040787Y1563508D01*
G01X1023622Y1553287D02*
X1023228Y1552894D01*
G01X1040672Y1573543D02*
X1040612Y1573484D01*
G01X1040672Y1563543D02*
X1040612Y1563484D01*
G01X1040713Y1573417D02*
X1040787Y1573508D01*
G01X1040713Y1563417D02*
X1040787Y1563508D01*
G01X1040615Y1573484D02*
X1040532Y1573365D01*
X1040482Y1573234D01*
X1040464Y1573091D01*
G01X1040615Y1563484D02*
X1040532Y1563365D01*
X1040482Y1563234D01*
X1040464Y1563091D01*
G01X1040615Y1573484D02*
X1040531Y1573366D01*
X1040481Y1573234D01*
X1040464Y1573091D01*
G01X1040615Y1563484D02*
X1040531Y1563366D01*
X1040481Y1563234D01*
X1040464Y1563091D01*
G01X1040714Y1573419D02*
X1040659Y1573315D01*
G01X1040714Y1563419D02*
X1040659Y1563315D01*
G01X1040660Y1573317D02*
X1040626Y1573205D01*
G01X1040660Y1563317D02*
X1040626Y1563205D01*
G01X1040969Y1563675D02*
X1040887Y1563657D01*
G01X1040969Y1573675D02*
X1040887Y1573657D01*
G01X1014457Y1579449D02*
Y1575197D01*
G01Y1569449D02*
Y1565197D01*
G01Y1559449D02*
Y1555197D01*
G01X1015060Y1579449D02*
Y1575197D01*
G01Y1569449D02*
Y1565197D01*
G01Y1559449D02*
Y1555197D01*
G01X1015663Y1579449D02*
Y1575197D01*
G01Y1569449D02*
Y1565197D01*
G01Y1559449D02*
Y1555197D01*
G01X1019600Y1579449D02*
Y1575197D01*
G01Y1569449D02*
Y1565197D01*
G01Y1559449D02*
Y1555197D01*
G01X1020781Y1579449D02*
Y1575197D01*
G01Y1569449D02*
Y1565197D01*
G01Y1559449D02*
Y1555197D01*
G01X1021962Y1579449D02*
Y1575197D01*
G01Y1569449D02*
Y1565197D01*
G01Y1559449D02*
Y1555197D01*
G01X1023622Y1554449D02*
Y1553287D01*
G01Y1551358D02*
Y1550197D01*
G01X1024409Y1579449D02*
Y1575197D01*
G01Y1569449D02*
Y1565197D01*
G01Y1559449D02*
Y1555197D01*
G01X1025591Y1579449D02*
Y1575197D01*
G01Y1569449D02*
Y1565197D01*
G01Y1559449D02*
Y1555197D01*
G01X1026378Y1575197D02*
Y1569449D01*
G01Y1565197D02*
Y1559449D01*
G01Y1555197D02*
Y1553287D01*
G01Y1551358D02*
Y1549449D01*
G01X1027165Y1573484D02*
Y1571161D01*
G01Y1563484D02*
Y1561161D01*
G01X1029134Y1565276D02*
Y1559370D01*
G01X1031102Y1566260D02*
Y1558386D01*
G01X1031496Y1565276D02*
Y1559370D01*
G01X1032299D02*
Y1565276D01*
G01X1034055D02*
Y1559370D01*
G01X1034858Y1565276D02*
Y1559370D01*
G01X1039921Y1590965D02*
Y1553681D01*
G01X1040048Y1581161D02*
Y1573484D01*
G01Y1571161D02*
Y1563484D01*
G01Y1561161D02*
Y1553681D01*
G01X1040201Y1590965D02*
Y1553681D01*
G01X1040464Y1573091D02*
Y1571555D01*
G01Y1563091D02*
Y1561555D01*
G01X1040615Y1573091D02*
Y1571555D01*
G01Y1563091D02*
Y1561555D01*
G01X1040709Y1572854D02*
Y1571791D01*
G01Y1566260D02*
Y1558386D01*
G01X1044646Y1561398D02*
Y1563248D01*
G01Y1571398D02*
Y1573248D01*
G01X1040626Y1573207D02*
X1040615Y1573091D01*
G01X1040626Y1563207D02*
X1040615Y1563091D01*
G01X1039921Y1553681D02*
X1035984Y1553287D01*
G01X1041087Y1563669D02*
X1041204Y1563681D01*
G01X1041087Y1573669D02*
X1041204Y1573681D01*
G01X1040967Y1563675D02*
X1041052Y1563681D01*
G01X1040967Y1573675D02*
X1041052Y1573681D01*
G01X1040626Y1561438D02*
X1040615Y1561555D01*
G01X1040626Y1571438D02*
X1040615Y1571555D01*
G01X1043858Y1545276D02*
X1040709D01*
G01X1023228D02*
X1034858D01*
G01X1039724Y1547244D02*
X1023228D01*
G01X1043858Y1550197D02*
X1023228D01*
G01X1076791Y1550965D02*
X1023228D01*
G01X1043858Y1551358D02*
X1023622D01*
G01X1083228Y1551398D02*
X1043858D01*
G01X1083228Y1553248D02*
X1043858D01*
G01X1023622Y1553287D02*
X1043858D01*
G01X1076791Y1553681D02*
X1023228D01*
G01X1043858Y1554449D02*
X1023228D01*
G01X1039724Y1557402D02*
X1023228D01*
G01X1043858Y1559370D02*
X1040709D01*
G01X1023228D02*
X1034858D01*
G01X1076791Y1560965D02*
X1041052D01*
G01X1043858Y1561161D02*
X1023228D01*
G01X1083228Y1561398D02*
X1041102D01*
G01X1040615Y1561555D02*
X1040464D01*
G01X1040615Y1563091D02*
X1040464D01*
G01X1083228Y1563248D02*
X1041102D01*
G01X1023228Y1563484D02*
X1043858D01*
G01X1076791Y1563681D02*
X1041052D01*
G01X1043858Y1565276D02*
X1040709D01*
G01X1023228D02*
X1034858D01*
G01X1039724Y1567244D02*
X1023228D01*
G01X1043858Y1570197D02*
X1023228D01*
G01X1076791Y1570965D02*
X1041052D01*
G01X1043858Y1571161D02*
X1023228D01*
G01X1083228Y1571398D02*
X1041102D01*
G01X1040615Y1571555D02*
X1040464D01*
G01X1040615Y1573091D02*
X1040464D01*
G01X1083228Y1573248D02*
X1041102D01*
G01X1043858Y1573484D02*
X1023228D01*
G01X1076791Y1573681D02*
X1041052D01*
G01X1043858Y1574449D02*
X1023228D01*
G01X1040967Y1560970D02*
X1041052Y1560965D01*
G01X1040967Y1570970D02*
X1041052Y1570965D01*
G01X1039921Y1550965D02*
X1035984Y1551358D01*
G01X1041087Y1560976D02*
X1041204Y1560965D01*
G01X1040481Y1561411D02*
X1040464Y1561555D01*
G01X1041087Y1570976D02*
X1041204Y1570965D01*
G01X1040887Y1560988D02*
X1040969Y1560970D01*
G01X1040887Y1570988D02*
X1040969Y1570970D01*
G01X1040978Y1561010D02*
X1041090Y1560976D01*
G01X1040481Y1561411D02*
X1040531Y1561280D01*
X1040615Y1561161D01*
G01X1040626Y1561440D02*
X1040660Y1561328D01*
G01X1040626Y1571440D02*
X1040660Y1571328D01*
G01X1040978Y1571010D02*
X1041090Y1570976D01*
G01X1040810Y1561016D02*
X1040889Y1560987D01*
G01X1040810Y1571016D02*
X1040889Y1570987D01*
G01X1040737Y1561055D02*
X1040812Y1561015D01*
G01X1040876Y1561064D02*
X1040980Y1561009D01*
G01X1040737Y1571055D02*
X1040812Y1571015D01*
G01X1040876Y1571064D02*
X1040980Y1571009D01*
G01X1040671Y1561104D02*
X1040739Y1561054D01*
G01X1040878Y1561063D02*
X1040787Y1561137D01*
G01X1040672Y1561103D02*
X1040612Y1561161D01*
G01X1023228Y1551752D02*
X1023622Y1551358D01*
G01X1040713Y1561228D02*
X1040787Y1561137D01*
G01X1040713Y1571228D02*
X1040787Y1571137D01*
G01X1040615Y1571161D02*
X1040531Y1571280D01*
X1040481Y1571411D01*
X1040464Y1571555D01*
G01X1040615Y1571161D02*
X1040532Y1571280D01*
X1040482Y1571411D01*
X1040464Y1571555D01*
G01X1040659Y1561330D02*
X1040714Y1561226D01*
G01X1040659Y1571330D02*
X1040714Y1571226D01*
G01X1040671Y1571104D02*
X1040739Y1571054D01*
G01X1040878Y1571063D02*
X1040787Y1571137D01*
G01X1040672Y1571103D02*
X1040612Y1571161D01*
G01X1031102Y1558386D02*
G03X1032087Y1557402I984J0D01*
G01Y1567244D02*
G03X1031102Y1566260I-1J-984D01*
G01X1032087Y1547244D02*
G03X1031102Y1546260I-1J-984D01*
G01X1040709D02*
G03X1039724Y1547244I-984J0D01*
G01X1040709Y1566260D02*
G03X1039724Y1567244I-984J0D01*
G01Y1557402D02*
G03X1040709Y1558386I1J984D01*
G01Y1571791D02*
G03X1041102Y1571398I393J0D01*
G01Y1573248D02*
G03X1040709Y1572854I1J-394D01*
G01X1041102Y1563248D02*
G03X1040709Y1562854I1J-394D01*
G01Y1561791D02*
G03X1041102Y1561398I393J0D01*
G01X997340Y1569430D02*
X997178Y1569373D01*
G01X998521Y1569430D02*
X998359Y1569373D01*
G01X997340Y1559430D02*
X997178Y1559373D01*
G01X998521Y1559430D02*
X998359Y1559373D01*
G01X997340Y1549430D02*
X997178Y1549373D01*
G01X998521Y1549430D02*
X998359Y1549373D01*
G01X997181Y1569374D02*
X997031Y1569282D01*
G01X998362Y1569374D02*
X998213Y1569282D01*
G01X997181Y1559374D02*
X997031Y1559282D01*
G01X998362Y1559374D02*
X998213Y1559282D01*
G01X997181Y1549374D02*
X997031Y1549282D01*
G01X998362Y1549374D02*
X998213Y1549282D01*
G01X997034Y1569284D02*
X996903Y1569160D01*
G01X998215Y1569284D02*
X998084Y1569160D01*
G01X997034Y1559284D02*
X996903Y1559160D01*
G01X998215Y1559284D02*
X998084Y1559160D01*
G01X997034Y1549284D02*
X996903Y1549160D01*
G01X998215Y1549284D02*
X998084Y1549160D01*
G01X996796Y1569009D02*
X996903Y1569160D01*
G01X997977Y1569009D02*
X998084Y1569160D01*
G01X996796Y1559009D02*
X996903Y1559160D01*
G01X997977Y1559009D02*
X998084Y1559160D01*
G01X996796Y1549009D02*
X996903Y1549160D01*
G01X997977Y1549009D02*
X998084Y1549160D01*
X998213Y1549282D01*
G01X996798Y1569012D02*
X996718Y1568839D01*
G01X997979Y1569012D02*
X997899Y1568839D01*
G01X996798Y1559012D02*
X996718Y1558839D01*
G01X997979Y1559012D02*
X997899Y1558839D01*
G01X996798Y1549012D02*
X996718Y1548839D01*
G01X997979Y1549012D02*
X997899Y1548839D01*
G01X996719Y1568843D02*
X996670Y1568656D01*
G01X997900Y1568843D02*
X997851Y1568656D01*
G01X996719Y1558843D02*
X996670Y1558656D01*
G01X997900Y1558843D02*
X997851Y1558656D01*
G01X996719Y1548843D02*
X996670Y1548656D01*
G01X997900Y1548843D02*
X997851Y1548656D01*
G01X996670Y1568659D02*
X996654Y1568465D01*
G01X996670Y1558659D02*
X996654Y1558465D01*
G01X997851Y1568659D02*
X997835Y1568465D01*
G01X996670Y1548659D02*
X996654Y1548465D01*
G01X997851Y1558659D02*
X997835Y1558465D01*
G01X997851Y1548659D02*
X997835Y1548465D01*
G01X996670Y1545987D02*
X996654Y1546181D01*
G01X996670Y1555987D02*
X996654Y1556181D01*
G01X997851Y1545987D02*
X997835Y1546181D01*
G01X996670Y1565987D02*
X996654Y1566181D01*
G01X997851Y1555987D02*
X997835Y1556181D01*
G01X997851Y1565987D02*
X997835Y1566181D01*
G01X996654Y1568465D02*
Y1566181D01*
G01Y1558465D02*
Y1556181D01*
G01Y1548465D02*
Y1546181D01*
G01X997835Y1568465D02*
Y1566181D01*
G01Y1558465D02*
Y1556181D01*
G01Y1548465D02*
Y1546181D01*
G01X1002362Y1579449D02*
Y1575197D01*
G01Y1569449D02*
Y1565197D01*
G01Y1559449D02*
Y1555197D01*
G01X1003543Y1579449D02*
Y1575197D01*
G01Y1569449D02*
Y1565197D01*
G01Y1559449D02*
Y1555197D01*
G01X1004733Y1579449D02*
Y1575197D01*
G01Y1569449D02*
Y1565197D01*
G01Y1559449D02*
Y1555197D01*
G01X1005335Y1579449D02*
Y1575197D01*
G01Y1569449D02*
Y1565197D01*
G01Y1559449D02*
Y1555197D01*
G01X998519Y1549429D02*
X998687Y1549449D01*
G01X997337Y1549429D02*
X997506Y1549449D01*
G01X998519Y1559429D02*
X998687Y1559449D01*
G01X997337Y1559429D02*
X997506Y1559449D01*
G01X998519Y1569429D02*
X998687Y1569449D01*
G01X997337Y1569429D02*
X997506Y1569449D01*
G01X997835Y1546181D02*
X996654D01*
G01X997835Y1548465D02*
X996654D01*
G01X1026378Y1549449D02*
X997506D01*
G01X1026378Y1555197D02*
X997506D01*
G01X997835Y1556181D02*
X996654D01*
G01X997835Y1558465D02*
X996654D01*
G01X1026378Y1559449D02*
X997506D01*
G01X1026378Y1565197D02*
X997506D01*
G01X997835Y1566181D02*
X996654D01*
G01X997835Y1568465D02*
X996654D01*
G01X1026378Y1569449D02*
X997506D01*
G01X1026378Y1575197D02*
X997506D01*
G01X997337Y1555216D02*
X997506Y1555197D01*
G01X998519Y1555216D02*
X998687Y1555197D01*
G01X997337Y1565216D02*
X997506Y1565197D01*
G01X998519Y1565216D02*
X998687Y1565197D01*
G01X996670Y1545990D02*
X996719Y1545803D01*
G01X997851Y1545990D02*
X997900Y1545803D01*
G01X996670Y1555990D02*
X996719Y1555803D01*
G01X997851Y1555990D02*
X997900Y1555803D01*
G01X996670Y1565990D02*
X996719Y1565803D01*
G01X997851Y1565990D02*
X997900Y1565803D01*
G01X997337Y1575216D02*
X997506Y1575197D01*
G01X998519Y1575216D02*
X998687Y1575197D01*
G01X997178Y1555272D02*
X997340Y1555215D01*
G01X998359Y1555272D02*
X998521Y1555215D01*
G01X997178Y1565272D02*
X997340Y1565215D01*
G01X998359Y1565272D02*
X998521Y1565215D01*
G01X996718Y1545806D02*
X996798Y1545633D01*
G01X997899Y1545806D02*
X997979Y1545633D01*
G01X996718Y1555806D02*
X996798Y1555633D01*
G01X997899Y1555806D02*
X997979Y1555633D01*
G01X996718Y1565806D02*
X996798Y1565633D01*
G01X997899Y1565806D02*
X997979Y1565633D01*
G01X997178Y1575272D02*
X997340Y1575215D01*
G01X998359Y1575272D02*
X998521Y1575215D01*
G01X997031Y1545363D02*
X997181Y1545271D01*
G01X998213Y1545363D02*
X998362Y1545271D01*
G01X997031Y1555363D02*
X997181Y1555271D01*
G01X998213Y1555363D02*
X998362Y1555271D01*
G01X997031Y1565363D02*
X997181Y1565271D01*
G01X998213Y1565363D02*
X998362Y1565271D01*
G01X997031Y1575363D02*
X997181Y1575271D01*
G01X998213Y1575363D02*
X998362Y1575271D01*
G01X997034Y1545361D02*
X996903Y1545485D01*
G01X998215Y1545361D02*
X998084Y1545485D01*
G01X997034Y1555361D02*
X996903Y1555485D01*
G01X998215Y1555361D02*
X998084Y1555485D01*
G01X997034Y1565361D02*
X996903Y1565485D01*
G01X998215Y1565361D02*
X998084Y1565485D01*
G01X997034Y1575361D02*
X996903Y1575485D01*
G01X998215Y1575361D02*
X998084Y1575485D01*
G01X996796Y1545636D02*
X996903Y1545485D01*
G01X997977Y1545636D02*
X998084Y1545485D01*
G01X996796Y1555636D02*
X996903Y1555485D01*
G01X997977Y1555636D02*
X998084Y1555485D01*
G01X996796Y1565636D02*
X996903Y1565485D01*
G01X997977Y1565636D02*
X998084Y1565485D01*
G01X996796Y1575636D02*
X996903Y1575485D01*
G01X997977Y1575636D02*
X998084Y1575485D01*
G01X1040889Y1543658D02*
X1040810Y1543629D01*
G01X1040889Y1533658D02*
X1040810Y1533629D01*
G01X1040889Y1523658D02*
X1040810Y1523629D01*
G01X1041090Y1543670D02*
X1040978Y1543636D01*
G01X1041090Y1533670D02*
X1040978Y1533636D01*
G01X1041090Y1523670D02*
X1040978Y1523636D01*
G01X1041090Y1503670D02*
X1040978Y1503636D01*
G01X1040812Y1543630D02*
X1040737Y1543590D01*
G01X1040980Y1543637D02*
X1040876Y1543581D01*
G01X1040812Y1533630D02*
X1040737Y1533590D01*
G01X1040980Y1533637D02*
X1040876Y1533581D01*
G01X1040889Y1503658D02*
X1040810Y1503629D01*
G01X1040812Y1523630D02*
X1040737Y1523590D01*
G01X1040980Y1523637D02*
X1040876Y1523581D01*
G01X1040812Y1503630D02*
X1040737Y1503590D01*
G01X1040980Y1503637D02*
X1040876Y1503581D01*
G01X1040878Y1543582D02*
X1040787Y1543508D01*
G01X1040878Y1533582D02*
X1040787Y1533508D01*
G01X1040878Y1523582D02*
X1040787Y1523508D01*
G01X1040739Y1543591D02*
X1040671Y1543541D01*
G01X1040739Y1533591D02*
X1040671Y1533541D01*
G01X1040739Y1523591D02*
X1040671Y1523541D01*
G01X1040739Y1503591D02*
X1040671Y1503541D01*
G01X1023622Y1513287D02*
X1023228Y1512894D01*
G01X1040672Y1543543D02*
X1040612Y1543484D01*
G01X1040672Y1533543D02*
X1040612Y1533484D01*
G01X1040672Y1523543D02*
X1040612Y1523484D01*
G01X1040672Y1503543D02*
X1040612Y1503484D01*
G01X1040878Y1503582D02*
X1040787Y1503508D01*
G01X1040713Y1543417D02*
X1040787Y1543508D01*
G01X1040713Y1533417D02*
X1040787Y1533508D01*
G01X1040713Y1523417D02*
X1040787Y1523508D01*
G01X1040615Y1543484D02*
X1040532Y1543365D01*
X1040482Y1543234D01*
X1040464Y1543091D01*
G01X1040615Y1543484D02*
X1040531Y1543366D01*
X1040481Y1543234D01*
X1040464Y1543091D01*
G01X1040615Y1523484D02*
X1040531Y1523366D01*
X1040481Y1523234D01*
X1040464Y1523091D01*
G01X1040615Y1503484D02*
X1040531Y1503366D01*
X1040481Y1503234D01*
X1040464Y1503091D01*
G01X1040713Y1503417D02*
X1040787Y1503508D01*
G01X1040714Y1543419D02*
X1040659Y1543315D01*
G01X1040714Y1533419D02*
X1040659Y1533315D01*
G01X1040714Y1523419D02*
X1040659Y1523315D01*
G01X1040714Y1503419D02*
X1040659Y1503315D01*
G01X1040660Y1543317D02*
X1040626Y1543205D01*
G01X1040660Y1533317D02*
X1040626Y1533205D01*
G01X1040660Y1523317D02*
X1040626Y1523205D01*
G01X1040660Y1503317D02*
X1040626Y1503205D01*
G01X1040969Y1503675D02*
X1040887Y1503657D01*
G01X1040464Y1533091D02*
X1040481Y1533234D01*
X1040531Y1533366D01*
X1040615Y1533484D01*
G01X1040464Y1533091D02*
X1040482Y1533234D01*
X1040532Y1533365D01*
X1040615Y1533484D01*
G01X1040969Y1523675D02*
X1040887Y1523657D01*
G01X1040969Y1533675D02*
X1040887Y1533657D01*
G01X1040969Y1543675D02*
X1040887Y1543657D01*
G01X1041087Y1503669D02*
X1041204Y1503681D01*
G01X1039921Y1513681D02*
X1035984Y1513287D01*
G01X1040967Y1503675D02*
X1041052Y1503681D01*
G01X1014457Y1549449D02*
Y1545197D01*
G01Y1539449D02*
Y1535197D01*
G01Y1529449D02*
Y1525197D01*
G01Y1519449D02*
Y1515197D01*
G01Y1509449D02*
Y1505197D01*
G01X1015060Y1549449D02*
Y1545197D01*
G01Y1539449D02*
Y1535197D01*
G01Y1529449D02*
Y1525197D01*
G01Y1519449D02*
Y1515197D01*
G01Y1509449D02*
Y1505197D01*
G01X1015663Y1549449D02*
Y1545197D01*
G01Y1539449D02*
Y1535197D01*
G01Y1529449D02*
Y1525197D01*
G01Y1519449D02*
Y1515197D01*
G01Y1509449D02*
Y1505197D01*
G01X1019600Y1549449D02*
Y1545197D01*
G01Y1539449D02*
Y1535197D01*
G01Y1529449D02*
Y1525197D01*
G01Y1519449D02*
Y1515197D01*
G01Y1509449D02*
Y1505197D01*
G01X1020781Y1549449D02*
Y1545197D01*
G01Y1539449D02*
Y1535197D01*
G01Y1529449D02*
Y1525197D01*
G01Y1519449D02*
Y1515197D01*
G01Y1509449D02*
Y1505197D01*
G01X1021962Y1549449D02*
Y1545197D01*
G01Y1539449D02*
Y1535197D01*
G01Y1529449D02*
Y1525197D01*
G01Y1519449D02*
Y1515197D01*
G01Y1509449D02*
Y1505197D01*
G01X1023622Y1511358D02*
Y1510197D01*
G01Y1513287D02*
Y1514449D01*
G01X1024409Y1549449D02*
Y1545197D01*
G01Y1539449D02*
Y1535197D01*
G01Y1529449D02*
Y1525197D01*
G01Y1519449D02*
Y1515197D01*
G01Y1509449D02*
Y1505197D01*
G01X1025591Y1549449D02*
Y1545197D01*
G01Y1539449D02*
Y1535197D01*
G01Y1529449D02*
Y1525197D01*
G01Y1519449D02*
Y1515197D01*
G01Y1509449D02*
Y1505197D01*
G01X1026378Y1545197D02*
Y1539449D01*
G01Y1535197D02*
Y1529449D01*
G01Y1525197D02*
Y1519449D01*
G01Y1515197D02*
Y1513287D01*
G01Y1511358D02*
Y1509449D01*
G01X1027165Y1543484D02*
Y1541161D01*
G01Y1533484D02*
Y1531161D01*
G01Y1523484D02*
Y1521161D01*
G01X1029134Y1545276D02*
Y1539370D01*
G01Y1525276D02*
Y1519370D01*
G01X1031102Y1546260D02*
Y1538386D01*
G01Y1526260D02*
Y1518386D01*
G01X1031496Y1545276D02*
Y1539370D01*
G01Y1525276D02*
Y1519370D01*
G01X1032299Y1545276D02*
Y1539370D01*
G01Y1525276D02*
Y1519370D01*
G01X1034055Y1545276D02*
Y1539370D01*
G01Y1525276D02*
Y1519370D01*
G01X1034858Y1545276D02*
Y1539370D01*
G01Y1525276D02*
Y1519370D01*
G01X1039921Y1550965D02*
Y1513681D01*
G01X1040048Y1550965D02*
Y1543484D01*
G01Y1541161D02*
Y1533484D01*
G01Y1531161D02*
Y1523484D01*
G01Y1521161D02*
Y1513681D01*
G01Y1510965D02*
Y1503484D01*
G01X1040201Y1550965D02*
Y1513681D01*
G01X1040464Y1543091D02*
Y1541555D01*
G01Y1533091D02*
Y1531555D01*
G01Y1523091D02*
Y1521555D01*
G01X1040615Y1543091D02*
Y1541555D01*
G01Y1533091D02*
Y1531555D01*
G01Y1523091D02*
Y1521555D01*
G01X1040709Y1546260D02*
Y1538386D01*
G01Y1532854D02*
Y1531791D01*
G01Y1526260D02*
Y1518386D01*
G01X1044646Y1533248D02*
Y1531398D01*
G01Y1521398D02*
Y1523248D01*
G01Y1541398D02*
Y1543248D01*
G01X1040626Y1543207D02*
X1040615Y1543091D01*
G01X1040626Y1533207D02*
X1040615Y1533091D01*
G01X1040626Y1523207D02*
X1040615Y1523091D01*
G01X1040626Y1503207D02*
X1040615Y1503091D01*
G01X1041087Y1523669D02*
X1041204Y1523681D01*
G01X1041087Y1533669D02*
X1041204Y1533681D01*
G01X1041087Y1543669D02*
X1041204Y1543681D01*
G01X1040967Y1523675D02*
X1041052Y1523681D01*
G01X1040967Y1533675D02*
X1041052Y1533681D01*
G01X1040967Y1543675D02*
X1041052Y1543681D01*
G01X1040615Y1503091D02*
X1040464D01*
G01X1083228Y1503248D02*
X1041102D01*
G01X1043858Y1503484D02*
X1023228D01*
G01X1076791Y1503681D02*
X1041052D01*
G01X1043858Y1505276D02*
X1040709D01*
G01X1023228D02*
X1034858D01*
G01X1039724Y1507244D02*
X1023228D01*
G01X1043858Y1510197D02*
X1023228D01*
G01X1076791Y1510965D02*
X1023228D01*
G01X1043858Y1511358D02*
X1023622D01*
G01X1083228Y1511398D02*
X1043858D01*
G01X1083228Y1513248D02*
X1043858D01*
G01Y1513287D02*
X1023622D01*
G01X1076791Y1513681D02*
X1023228D01*
G01X1043858Y1514449D02*
X1023228D01*
G01X1039724Y1517402D02*
X1023228D01*
G01X1043858Y1519370D02*
X1040709D01*
G01X1023228D02*
X1034858D01*
G01X1076791Y1520965D02*
X1041052D01*
G01X1043858Y1521161D02*
X1023228D01*
G01X1083228Y1521398D02*
X1041102D01*
G01X1040615Y1521555D02*
X1040464D01*
G01X1040615Y1523091D02*
X1040464D01*
G01X1083228Y1523248D02*
X1041102D01*
G01X1043858Y1523484D02*
X1023228D01*
G01X1076791Y1523681D02*
X1041052D01*
G01X1043858Y1525276D02*
X1040709D01*
G01X1023228D02*
X1034858D01*
G01X1039724Y1527244D02*
X1023228D01*
G01X1043858Y1530197D02*
X1023228D01*
G01X1076791Y1530965D02*
X1041052D01*
G01X1043858Y1531161D02*
X1023228D01*
G01X1083228Y1531398D02*
X1041102D01*
G01X1040615Y1531555D02*
X1040464D01*
G01X1040615Y1533091D02*
X1040464D01*
G01X1083228Y1533248D02*
X1041102D01*
G01X1043858Y1533484D02*
X1023228D01*
G01X1076791Y1533681D02*
X1041052D01*
G01X1043858Y1534449D02*
X1023228D01*
G01X1039724Y1537402D02*
X1023228D01*
G01X1043858Y1539370D02*
X1040709D01*
G01X1023228D02*
X1034858D01*
G01X1076791Y1540965D02*
X1041052D01*
G01X1043858Y1541161D02*
X1023228D01*
G01X1083228Y1541398D02*
X1041102D01*
G01X1040615Y1541555D02*
X1040464D01*
G01X1040626Y1521438D02*
X1040615Y1521555D01*
G01X1040626Y1531438D02*
X1040615Y1531555D01*
G01X1040626Y1541438D02*
X1040615Y1541555D01*
G01Y1543091D02*
X1040464D01*
G01X1083228Y1543248D02*
X1041102D01*
G01X1043858Y1543484D02*
X1023228D01*
G01X1076791Y1543681D02*
X1041052D01*
G01X1040967Y1520970D02*
X1041052Y1520965D01*
G01X1040967Y1530970D02*
X1041052Y1530965D01*
G01X1040967Y1540970D02*
X1041052Y1540965D01*
G01X1039921Y1510965D02*
X1035984Y1511358D01*
G01X1041087Y1520976D02*
X1041204Y1520965D01*
G01X1041087Y1530976D02*
X1041204Y1530965D01*
G01X1041087Y1540976D02*
X1041204Y1540965D01*
G01X1040464Y1521555D02*
X1040481Y1521411D01*
X1040531Y1521280D01*
X1040615Y1521161D01*
G01X1040464Y1531555D02*
X1040481Y1531411D01*
X1040531Y1531280D01*
X1040615Y1531161D01*
G01X1040464Y1541555D02*
X1040481Y1541411D01*
X1040531Y1541280D01*
X1040615Y1541161D01*
G01X1040887Y1520988D02*
X1040969Y1520970D01*
G01X1040887Y1530988D02*
X1040969Y1530970D01*
G01X1040887Y1540988D02*
X1040969Y1540970D01*
G01X1040978Y1521010D02*
X1041090Y1520976D01*
G01X1040978Y1531010D02*
X1041090Y1530976D01*
G01X1040978Y1541010D02*
X1041090Y1540976D01*
G01X1040810Y1521016D02*
X1040889Y1520987D01*
G01X1040810Y1531016D02*
X1040889Y1530987D01*
G01X1040810Y1541016D02*
X1040889Y1540987D01*
G01X1040626Y1521440D02*
X1040660Y1521328D01*
G01X1040626Y1531440D02*
X1040660Y1531328D01*
G01X1040626Y1541440D02*
X1040660Y1541328D01*
G01X1040737Y1521055D02*
X1040812Y1521015D01*
G01X1040876Y1521064D02*
X1040980Y1521009D01*
G01X1040737Y1531055D02*
X1040812Y1531015D01*
G01X1040876Y1531064D02*
X1040980Y1531009D01*
G01X1040737Y1541055D02*
X1040812Y1541015D01*
G01X1040876Y1541064D02*
X1040980Y1541009D01*
G01X1040671Y1521104D02*
X1040739Y1521054D01*
G01X1040671Y1531104D02*
X1040739Y1531054D01*
G01X1040671Y1541104D02*
X1040739Y1541054D01*
G01X1040878Y1521063D02*
X1040787Y1521137D01*
G01X1040878Y1531063D02*
X1040787Y1531137D01*
G01X1040878Y1541063D02*
X1040787Y1541137D01*
G01X1040672Y1521103D02*
X1040612Y1521161D01*
G01X1040672Y1531103D02*
X1040612Y1531161D01*
G01X1040672Y1541103D02*
X1040612Y1541161D01*
G01X1023228Y1511752D02*
X1023622Y1511358D01*
G01X1040713Y1521228D02*
X1040787Y1521137D01*
G01X1040713Y1531228D02*
X1040787Y1531137D01*
G01X1040713Y1541228D02*
X1040787Y1541137D01*
G01X1040659Y1521330D02*
X1040714Y1521226D01*
G01X1040659Y1531330D02*
X1040714Y1531226D01*
G01X1040659Y1541330D02*
X1040714Y1541226D01*
G01X1032087Y1507244D02*
G03X1031102Y1506260I-1J-984D01*
G01Y1538386D02*
G03X1032087Y1537402I984J0D01*
G01Y1527244D02*
G03X1031102Y1526260I-1J-984D01*
G01Y1518386D02*
G03X1032087Y1517402I984J0D01*
G01X1040709Y1506260D02*
G03X1039724Y1507244I-984J0D01*
G01X1040709Y1526260D02*
G03X1039724Y1527244I-984J0D01*
G01Y1517402D02*
G03X1040709Y1518386I1J984D01*
G01X1039724Y1537402D02*
G03X1040709Y1538386I1J984D01*
G01X1041102Y1503248D02*
G03X1040709Y1502854I1J-394D01*
G01X1041102Y1523248D02*
G03X1040709Y1522854I1J-394D01*
G01Y1521791D02*
G03X1041102Y1521398I393J0D01*
G01Y1543248D02*
G03X1040709Y1542854I1J-394D01*
G01Y1541791D02*
G03X1041102Y1541398I393J0D01*
G01Y1533248D02*
G03X1040709Y1532854I1J-394D01*
G01Y1531791D02*
G03X1041102Y1531398I393J0D01*
G01X997340Y1539430D02*
X997178Y1539373D01*
G01X998521Y1539430D02*
X998359Y1539373D01*
G01X997340Y1529430D02*
X997178Y1529373D01*
G01X998521Y1529430D02*
X998359Y1529373D01*
G01X997340Y1519430D02*
X997178Y1519373D01*
G01X998521Y1519430D02*
X998359Y1519373D01*
G01X997340Y1509430D02*
X997178Y1509373D01*
G01X998521Y1509430D02*
X998359Y1509373D01*
G01X997181Y1539374D02*
X997031Y1539282D01*
G01X998362Y1539374D02*
X998213Y1539282D01*
G01X997181Y1529374D02*
X997031Y1529282D01*
G01X998362Y1529374D02*
X998213Y1529282D01*
G01X997181Y1519374D02*
X997031Y1519282D01*
G01X998362Y1519374D02*
X998213Y1519282D01*
G01X997181Y1509374D02*
X997031Y1509282D01*
G01X998362Y1509374D02*
X998213Y1509282D01*
G01X997034Y1539284D02*
X996903Y1539160D01*
G01X998215Y1539284D02*
X998084Y1539160D01*
G01X997034Y1529284D02*
X996903Y1529160D01*
G01X998215Y1529284D02*
X998084Y1529160D01*
G01X997034Y1519284D02*
X996903Y1519160D01*
G01X998215Y1519284D02*
X998084Y1519160D01*
G01X997034Y1509284D02*
X996903Y1509160D01*
G01X998215Y1509284D02*
X998084Y1509160D01*
G01X996796Y1539009D02*
X996903Y1539160D01*
G01X997977Y1539009D02*
X998084Y1539160D01*
G01X996796Y1529009D02*
X996903Y1529160D01*
G01X997977Y1529009D02*
X998084Y1529160D01*
G01X996796Y1519009D02*
X996903Y1519160D01*
G01X997977Y1519009D02*
X998084Y1519160D01*
G01X996796Y1509009D02*
X996903Y1509160D01*
G01X997977Y1509009D02*
X998084Y1509160D01*
G01X996798Y1539012D02*
X996718Y1538839D01*
G01X997979Y1539012D02*
X997899Y1538839D01*
G01X996798Y1529012D02*
X996718Y1528839D01*
G01X997979Y1529012D02*
X997899Y1528839D01*
G01X996798Y1519012D02*
X996718Y1518839D01*
G01X997979Y1519012D02*
X997899Y1518839D01*
G01X996798Y1509012D02*
X996718Y1508839D01*
G01X997979Y1509012D02*
X997899Y1508839D01*
G01X996719Y1538843D02*
X996670Y1538656D01*
G01X997900Y1538843D02*
X997851Y1538656D01*
G01X996719Y1528843D02*
X996670Y1528656D01*
G01X997900Y1528843D02*
X997851Y1528656D01*
G01X996719Y1518843D02*
X996670Y1518656D01*
G01X997900Y1518843D02*
X997851Y1518656D01*
G01X996719Y1508843D02*
X996670Y1508656D01*
G01X997900Y1508843D02*
X997851Y1508656D01*
G01X996670Y1538659D02*
X996654Y1538465D01*
G01X996670Y1528659D02*
X996654Y1528465D01*
G01X997851Y1538659D02*
X997835Y1538465D01*
G01X996670Y1518659D02*
X996654Y1518465D01*
G01X997851Y1528659D02*
X997835Y1528465D01*
G01X996670Y1508659D02*
X996654Y1508465D01*
G01X997851Y1518659D02*
X997835Y1518465D01*
G01X997851Y1508659D02*
X997835Y1508465D01*
G01X998519Y1509429D02*
X998687Y1509449D01*
G01X997337Y1509429D02*
X997506Y1509449D01*
G01X998519Y1519429D02*
X998687Y1519449D01*
G01X997337Y1519429D02*
X997506Y1519449D01*
G01X996670Y1505987D02*
X996654Y1506181D01*
G01X996670Y1515987D02*
X996654Y1516181D01*
G01X997851Y1505987D02*
X997835Y1506181D01*
G01X996670Y1525987D02*
X996654Y1526181D01*
G01X997851Y1515987D02*
X997835Y1516181D01*
G01X996670Y1535987D02*
X996654Y1536181D01*
G01X997851Y1525987D02*
X997835Y1526181D01*
G01X997851Y1535987D02*
X997835Y1536181D01*
G01X996654Y1538465D02*
Y1536181D01*
G01Y1528465D02*
Y1526181D01*
G01Y1518465D02*
Y1516181D01*
G01Y1508465D02*
Y1506181D01*
G01X997835Y1538465D02*
Y1536181D01*
G01Y1528465D02*
Y1526181D01*
G01Y1518465D02*
Y1516181D01*
G01Y1508465D02*
Y1506181D01*
G01X1002362Y1549449D02*
Y1545197D01*
G01Y1539449D02*
Y1535197D01*
G01Y1529449D02*
Y1525197D01*
G01Y1519449D02*
Y1515197D01*
G01Y1509449D02*
Y1505197D01*
G01X1003543Y1549449D02*
Y1545197D01*
G01Y1539449D02*
Y1535197D01*
G01Y1529449D02*
Y1525197D01*
G01Y1519449D02*
Y1515197D01*
G01Y1509449D02*
Y1505197D01*
G01X1004733Y1549449D02*
Y1545197D01*
G01Y1539449D02*
Y1535197D01*
G01Y1529449D02*
Y1525197D01*
G01Y1519449D02*
Y1515197D01*
G01Y1509449D02*
Y1505197D01*
G01X1005335Y1549449D02*
Y1545197D01*
G01Y1539449D02*
Y1535197D01*
G01Y1529449D02*
Y1525197D01*
G01Y1519449D02*
Y1515197D01*
G01Y1509449D02*
Y1505197D01*
G01X998519Y1529429D02*
X998687Y1529449D01*
G01X997337Y1529429D02*
X997506Y1529449D01*
G01X998519Y1539429D02*
X998687Y1539449D01*
G01X997337Y1539429D02*
X997506Y1539449D01*
G01X1026378Y1505197D02*
X997506D01*
G01X997835Y1506181D02*
X996654D01*
G01X997835Y1508465D02*
X996654D01*
G01X1026378Y1509449D02*
X997506D01*
G01X1026378Y1515197D02*
X997506D01*
G01X997835Y1516181D02*
X996654D01*
G01X997835Y1518465D02*
X996654D01*
G01X1026378Y1519449D02*
X997506D01*
G01X1026378Y1525197D02*
X997506D01*
G01X997835Y1526181D02*
X996654D01*
G01X997835Y1528465D02*
X996654D01*
G01X1026378Y1529449D02*
X997506D01*
G01X1026378Y1535197D02*
X997506D01*
G01X997835Y1536181D02*
X996654D01*
G01X997835Y1538465D02*
X996654D01*
G01X1026378Y1539449D02*
X997506D01*
G01X1026378Y1545197D02*
X997506D01*
G01X997337Y1505216D02*
X997506Y1505197D01*
G01X998519Y1505216D02*
X998687Y1505197D01*
G01X997337Y1515216D02*
X997506Y1515197D01*
G01X998519Y1515216D02*
X998687Y1515197D01*
G01X997337Y1525216D02*
X997506Y1525197D01*
G01X998519Y1525216D02*
X998687Y1525197D01*
G01X997337Y1535216D02*
X997506Y1535197D01*
G01X998519Y1535216D02*
X998687Y1535197D01*
G01X997337Y1545216D02*
X997506Y1545197D01*
G01X998519Y1545216D02*
X998687Y1545197D01*
G01X996670Y1505990D02*
X996719Y1505803D01*
G01X997851Y1505990D02*
X997900Y1505803D01*
G01X996670Y1515990D02*
X996719Y1515803D01*
G01X997851Y1515990D02*
X997900Y1515803D01*
G01X996670Y1525990D02*
X996719Y1525803D01*
G01X997851Y1525990D02*
X997900Y1525803D01*
G01X996670Y1535990D02*
X996719Y1535803D01*
G01X997851Y1535990D02*
X997900Y1535803D01*
G01X997178Y1505272D02*
X997340Y1505215D01*
G01X998359Y1505272D02*
X998521Y1505215D01*
G01X997178Y1515272D02*
X997340Y1515215D01*
G01X998359Y1515272D02*
X998521Y1515215D01*
G01X997178Y1525272D02*
X997340Y1525215D01*
G01X998359Y1525272D02*
X998521Y1525215D01*
G01X997178Y1535272D02*
X997340Y1535215D01*
G01X998359Y1535272D02*
X998521Y1535215D01*
G01X997178Y1545272D02*
X997340Y1545215D01*
G01X998359Y1545272D02*
X998521Y1545215D01*
G01X997031Y1505363D02*
X997181Y1505271D01*
G01X998213Y1505363D02*
X998362Y1505271D01*
G01X997031Y1515363D02*
X997181Y1515271D01*
G01X998213Y1515363D02*
X998362Y1515271D01*
G01X996796Y1505636D02*
X996903Y1505485D01*
G01X997977Y1505636D02*
X998084Y1505485D01*
G01X996796Y1515636D02*
X996903Y1515485D01*
G01X997977Y1515636D02*
X998084Y1515485D01*
G01X996718Y1505806D02*
X996798Y1505633D01*
G01X997899Y1505806D02*
X997979Y1505633D01*
G01X996718Y1515806D02*
X996798Y1515633D01*
G01X997899Y1515806D02*
X997979Y1515633D01*
G01X996718Y1525806D02*
X996798Y1525633D01*
G01X997899Y1525806D02*
X997979Y1525633D01*
G01X996718Y1535806D02*
X996798Y1535633D01*
G01X997899Y1535806D02*
X997979Y1535633D01*
G01X997031Y1525363D02*
X997181Y1525271D01*
G01X998213Y1525363D02*
X998362Y1525271D01*
G01X997031Y1535363D02*
X997181Y1535271D01*
G01X998213Y1535363D02*
X998362Y1535271D01*
G01X997034Y1505361D02*
X996903Y1505485D01*
G01X998215Y1505361D02*
X998084Y1505485D01*
G01X997034Y1515361D02*
X996903Y1515485D01*
G01X998215Y1515361D02*
X998084Y1515485D01*
G01X997034Y1525361D02*
X996903Y1525485D01*
G01X998215Y1525361D02*
X998084Y1525485D01*
G01X997034Y1535361D02*
X996903Y1535485D01*
G01X998215Y1535361D02*
X998084Y1535485D01*
G01X996796Y1525636D02*
X996903Y1525485D01*
G01X997977Y1525636D02*
X998084Y1525485D01*
G01X996796Y1535636D02*
X996903Y1535485D01*
G01X997977Y1535636D02*
X998084Y1535485D01*
G01X1041090Y1583670D02*
X1040978Y1583636D01*
G01X1040889Y1583658D02*
X1040810Y1583629D01*
G01X1040812Y1583630D02*
X1040737Y1583590D01*
G01X1040980Y1583637D02*
X1040876Y1583581D01*
G01X1040739Y1583591D02*
X1040671Y1583541D01*
G01X1040878Y1583582D02*
X1040787Y1583508D01*
G01X1040672Y1583543D02*
X1040612Y1583484D01*
G01X1040713Y1583417D02*
X1040787Y1583508D01*
G01X1040615Y1583484D02*
X1040531Y1583366D01*
X1040481Y1583234D01*
X1040464Y1583091D01*
G01X1040714Y1583419D02*
X1040659Y1583315D01*
G01X1040660Y1583317D02*
X1040626Y1583205D01*
G01Y1583207D02*
X1040615Y1583091D01*
G01X1040969Y1583675D02*
X1040887Y1583657D01*
G01X1014457Y1589449D02*
Y1585197D01*
G01X1015060Y1589449D02*
Y1585197D01*
G01X1015663Y1589449D02*
Y1585197D01*
G01X1019600Y1589449D02*
Y1585197D01*
G01X1020781Y1589449D02*
Y1585197D01*
G01X1021962Y1589449D02*
Y1585197D01*
G01X1024409Y1589449D02*
Y1585197D01*
G01X1025591Y1589449D02*
Y1585197D01*
G01X1026378D02*
Y1579449D01*
G01X1027165Y1583484D02*
Y1581161D01*
G01X1029134Y1585276D02*
Y1579370D01*
G01X1031102Y1586260D02*
Y1578386D01*
G01X1031496Y1585276D02*
Y1579370D01*
G01X1032299Y1585276D02*
Y1579370D01*
G01X1034055Y1585276D02*
Y1579370D01*
G01X1034858Y1585276D02*
Y1579370D01*
G01X1040048Y1590965D02*
Y1583484D01*
G01X1040464Y1583091D02*
Y1581555D01*
G01X1040615Y1583091D02*
Y1581555D01*
G01X1040709Y1586260D02*
Y1578386D01*
G01X1044646Y1581398D02*
Y1583248D01*
G01X1040615Y1583091D02*
X1040626Y1583205D01*
G01X1041087Y1583669D02*
X1041204Y1583681D01*
G01X1040626Y1581438D02*
X1040615Y1581555D01*
G01X1040967Y1583675D02*
X1041052Y1583681D01*
G01X1039724Y1577402D02*
X1023228D01*
G01X1043858Y1579370D02*
X1040709D01*
G01X1023228D02*
X1034858D01*
G01X1076791Y1580965D02*
X1041052D01*
G01X1043858Y1581161D02*
X1023228D01*
G01X1083228Y1581398D02*
X1041102D01*
G01X1040615Y1581555D02*
X1040464D01*
G01X1040615Y1583091D02*
X1040464D01*
G01X1083228Y1583248D02*
X1041102D01*
G01X1043858Y1583484D02*
X1023228D01*
G01X1076791Y1583681D02*
X1041052D01*
G01X1040967Y1580970D02*
X1041052Y1580965D01*
G01X1041087Y1580976D02*
X1041204Y1580965D01*
G01X1040887Y1580988D02*
X1040969Y1580970D01*
G01X1040626Y1581440D02*
X1040660Y1581328D01*
G01X1040978Y1581010D02*
X1041090Y1580976D01*
G01X1040810Y1581016D02*
X1040889Y1580987D01*
G01X1040737Y1581055D02*
X1040812Y1581015D01*
G01X1040876Y1581064D02*
X1040980Y1581009D01*
G01X1040615Y1581161D02*
X1040531Y1581280D01*
X1040481Y1581411D01*
X1040464Y1581555D01*
G01X1040615Y1581161D02*
X1040532Y1581280D01*
X1040482Y1581411D01*
X1040464Y1581555D01*
G01X1040659Y1581330D02*
X1040714Y1581226D01*
G01X1040671Y1581104D02*
X1040739Y1581054D01*
G01X1040878Y1581063D02*
X1040787Y1581137D01*
G01X1040672Y1581103D02*
X1040612Y1581161D01*
G01X1040713Y1581228D02*
X1040787Y1581137D01*
G01X1031102Y1578386D02*
G03X1032087Y1577402I984J0D01*
G01X1039724D02*
G03X1040709Y1578386I1J984D01*
G01X1041102Y1583248D02*
G03X1040709Y1582854I1J-394D01*
G01Y1581791D02*
G03X1041102Y1581398I393J0D01*
G01X997340Y1579430D02*
X997178Y1579373D01*
G01X998521Y1579430D02*
X998359Y1579373D01*
G01X997181Y1579374D02*
X997031Y1579282D01*
G01X998362Y1579374D02*
X998213Y1579282D01*
G01X997034Y1579284D02*
X996903Y1579160D01*
G01X998215Y1579284D02*
X998084Y1579160D01*
G01X996796Y1579009D02*
X996903Y1579160D01*
G01X997977Y1579009D02*
X998084Y1579160D01*
G01X996798Y1579012D02*
X996718Y1578839D01*
G01X997979Y1579012D02*
X997899Y1578839D01*
G01X996719Y1578843D02*
X996670Y1578656D01*
G01X997900Y1578843D02*
X997851Y1578656D01*
G01X996670Y1578659D02*
X996654Y1578465D01*
G01X997851Y1578659D02*
X997835Y1578465D01*
G01X996670Y1575987D02*
X996654Y1576181D01*
G01X997851Y1575987D02*
X997835Y1576181D01*
G01X996654Y1578465D02*
Y1576181D01*
G01X997835Y1578465D02*
Y1576181D01*
G01X1002362Y1589449D02*
Y1585197D01*
G01X1003543Y1589449D02*
Y1585197D01*
G01X1004733Y1589449D02*
Y1585197D01*
G01X1005335Y1589449D02*
Y1585197D01*
G01X998519Y1579429D02*
X998687Y1579449D01*
G01X997337Y1579429D02*
X997506Y1579449D01*
G01X997835Y1576181D02*
X996654D01*
G01X997835Y1578465D02*
X996654D01*
G01X1026378Y1579449D02*
X997506D01*
G01X1026378Y1585197D02*
X997506D01*
G01X996670Y1575990D02*
X996719Y1575803D01*
G01X997851Y1575990D02*
X997900Y1575803D01*
G01X997337Y1585216D02*
X997506Y1585197D01*
G01X998519Y1585216D02*
X998687Y1585197D01*
G01X996718Y1575806D02*
X996798Y1575633D01*
G01X997899Y1575806D02*
X997979Y1575633D01*
G01X997178Y1585272D02*
X997340Y1585215D01*
G01X998359Y1585272D02*
X998521Y1585215D01*
G01X1038446Y1645236D02*
X1037219Y1644528D01*
G01X1045139Y1645295D02*
X1044083Y1644685D01*
G01X1038446Y1640236D02*
X1037219Y1639528D01*
G01X1045139Y1640295D02*
X1044083Y1639685D01*
G01X1038446Y1635236D02*
X1037219Y1634528D01*
G01X1045139Y1635295D02*
X1044083Y1634685D01*
G01X1038446Y1630236D02*
X1037219Y1629528D01*
G01X1045139Y1630295D02*
X1044083Y1629685D01*
G01X1038446Y1625236D02*
X1037219Y1624528D01*
G01X1045139Y1625295D02*
X1044083Y1624685D01*
G01X1038446Y1620236D02*
X1037219Y1619528D01*
G01X1045139Y1620295D02*
X1044083Y1619685D01*
G01X1034449Y1645118D02*
X1033465Y1644134D01*
G01X1034449Y1644528D02*
X1033524Y1643602D01*
G01X1034449Y1640118D02*
X1033465Y1639134D01*
G01X1034449Y1639528D02*
X1033524Y1638602D01*
G01X1034449Y1635118D02*
X1033465Y1634134D01*
G01X1034449Y1634528D02*
X1033524Y1633602D01*
G01X1033465Y1629134D02*
X1034449Y1630118D01*
G01Y1629528D02*
X1033524Y1628602D01*
G01X1034449Y1625118D02*
X1033465Y1624134D01*
G01X1034449Y1624528D02*
X1033524Y1623602D01*
G01X1034449Y1620118D02*
X1033465Y1619134D01*
G01X1034449Y1619528D02*
X1033465Y1618543D01*
G01X1021700Y1609449D02*
Y1609374D01*
G01X1023228Y1617756D02*
Y1615787D01*
G01X1026378Y1611358D02*
Y1609449D01*
G01X1032421Y1647087D02*
Y1645118D01*
G01Y1642087D02*
Y1640118D01*
G01Y1637087D02*
Y1635118D01*
G01Y1632087D02*
Y1630118D01*
G01Y1627087D02*
Y1625118D01*
G01Y1622087D02*
Y1620118D01*
G01X1032665Y1647087D02*
Y1645118D01*
G01Y1642087D02*
Y1640118D01*
G01Y1637087D02*
Y1635118D01*
G01Y1632087D02*
Y1630118D01*
G01Y1627087D02*
Y1625118D01*
G01Y1622087D02*
Y1620118D01*
G01X1033071Y1647087D02*
Y1645118D01*
G01Y1642087D02*
Y1640118D01*
G01Y1637087D02*
Y1635118D01*
G01Y1632087D02*
Y1630118D01*
G01Y1627087D02*
Y1625118D01*
G01Y1622087D02*
Y1620118D01*
G01X1033465Y1681811D02*
Y1615394D01*
G01X1034449Y1647677D02*
Y1644528D01*
G01Y1642677D02*
Y1639528D01*
G01Y1637677D02*
Y1634528D01*
G01Y1632677D02*
Y1629528D01*
G01Y1627677D02*
Y1624528D01*
G01Y1622677D02*
Y1619528D01*
G01X1039764Y1644724D02*
Y1644606D01*
G01Y1647598D02*
Y1647480D01*
G01Y1639724D02*
Y1639606D01*
G01Y1642598D02*
Y1642480D01*
G01Y1637598D02*
Y1637480D01*
G01Y1634724D02*
Y1634606D01*
G01Y1632598D02*
Y1632480D01*
G01Y1627598D02*
Y1627480D01*
G01Y1629724D02*
Y1629606D01*
G01Y1624724D02*
Y1624606D01*
G01Y1622598D02*
Y1622480D01*
G01Y1619724D02*
Y1619606D01*
G01X1047205Y1646831D02*
Y1645374D01*
G01Y1641831D02*
Y1640374D01*
G01Y1636831D02*
Y1635374D01*
G01Y1631831D02*
Y1630374D01*
G01Y1626831D02*
Y1625374D01*
G01Y1621831D02*
Y1620374D01*
G01X1048142Y1646831D02*
Y1645374D01*
G01Y1641831D02*
Y1640374D01*
G01Y1636831D02*
Y1635374D01*
G01Y1631831D02*
Y1630374D01*
G01Y1626831D02*
Y1625374D01*
G01Y1621831D02*
Y1620374D01*
G01X1048704Y1646831D02*
Y1645374D01*
G01Y1641831D02*
Y1640374D01*
G01Y1636831D02*
Y1635374D01*
G01Y1631831D02*
Y1630374D01*
G01Y1626831D02*
Y1625374D01*
G01Y1621831D02*
Y1620374D01*
G01X1051969Y1647677D02*
Y1644528D01*
G01Y1642677D02*
Y1639528D01*
G01Y1637677D02*
Y1634528D01*
G01Y1632677D02*
Y1629528D01*
G01Y1627677D02*
Y1624528D01*
G01Y1622677D02*
Y1619528D01*
G01X1053937Y1647087D02*
Y1645118D01*
G01Y1642087D02*
Y1640118D01*
G01Y1637087D02*
Y1635118D01*
G01Y1632087D02*
Y1630118D01*
G01Y1627087D02*
Y1625118D01*
G01Y1622087D02*
Y1620118D01*
G01X1043858Y1605276D02*
X1040709D01*
G01X1034858D02*
X1023228D01*
G01X1039724Y1607244D02*
X1023103D01*
G01X1082244Y1611398D02*
X1043858D01*
G01X1034252Y1619331D02*
X1033465D01*
G01X1051969Y1619528D02*
X1034449D01*
G01X1043787Y1619606D02*
X1039764D01*
G01X1083228Y1620118D02*
X1034449D01*
G01X1039173Y1620315D02*
X1038741D01*
G01X1079931Y1620374D02*
X1045434D01*
G01X1079931Y1621831D02*
X1045434D01*
G01X1039173Y1621890D02*
X1038741D01*
G01X1083228Y1622087D02*
X1034449D01*
G01X1043787Y1622598D02*
X1039764D01*
G01X1051969Y1622677D02*
X1034449D01*
G01X1034252Y1622874D02*
X1033465D01*
G01X1034252Y1624331D02*
X1033465D01*
G01X1051969Y1624528D02*
X1034449D01*
G01X1043787Y1624606D02*
X1039764D01*
G01X1083228Y1625118D02*
X1034449D01*
G01X1039173Y1625315D02*
X1038741D01*
G01X1079931Y1625374D02*
X1045434D01*
G01X1079931Y1626831D02*
X1045434D01*
G01X1039173Y1626890D02*
X1038741D01*
G01X1083228Y1627087D02*
X1034449D01*
G01X1043787Y1627598D02*
X1039764D01*
G01X1051969Y1627677D02*
X1034449D01*
G01X1034252Y1627874D02*
X1033465D01*
G01X1034252Y1629331D02*
X1033465D01*
G01X1051969Y1629528D02*
X1034449D01*
G01X1043787Y1629606D02*
X1039764D01*
G01X1083228Y1630118D02*
X1034449D01*
G01X1039173Y1630315D02*
X1038741D01*
G01X1079931Y1630374D02*
X1045434D01*
G01X1079931Y1631831D02*
X1045434D01*
G01X1039173Y1631890D02*
X1038741D01*
G01X1083228Y1632087D02*
X1034449D01*
G01X1043787Y1632598D02*
X1039764D01*
G01X1051969Y1632677D02*
X1034449D01*
G01X1034252Y1632874D02*
X1033465D01*
G01X1034252Y1634331D02*
X1033465D01*
G01X1051969Y1634528D02*
X1034449D01*
G01X1043787Y1634606D02*
X1039764D01*
G01X1083228Y1635118D02*
X1034449D01*
G01X1039173Y1635315D02*
X1038741D01*
G01X1079931Y1635374D02*
X1045434D01*
G01X1079931Y1636831D02*
X1045434D01*
G01X1039173Y1636890D02*
X1038741D01*
G01X1083228Y1637087D02*
X1034449D01*
G01X1043787Y1637598D02*
X1039764D01*
G01X1051969Y1637677D02*
X1034449D01*
G01X1034252Y1637874D02*
X1033465D01*
G01X1034252Y1639331D02*
X1033465D01*
G01X1051969Y1639528D02*
X1034449D01*
G01X1043787Y1639606D02*
X1039764D01*
G01X1083228Y1640118D02*
X1034449D01*
G01X1039173Y1640315D02*
X1038741D01*
G01X1079931Y1640374D02*
X1045434D01*
G01X1079931Y1641831D02*
X1045434D01*
G01X1039173Y1641890D02*
X1038741D01*
G01X1083228Y1642087D02*
X1034449D01*
G01X1043787Y1642598D02*
X1039764D01*
G01X1051969Y1642677D02*
X1034449D01*
G01X1034252Y1642874D02*
X1033465D01*
G01X1034252Y1644331D02*
X1033465D01*
G01X1051969Y1644528D02*
X1034449D01*
G01X1043787Y1644606D02*
X1039764D01*
G01X1083228Y1645118D02*
X1034449D01*
G01X1039173Y1645315D02*
X1038741D01*
G01X1079931Y1645374D02*
X1045434D01*
G01X1079931Y1646831D02*
X1045434D01*
G01X1039173Y1646890D02*
X1038741D01*
G01X1083228Y1647087D02*
X1034449D01*
G01X1043787Y1647598D02*
X1039764D01*
G01X1051969Y1647677D02*
X1034449D01*
G01X1034252Y1647874D02*
X1033465D01*
G01X1039921Y1610965D02*
X1035984Y1611358D01*
G01X1038446Y1621969D02*
X1037219Y1622677D01*
G01X1045139Y1621910D02*
X1044083Y1622519D01*
G01X1038446Y1626969D02*
X1037219Y1627677D01*
G01X1045139Y1626910D02*
X1044083Y1627519D01*
G01X1038446Y1631969D02*
X1037219Y1632677D01*
G01X1045139Y1631910D02*
X1044083Y1632519D01*
G01X1038446Y1636969D02*
X1037219Y1637677D01*
G01X1045139Y1636910D02*
X1044083Y1637519D01*
G01X1038446Y1641969D02*
X1037219Y1642677D01*
G01X1045139Y1641910D02*
X1044083Y1642519D01*
G01X1038446Y1646969D02*
X1037219Y1647677D01*
G01X1045139Y1646910D02*
X1044083Y1647519D01*
G01X1034449Y1622087D02*
X1033465Y1623071D01*
G01X1033524Y1623602D02*
X1034449Y1622677D01*
G01X1033465Y1628071D02*
X1034449Y1627087D01*
G01X1033524Y1628602D02*
X1034449Y1627677D01*
G01X1033465Y1633071D02*
X1034449Y1632087D01*
G01X1033524Y1633602D02*
X1034449Y1632677D01*
G01X1033465Y1638071D02*
X1034449Y1637087D01*
G01X1033524Y1638602D02*
X1034449Y1637677D01*
G01X1033465Y1643071D02*
X1034449Y1642087D01*
G01X1033524Y1643602D02*
X1034449Y1642677D01*
G01X1033465Y1648071D02*
X1034449Y1647087D01*
G01X1033524Y1648602D02*
X1034449Y1647677D01*
G01X1023228Y1606260D02*
G03X1019291Y1610197I-3937J0D01*
G01X1032087Y1607244D02*
G03X1031102Y1606260I-1J-984D01*
G01X1038741Y1620315D02*
G03X1038446Y1620236I0J-591D01*
G01X1039764Y1619724D02*
G03X1039173Y1620315I-591J0D01*
G01Y1621890D02*
G03X1039764Y1622480I0J591D01*
G01X1038446Y1621969D02*
G03X1038741Y1621890I295J511D01*
G01Y1625315D02*
G03X1038446Y1625236I0J-591D01*
G01X1039764Y1624724D02*
G03X1039173Y1625315I-591J0D01*
G01Y1626890D02*
G03X1039764Y1627480I0J591D01*
G01X1038446Y1626969D02*
G03X1038741Y1626890I295J511D01*
G01Y1630315D02*
G03X1038446Y1630236I0J-591D01*
G01Y1631969D02*
G03X1038741Y1631890I295J511D01*
G01Y1635315D02*
G03X1038446Y1635236I0J-591D01*
G01Y1636969D02*
G03X1038741Y1636890I295J511D01*
G01Y1640315D02*
G03X1038446Y1640236I0J-591D01*
G01Y1641969D02*
G03X1038741Y1641890I295J511D01*
G01Y1645315D02*
G03X1038446Y1645236I0J-591D01*
G01Y1646969D02*
G03X1038741Y1646890I295J511D01*
G01X1039764Y1629724D02*
G03X1039173Y1630315I-591J0D01*
G01Y1631890D02*
G03X1039764Y1632480I0J591D01*
G01Y1634724D02*
G03X1039173Y1635315I-591J0D01*
G01Y1636890D02*
G03X1039764Y1637480I0J591D01*
G01Y1639724D02*
G03X1039173Y1640315I-591J0D01*
G01Y1641890D02*
G03X1039764Y1642480I0J591D01*
G01Y1644724D02*
G03X1039173Y1645315I-591J0D01*
G01Y1646890D02*
G03X1039764Y1647480I0J591D01*
G01X1040709Y1606260D02*
G03X1039724Y1607244I-984J0D01*
G01X1043787Y1619606D02*
G03X1044083Y1619685I1J591D01*
G01X1045434Y1620374D02*
G03X1045139Y1620295I0J-591D01*
G01Y1621910D02*
G03X1045434Y1621831I295J511D01*
G01X1044083Y1622519D02*
G03X1043787Y1622598I-295J-511D01*
G01Y1624606D02*
G03X1044083Y1624685I1J591D01*
G01X1045434Y1625374D02*
G03X1045139Y1625295I0J-591D01*
G01X1044083Y1627519D02*
G03X1043787Y1627598I-295J-511D01*
G01Y1629606D02*
G03X1044083Y1629685I1J591D01*
G01Y1632519D02*
G03X1043787Y1632598I-295J-511D01*
G01Y1634606D02*
G03X1044083Y1634685I1J591D01*
G01Y1637519D02*
G03X1043787Y1637598I-295J-511D01*
G01Y1639606D02*
G03X1044083Y1639685I1J591D01*
G01Y1642519D02*
G03X1043787Y1642598I-295J-511D01*
G01Y1644606D02*
G03X1044083Y1644685I1J591D01*
G01Y1647519D02*
G03X1043787Y1647598I-295J-511D01*
G01X1045139Y1626910D02*
G03X1045434Y1626831I295J511D01*
G01Y1630374D02*
G03X1045139Y1630295I0J-591D01*
G01Y1631910D02*
G03X1045434Y1631831I295J511D01*
G01Y1635374D02*
G03X1045139Y1635295I0J-591D01*
G01Y1636910D02*
G03X1045434Y1636831I295J511D01*
G01Y1640374D02*
G03X1045139Y1640295I0J-591D01*
G01Y1641910D02*
G03X1045434Y1641831I295J511D01*
G01Y1645374D02*
G03X1045139Y1645295I0J-591D01*
G01Y1646910D02*
G03X1045434Y1646831I295J511D01*
G01X1040889Y1603658D02*
X1040810Y1603629D01*
G01X1041090Y1603670D02*
X1040978Y1603636D01*
G01X1040812Y1603630D02*
X1040737Y1603590D01*
G01X1040980Y1603637D02*
X1040876Y1603581D01*
G01X1040739Y1603591D02*
X1040671Y1603541D01*
G01X1040672Y1603543D02*
X1040612Y1603484D01*
G01X1040878Y1603582D02*
X1040787Y1603508D01*
G01X1023228Y1592894D02*
X1023622Y1593287D01*
G01X1040612Y1603484D02*
X1040671Y1603541D01*
G01X1040615Y1603484D02*
X1040531Y1603366D01*
X1040481Y1603234D01*
X1040464Y1603091D01*
G01X1040713Y1603417D02*
X1040787Y1603508D01*
G01X1040714Y1603419D02*
X1040659Y1603315D01*
G01X1040660Y1603317D02*
X1040626Y1603205D01*
G01Y1603207D02*
X1040615Y1603091D01*
G01X1014457Y1609449D02*
Y1605197D01*
G01Y1599449D02*
Y1595197D01*
G01X1015060Y1609449D02*
Y1605197D01*
G01Y1599449D02*
Y1595197D01*
G01X1015663Y1609449D02*
Y1605197D01*
G01Y1599449D02*
Y1595197D01*
G01X1019600Y1609449D02*
Y1605197D01*
G01Y1599449D02*
Y1595197D01*
G01X1020781Y1609449D02*
Y1605197D01*
G01Y1599449D02*
Y1595197D01*
G01X1021962Y1609449D02*
Y1605197D01*
G01Y1599449D02*
Y1595197D01*
G01X1023622Y1591358D02*
Y1590197D01*
G01Y1593287D02*
Y1594449D01*
G01X1024409Y1609449D02*
Y1605197D01*
G01Y1599449D02*
Y1595197D01*
G01X1025591Y1609449D02*
Y1605197D01*
G01Y1599449D02*
Y1595197D01*
G01X1026378Y1605197D02*
Y1599449D01*
G01Y1595197D02*
Y1593287D01*
G01Y1591358D02*
Y1589449D01*
G01X1027165Y1603484D02*
Y1601161D01*
G01X1029134Y1605276D02*
Y1599370D01*
G01X1031102Y1606260D02*
Y1598386D01*
G01X1031496Y1605276D02*
Y1599370D01*
G01X1032299Y1605276D02*
Y1599370D01*
G01X1034055Y1605276D02*
Y1599370D01*
G01X1034858Y1605276D02*
Y1599370D01*
G01X1039921Y1610965D02*
Y1593681D01*
G01X1040048Y1610965D02*
Y1603484D01*
G01Y1601161D02*
Y1593681D01*
G01X1040201Y1610965D02*
Y1593681D01*
G01X1040464Y1603091D02*
Y1601555D01*
G01X1040615D02*
Y1603091D01*
G01X1040709Y1606260D02*
Y1598386D01*
G01X1044646Y1601398D02*
Y1603248D01*
G01X1040969Y1603675D02*
X1040887Y1603657D01*
G01X1039921Y1593681D02*
X1035984Y1593287D01*
G01X1040626Y1601438D02*
X1040615Y1601555D01*
G01X1041087Y1603669D02*
X1041204Y1603681D01*
G01X1040967Y1603675D02*
X1041052Y1603681D01*
G01X1043858Y1585276D02*
X1040709D01*
G01X1023228D02*
X1034858D01*
G01X1039724Y1587244D02*
X1023228D01*
G01X1043858Y1590197D02*
X1023228D01*
G01Y1590965D02*
X1076791D01*
G01X1023622Y1591358D02*
X1043858D01*
G01X1083228Y1591398D02*
X1043858D01*
G01X1083228Y1593248D02*
X1043858D01*
G01Y1593287D02*
X1023622D01*
G01X1076791Y1593681D02*
X1023228D01*
G01X1043858Y1594449D02*
X1023228D01*
G01X1039724Y1597402D02*
X1023228D01*
G01X1043858Y1599370D02*
X1040709D01*
G01X1034858D02*
X1023228D01*
G01X1076791Y1600965D02*
X1041052D01*
G01X1043858Y1601161D02*
X1023228D01*
G01X1083228Y1601398D02*
X1041102D01*
G01X1040615Y1601555D02*
X1040464D01*
G01X1040615Y1603091D02*
X1040464D01*
G01X1083228Y1603248D02*
X1041102D01*
G01X1043858Y1603484D02*
X1023228D01*
G01X1076791Y1603681D02*
X1041052D01*
G01X1040967Y1600970D02*
X1041052Y1600965D01*
G01X1039921Y1590965D02*
X1035984Y1591358D01*
G01X1041087Y1600976D02*
X1041204Y1600965D01*
G01X1040626Y1601440D02*
X1040660Y1601328D01*
G01X1040887Y1600988D02*
X1040969Y1600970D01*
G01X1040978Y1601010D02*
X1041090Y1600976D01*
G01X1040810Y1601016D02*
X1040889Y1600987D01*
G01X1040659Y1601330D02*
X1040714Y1601226D01*
G01X1040737Y1601055D02*
X1040812Y1601015D01*
G01X1040876Y1601064D02*
X1040980Y1601009D01*
G01X1040671Y1601104D02*
X1040739Y1601054D01*
G01X1040878Y1601063D02*
X1040787Y1601137D01*
G01X1040672Y1601103D02*
X1040612Y1601161D01*
G01X1023228Y1591752D02*
X1023622Y1591358D01*
G01X1040713Y1601228D02*
X1040787Y1601137D01*
G01X1040615Y1601161D02*
X1040531Y1601280D01*
X1040481Y1601411D01*
X1040464Y1601555D01*
G01X1040615Y1601161D02*
X1040532Y1601280D01*
X1040482Y1601411D01*
X1040464Y1601555D01*
G01X1032087Y1587244D02*
G03X1031102Y1586260I-1J-984D01*
G01Y1598386D02*
G03X1032087Y1597402I984J0D01*
G01X1040709Y1586260D02*
G03X1039724Y1587244I-984J0D01*
G01Y1597402D02*
G03X1040709Y1598386I1J984D01*
G01X1041102Y1603248D02*
G03X1040709Y1602854I1J-394D01*
G01Y1601791D02*
G03X1041102Y1601398I393J0D01*
G01X997340Y1609430D02*
X997178Y1609373D01*
G01X998521Y1609430D02*
X998359Y1609373D01*
G01X997181Y1609374D02*
X997031Y1609282D01*
G01X998362Y1609374D02*
X998213Y1609282D01*
G01X1008032Y1647087D02*
X1007839Y1646890D01*
G01X1008275Y1647087D02*
X1008083Y1646890D01*
G01X1008032Y1642087D02*
X1007839Y1641890D01*
G01X1008275Y1642087D02*
X1008083Y1641890D01*
G01X1008032Y1637087D02*
X1007839Y1636890D01*
G01X1008275Y1637087D02*
X1008083Y1636890D01*
G01X1008032Y1632087D02*
X1007839Y1631890D01*
G01X1008275Y1632087D02*
X1008083Y1631890D01*
G01X1008032Y1627087D02*
X1007839Y1626890D01*
G01X1008275Y1627087D02*
X1008083Y1626890D01*
G01X1008032Y1622087D02*
X1007839Y1621890D01*
G01X1008275Y1622087D02*
X1008083Y1621890D01*
G01X995669Y1614803D02*
X996654Y1615787D01*
G01X997034Y1609284D02*
X996903Y1609160D01*
G01X998215Y1609284D02*
X998084Y1609160D01*
G01X996796Y1609009D02*
X996903Y1609160D01*
G01X997977Y1609009D02*
X998084Y1609160D01*
G01X996798Y1609012D02*
X996718Y1608839D01*
G01X997979Y1609012D02*
X997899Y1608839D01*
G01X996719Y1608843D02*
X996670Y1608656D01*
G01X997900Y1608843D02*
X997851Y1608656D01*
G01X996670Y1608659D02*
X996654Y1608465D01*
G01X997851Y1608659D02*
X997835Y1608465D01*
G01X996670Y1605987D02*
X996654Y1606181D01*
G01X997851Y1605987D02*
X997835Y1606181D01*
G01X995669Y1617756D02*
Y1610197D01*
G01X996654Y1615394D02*
Y1610197D01*
G01Y1608465D02*
Y1606181D01*
G01X996890Y1646890D02*
Y1645315D01*
G01Y1641890D02*
Y1640315D01*
G01Y1636890D02*
Y1635315D01*
G01Y1631890D02*
Y1630315D01*
G01Y1626890D02*
Y1625315D01*
G01Y1621890D02*
Y1620315D01*
G01X997480Y1646890D02*
Y1645315D01*
G01Y1641890D02*
Y1640315D01*
G01Y1636890D02*
Y1635315D01*
G01Y1631890D02*
Y1630315D01*
G01Y1626890D02*
Y1625315D01*
G01Y1621890D02*
Y1620315D01*
G01X997835Y1608465D02*
Y1606181D01*
G01X999178Y1611358D02*
Y1610965D01*
G01X999606Y1617756D02*
Y1615787D01*
G01Y1612165D02*
Y1610965D01*
G01X1002362Y1646890D02*
Y1645315D01*
G01Y1641890D02*
Y1640315D01*
G01Y1636890D02*
Y1635315D01*
G01Y1631890D02*
Y1630315D01*
G01Y1626890D02*
Y1625315D01*
G01Y1621890D02*
Y1620315D01*
G01X1002953Y1646890D02*
Y1645315D01*
G01Y1641890D02*
Y1640315D01*
G01Y1636890D02*
Y1635315D01*
G01Y1631890D02*
Y1630315D01*
G01Y1626890D02*
Y1625315D01*
G01Y1621890D02*
Y1620315D01*
G01X1004899Y1646890D02*
Y1645315D01*
G01Y1641890D02*
Y1640315D01*
G01Y1636890D02*
Y1635315D01*
G01Y1631890D02*
Y1630315D01*
G01Y1626890D02*
Y1625315D01*
G01Y1621890D02*
Y1620315D01*
G01X1005142Y1646890D02*
Y1645315D01*
G01Y1641890D02*
Y1640315D01*
G01Y1636890D02*
Y1635315D01*
G01Y1631890D02*
Y1630315D01*
G01Y1626890D02*
Y1625315D01*
G01Y1621890D02*
Y1620315D01*
G01X998519Y1609429D02*
X998687Y1609449D01*
G01X997337Y1609429D02*
X997506Y1609449D01*
G01X997835Y1606181D02*
X996654D01*
G01X997835Y1608465D02*
X996654D01*
G01X1026378Y1609449D02*
X997506D01*
G01X1043858Y1610197D02*
X995669D01*
G01X1076791Y1610965D02*
X999178D01*
G01X1043858Y1611358D02*
X995669D01*
G01X1023228Y1612165D02*
X996654D01*
G01X1033465Y1615394D02*
X995669D01*
G01X1023228Y1615787D02*
X996654D01*
G01X1033465Y1617756D02*
X995669D01*
G01X1033465Y1620118D02*
X1008032D01*
G01X1008083Y1620315D02*
X996890D01*
G01X1008083Y1621890D02*
X996890D01*
G01X1033465Y1622087D02*
X1008032D01*
G01X1033465Y1625118D02*
X1008032D01*
G01X1008083Y1625315D02*
X996890D01*
G01X1008083Y1626890D02*
X996890D01*
G01X1033465Y1627087D02*
X1008032D01*
G01X1033465Y1630118D02*
X1008032D01*
G01X1008083Y1630315D02*
X996890D01*
G01X1008083Y1631890D02*
X996890D01*
G01X1033465Y1632087D02*
X1008032D01*
G01X1033465Y1635118D02*
X1008032D01*
G01X1008083Y1635315D02*
X996890D01*
G01X1008083Y1636890D02*
X996890D01*
G01X1033465Y1637087D02*
X1008032D01*
G01X1033465Y1640118D02*
X1008032D01*
G01X1008083Y1640315D02*
X996890D01*
G01X1008083Y1641890D02*
X996890D01*
G01X1033465Y1642087D02*
X1008032D01*
G01X1033465Y1645118D02*
X1008032D01*
G01X1008083Y1645315D02*
X996890D01*
G01X1008083Y1646890D02*
X996890D01*
G01X1033465Y1647087D02*
X1008032D01*
G01X996718Y1605806D02*
X996798Y1605633D01*
G01X997899Y1605806D02*
X997979Y1605633D01*
G01X996670Y1605990D02*
X996719Y1605803D01*
G01X997851Y1605990D02*
X997900Y1605803D01*
G01X997031Y1605363D02*
X997181Y1605271D01*
G01X998213Y1605363D02*
X998362Y1605271D01*
G01X996796Y1605636D02*
X996903Y1605485D01*
G01X997977Y1605636D02*
X998084Y1605485D01*
G01X997034Y1605361D02*
X996903Y1605485D01*
G01X998215Y1605361D02*
X998084Y1605485D01*
G01X995669Y1613150D02*
X996654Y1612165D01*
G01X1007839Y1620315D02*
X1008032Y1620118D01*
G01X1008083Y1620315D02*
X1008275Y1620118D01*
G01X1007839Y1625315D02*
X1008032Y1625118D01*
G01X1008083Y1625315D02*
X1008275Y1625118D01*
G01X1007839Y1630315D02*
X1008032Y1630118D01*
G01X1008083Y1630315D02*
X1008275Y1630118D01*
G01X1007839Y1635315D02*
X1008032Y1635118D01*
G01X1008083Y1635315D02*
X1008275Y1635118D01*
G01X1007839Y1640315D02*
X1008032Y1640118D01*
G01X1008083Y1640315D02*
X1008275Y1640118D01*
G01X1007839Y1645315D02*
X1008032Y1645118D01*
G01X1008083Y1645315D02*
X1008275Y1645118D01*
G01X997340Y1599430D02*
X997178Y1599373D01*
G01X998521Y1599430D02*
X998359Y1599373D01*
G01X997340Y1589430D02*
X997178Y1589373D01*
G01X998521Y1589430D02*
X998359Y1589373D01*
G01X997181Y1599374D02*
X997031Y1599282D01*
G01X998362Y1599374D02*
X998213Y1599282D01*
G01X997181Y1589374D02*
X997031Y1589282D01*
G01X998362Y1589374D02*
X998213Y1589282D01*
G01X997034Y1599284D02*
X996903Y1599160D01*
G01X998215Y1599284D02*
X998084Y1599160D01*
G01X997034Y1589284D02*
X996903Y1589160D01*
G01X998215Y1589284D02*
X998084Y1589160D01*
G01X996796Y1599009D02*
X996903Y1599160D01*
G01X997977Y1599009D02*
X998084Y1599160D01*
G01X996796Y1589009D02*
X996903Y1589160D01*
G01X997977Y1589009D02*
X998084Y1589160D01*
G01X996798Y1599012D02*
X996718Y1598839D01*
G01X997979Y1599012D02*
X997899Y1598839D01*
G01X996798Y1589012D02*
X996718Y1588839D01*
G01X997979Y1589012D02*
X997899Y1588839D01*
G01X996719Y1598843D02*
X996670Y1598659D01*
X996654Y1598465D01*
G01X996670Y1598656D02*
X996718Y1598839D01*
G01X997900Y1598843D02*
X997851Y1598656D01*
G01X996719Y1588843D02*
X996670Y1588656D01*
G01X997900Y1588843D02*
X997851Y1588656D01*
G01X996670Y1588659D02*
X996654Y1588465D01*
G01X997851Y1598659D02*
X997835Y1598465D01*
G01X997851Y1588659D02*
X997835Y1588465D01*
G01X996670Y1585987D02*
X996654Y1586181D01*
G01X997851Y1585987D02*
X997835Y1586181D01*
G01X997851Y1595987D02*
X997835Y1596181D01*
G01X996654Y1598465D02*
Y1596181D01*
G01Y1588465D02*
Y1586181D01*
G01X997835Y1598465D02*
Y1596181D01*
G01Y1588465D02*
Y1586181D01*
G01X1002362Y1609449D02*
Y1605197D01*
G01Y1599449D02*
Y1595197D01*
G01X1003543Y1609449D02*
Y1605197D01*
G01Y1599449D02*
Y1595197D01*
G01X1004733Y1609449D02*
Y1605197D01*
G01Y1599449D02*
Y1595197D01*
G01X1005335Y1609449D02*
Y1605197D01*
G01Y1599449D02*
Y1595197D01*
G01X998519Y1589429D02*
X998687Y1589449D01*
G01X997337Y1589429D02*
X997506Y1589449D01*
G01X998519Y1599429D02*
X998687Y1599449D01*
G01X997337Y1599429D02*
X997506Y1599449D01*
G01X997835Y1586181D02*
X996654D01*
G01X997835Y1588465D02*
X996654D01*
G01X1026378Y1589449D02*
X997506D01*
G01X1026378Y1595197D02*
X997506D01*
G01X997835Y1596181D02*
X996654D01*
G01X997835Y1598465D02*
X996654D01*
G01X1026378Y1599449D02*
X997506D01*
G01X1026378Y1605197D02*
X997506D01*
G01X996670Y1585990D02*
X996719Y1585803D01*
G01X997851Y1585990D02*
X997900Y1585803D01*
G01X996670Y1595990D02*
X996718Y1595806D01*
X996798Y1595633D01*
G01X997337Y1595216D02*
X997506Y1595197D01*
G01X998519Y1595216D02*
X998687Y1595197D01*
G01X997337Y1605216D02*
X997506Y1605197D01*
G01X998519Y1605216D02*
X998687Y1605197D01*
G01X996718Y1585806D02*
X996798Y1585633D01*
G01X997899Y1585806D02*
X997979Y1585633D01*
G01X997899Y1595806D02*
X997979Y1595633D01*
G01X996719Y1595803D02*
X996670Y1595987D01*
X996654Y1596181D01*
G01X997851Y1595990D02*
X997900Y1595803D01*
G01X997178Y1595272D02*
X997340Y1595215D01*
G01X998359Y1595272D02*
X998521Y1595215D01*
G01X997178Y1605272D02*
X997340Y1605215D01*
G01X998359Y1605272D02*
X998521Y1605215D01*
G01X997031Y1585363D02*
X997181Y1585271D01*
G01X998213Y1585363D02*
X998362Y1585271D01*
G01X997031Y1595363D02*
X997181Y1595271D01*
G01X998213Y1595363D02*
X998362Y1595271D01*
G01X997034Y1585361D02*
X996903Y1585485D01*
G01X998215Y1585361D02*
X998084Y1585485D01*
G01X997034Y1595361D02*
X996903Y1595485D01*
G01X998215Y1595361D02*
X998084Y1595485D01*
G01X996796Y1585636D02*
X996903Y1585485D01*
G01X997977Y1585636D02*
X998084Y1585485D01*
G01X996796Y1595636D02*
X996903Y1595485D01*
G01X997977Y1595636D02*
X998084Y1595485D01*
G01X1038446Y1675236D02*
X1037219Y1674528D01*
G01X1045139Y1675295D02*
X1044083Y1674685D01*
G01X1038446Y1670236D02*
X1037219Y1669528D01*
G01X1045139Y1670295D02*
X1044083Y1669685D01*
G01X1034449Y1675118D02*
X1033465Y1674134D01*
G01X1034449Y1674528D02*
X1033524Y1673602D01*
G01X1034449Y1670118D02*
X1033465Y1669134D01*
G01X1034449Y1669528D02*
X1033524Y1668602D01*
G01X1012362Y1679449D02*
Y1708976D01*
G01X1032421Y1677087D02*
Y1675118D01*
G01Y1672087D02*
Y1670118D01*
G01X1032665Y1677087D02*
Y1675118D01*
G01Y1672087D02*
Y1670118D01*
G01X1033071Y1677087D02*
Y1675118D01*
G01Y1672087D02*
Y1670118D01*
G01X1034449Y1672677D02*
Y1669528D01*
G01Y1674528D02*
Y1677677D01*
G01X1037953Y1679449D02*
Y1707008D01*
G01X1039764Y1677598D02*
Y1677480D01*
G01Y1674724D02*
Y1674606D01*
G01Y1672598D02*
Y1672480D01*
G01Y1669724D02*
Y1669606D01*
G01Y1667598D02*
Y1667480D01*
G01X1047205Y1676831D02*
Y1675374D01*
G01Y1671831D02*
Y1670374D01*
G01Y1666831D02*
Y1665374D01*
G01X1048142Y1676831D02*
Y1675374D01*
G01Y1671831D02*
Y1670374D01*
G01Y1666831D02*
Y1665374D01*
G01X1048704Y1676831D02*
Y1675374D01*
G01Y1671831D02*
Y1670374D01*
G01Y1666831D02*
Y1665374D01*
G01X1051969Y1677677D02*
Y1674528D01*
G01Y1669528D02*
Y1672677D01*
G01X1053937Y1677087D02*
Y1675118D01*
G01Y1672087D02*
Y1670118D01*
G01X1039173Y1665315D02*
X1038741D01*
G01X1079931Y1665374D02*
X1045434D01*
G01X1079931Y1666831D02*
X1045434D01*
G01X1039173Y1666890D02*
X1038741D01*
G01X1083228Y1667087D02*
X1034449D01*
G01X1043787Y1667598D02*
X1039764D01*
G01X1051969Y1667677D02*
X1034449D01*
G01X1034252Y1667874D02*
X1033465D01*
G01X1034252Y1669331D02*
X1033465D01*
G01X1051969Y1669528D02*
X1034449D01*
G01X1043787Y1669606D02*
X1039764D01*
G01X1083228Y1670118D02*
X1034449D01*
G01X1039173Y1670315D02*
X1038741D01*
G01X1079931Y1670374D02*
X1045434D01*
G01X1079931Y1671831D02*
X1045434D01*
G01X1039173Y1671890D02*
X1038741D01*
G01X1083228Y1672087D02*
X1034449D01*
G01X1043787Y1672598D02*
X1039764D01*
G01X1051969Y1672677D02*
X1034449D01*
G01X1034252Y1672874D02*
X1033465D01*
G01X1034252Y1674331D02*
X1033465D01*
G01X1051969Y1674528D02*
X1034449D01*
G01X1043787Y1674606D02*
X1039764D01*
G01X1083228Y1675118D02*
X1034449D01*
G01X1039173Y1675315D02*
X1038741D01*
G01X1079931Y1675374D02*
X1045434D01*
G01X1079931Y1676831D02*
X1045434D01*
G01X1039173Y1676890D02*
X1038741D01*
G01X1083228Y1677087D02*
X1034449D01*
G01X1043787Y1677598D02*
X1039764D01*
G01X1051969Y1677677D02*
X1034449D01*
G01X1034252Y1677874D02*
X1033465D01*
G01X1078504Y1685433D02*
X1043858D01*
G01X1083228Y1691339D02*
X1037953D01*
G01Y1693307D02*
X1083228D01*
G01X1038446Y1666969D02*
X1037219Y1667677D01*
G01X1045139Y1666910D02*
X1044083Y1667519D01*
G01X1038446Y1671969D02*
X1037219Y1672677D01*
G01X1045139Y1671910D02*
X1044083Y1672519D01*
G01X1033465Y1668071D02*
X1034449Y1667087D01*
G01X1033524Y1668602D02*
X1034449Y1667677D01*
G01X1033465Y1673071D02*
X1034449Y1672087D01*
G01X1033524Y1673602D02*
X1034449Y1672677D01*
G01X1033465Y1678071D02*
X1034449Y1677087D01*
G01X1033465Y1678661D02*
X1034449Y1677677D01*
G01X1038446Y1676969D02*
X1037219Y1677677D01*
G01X1045139Y1676910D02*
X1044083Y1677519D01*
G01X1030906Y1694212D02*
G03I-7678J0D01*
G01X1030512D02*
G03I-7284J0D01*
G01D02*
G03I-7284J0D01*
G01X1038446Y1666969D02*
G03X1038741Y1666890I295J511D01*
G01Y1670315D02*
G03X1038446Y1670236I0J-591D01*
G01Y1671969D02*
G03X1038741Y1671890I295J511D01*
G01Y1675315D02*
G03X1038446Y1675236I0J-591D01*
G01Y1676969D02*
G03X1038741Y1676890I295J511D01*
G01X1039173Y1666890D02*
G03X1039764Y1667480I0J591D01*
G01Y1669724D02*
G03X1039173Y1670315I-591J0D01*
G01Y1671890D02*
G03X1039764Y1672480I0J591D01*
G01Y1674724D02*
G03X1039173Y1675315I-591J0D01*
G01Y1676890D02*
G03X1039764Y1677480I0J591D01*
G01X1044083Y1667519D02*
G03X1043787Y1667598I-295J-511D01*
G01Y1669606D02*
G03X1044083Y1669685I1J591D01*
G01Y1672519D02*
G03X1043787Y1672598I-295J-511D01*
G01Y1674606D02*
G03X1044083Y1674685I1J591D01*
G01Y1677519D02*
G03X1043787Y1677598I-295J-511D01*
G01X1045434Y1665374D02*
G03X1045139Y1665295I0J-591D01*
G01Y1666910D02*
G03X1045434Y1666831I295J511D01*
G01Y1670374D02*
G03X1045139Y1670295I0J-591D01*
G01Y1671910D02*
G03X1045434Y1671831I295J511D01*
G01Y1675374D02*
G03X1045139Y1675295I0J-591D01*
G01Y1676910D02*
G03X1045434Y1676831I295J511D01*
G01X1008032Y1677087D02*
X1007839Y1676890D01*
G01X1008275Y1677087D02*
X1008083Y1676890D01*
G01X1008032Y1672087D02*
X1007839Y1671890D01*
G01X1008275Y1672087D02*
X1008083Y1671890D01*
G01X1008032Y1667087D02*
X1007839Y1666890D01*
G01X1008275Y1667087D02*
X1008083Y1666890D01*
G01X996890Y1676890D02*
Y1675315D01*
G01Y1671890D02*
Y1670315D01*
G01Y1666890D02*
Y1665315D01*
G01X997480Y1676890D02*
Y1675315D01*
G01Y1671890D02*
Y1670315D01*
G01Y1666890D02*
Y1665315D01*
G01X1002362Y1676890D02*
Y1675315D01*
G01Y1671890D02*
Y1670315D01*
G01Y1666890D02*
Y1665315D01*
G01X1002953Y1676890D02*
Y1675315D01*
G01Y1671890D02*
Y1670315D01*
G01Y1666890D02*
Y1665315D01*
G01X1004899Y1676890D02*
Y1675315D01*
G01Y1671890D02*
Y1670315D01*
G01Y1666890D02*
Y1665315D01*
G01X1005142Y1676890D02*
Y1675315D01*
G01Y1671890D02*
Y1670315D01*
G01Y1666890D02*
Y1665315D01*
G01X1008425Y1707008D02*
Y1681417D01*
G01X1008083Y1665315D02*
X996890D01*
G01X1008083Y1666890D02*
X996890D01*
G01X1033465Y1667087D02*
X1008032D01*
G01X1033465Y1670118D02*
X1008032D01*
G01X1008083Y1670315D02*
X996890D01*
G01X1008083Y1671890D02*
X996890D01*
G01X1033465Y1672087D02*
X1008032D01*
G01X1033465Y1675118D02*
X1008032D01*
G01X1008083Y1675315D02*
X996890D01*
G01X1008083Y1676890D02*
X996890D01*
G01X1033465Y1677087D02*
X1008032D01*
G01X1037953Y1679449D02*
X1010394D01*
G01X1008425Y1681811D02*
X1033465D01*
G01X1007839Y1670315D02*
X1008032Y1670118D01*
G01X1008083Y1670315D02*
X1008275Y1670118D01*
G01X1007839Y1675315D02*
X1008032Y1675118D01*
G01X1008083Y1675315D02*
X1008275Y1675118D01*
G01X1008425Y1681417D02*
G03X1010394Y1679449I1968J0D01*
G01X1037953Y1707008D02*
G03X1035984Y1708976I-1969J-1D01*
G01D02*
X1010394D01*
G01D02*
G03X1008425Y1707008I-1J-1968D01*
G01X1038446Y1665236D02*
X1037219Y1664528D01*
G01X1045139Y1665295D02*
X1044083Y1664685D01*
G01X1038446Y1660236D02*
X1037219Y1659528D01*
G01X1045139Y1660295D02*
X1044083Y1659685D01*
G01X1038446Y1655236D02*
X1037219Y1654528D01*
G01X1045139Y1655295D02*
X1044083Y1654685D01*
G01X1038446Y1650236D02*
X1037219Y1649528D01*
G01X1045139Y1650295D02*
X1044083Y1649685D01*
G01X1034449Y1665118D02*
X1033465Y1664134D01*
G01X1034449Y1664528D02*
X1033524Y1663602D01*
G01X1034449Y1660118D02*
X1033465Y1659134D01*
G01X1034449Y1659528D02*
X1033524Y1658602D01*
G01X1034449Y1655118D02*
X1033465Y1654134D01*
G01X1034449Y1654528D02*
X1033524Y1653602D01*
G01X1034449Y1650118D02*
X1033465Y1649134D01*
G01X1034449Y1649528D02*
X1033524Y1648602D01*
G01X1032421Y1667087D02*
Y1665118D01*
G01Y1662087D02*
Y1660118D01*
G01Y1657087D02*
Y1655118D01*
G01Y1652087D02*
Y1650118D01*
G01X1032665Y1667087D02*
Y1665118D01*
G01Y1662087D02*
Y1660118D01*
G01Y1657087D02*
Y1655118D01*
G01Y1652087D02*
Y1650118D01*
G01X1033071Y1667087D02*
Y1665118D01*
G01Y1662087D02*
Y1660118D01*
G01Y1657087D02*
Y1655118D01*
G01Y1652087D02*
Y1650118D01*
G01X1034449Y1667677D02*
Y1664528D01*
G01Y1662677D02*
Y1659528D01*
G01Y1657677D02*
Y1654528D01*
G01Y1652677D02*
Y1649528D01*
G01X1039764Y1664724D02*
Y1664606D01*
G01Y1659724D02*
Y1659606D01*
G01Y1662598D02*
Y1662480D01*
G01Y1654724D02*
Y1654606D01*
G01Y1657598D02*
Y1657480D01*
G01Y1649724D02*
Y1649606D01*
G01Y1652598D02*
Y1652480D01*
G01X1047205Y1661831D02*
Y1660374D01*
G01Y1656831D02*
Y1655374D01*
G01Y1651831D02*
Y1650374D01*
G01X1048142Y1661831D02*
Y1660374D01*
G01Y1656831D02*
Y1655374D01*
G01Y1651831D02*
Y1650374D01*
G01X1048704Y1661831D02*
Y1660374D01*
G01Y1656831D02*
Y1655374D01*
G01Y1651831D02*
Y1650374D01*
G01X1051969Y1667677D02*
Y1664528D01*
G01Y1662677D02*
Y1659528D01*
G01Y1657677D02*
Y1654528D01*
G01Y1652677D02*
Y1649528D01*
G01X1053937Y1667087D02*
Y1665118D01*
G01Y1662087D02*
Y1660118D01*
G01Y1657087D02*
Y1655118D01*
G01Y1652087D02*
Y1650118D01*
G01X1034252Y1649331D02*
X1033465D01*
G01X1051969Y1649528D02*
X1034449D01*
G01X1043787Y1649606D02*
X1039764D01*
G01X1083228Y1650118D02*
X1034449D01*
G01X1039173Y1650315D02*
X1038741D01*
G01X1079931Y1650374D02*
X1045434D01*
G01X1079931Y1651831D02*
X1045434D01*
G01X1039173Y1651890D02*
X1038741D01*
G01X1083228Y1652087D02*
X1034449D01*
G01X1043787Y1652598D02*
X1039764D01*
G01X1051969Y1652677D02*
X1034449D01*
G01X1034252Y1652874D02*
X1033465D01*
G01X1034252Y1654331D02*
X1033465D01*
G01X1051969Y1654528D02*
X1034449D01*
G01X1043787Y1654606D02*
X1039764D01*
G01X1083228Y1655118D02*
X1034449D01*
G01X1039173Y1655315D02*
X1038741D01*
G01X1079931Y1655374D02*
X1045434D01*
G01X1079931Y1656831D02*
X1045434D01*
G01X1039173Y1656890D02*
X1038741D01*
G01X1083228Y1657087D02*
X1034449D01*
G01X1043787Y1657598D02*
X1039764D01*
G01X1051969Y1657677D02*
X1034449D01*
G01X1034252Y1657874D02*
X1033465D01*
G01X1034252Y1659331D02*
X1033465D01*
G01X1051969Y1659528D02*
X1034449D01*
G01X1043787Y1659606D02*
X1039764D01*
G01X1083228Y1660118D02*
X1034449D01*
G01X1039173Y1660315D02*
X1038741D01*
G01X1079931Y1660374D02*
X1045434D01*
G01X1079931Y1661831D02*
X1045434D01*
G01X1039173Y1661890D02*
X1038741D01*
G01X1083228Y1662087D02*
X1034449D01*
G01X1043787Y1662598D02*
X1039764D01*
G01X1051969Y1662677D02*
X1034449D01*
G01X1034252Y1662874D02*
X1033465D01*
G01X1034252Y1664331D02*
X1033465D01*
G01X1051969Y1664528D02*
X1034449D01*
G01X1043787Y1664606D02*
X1039764D01*
G01X1083228Y1665118D02*
X1034449D01*
G01X1038446Y1651969D02*
X1037219Y1652677D01*
G01X1045139Y1651910D02*
X1044083Y1652519D01*
G01X1038446Y1656969D02*
X1037219Y1657677D01*
G01X1045139Y1656910D02*
X1044083Y1657519D01*
G01X1038446Y1661969D02*
X1037219Y1662677D01*
G01X1045139Y1661910D02*
X1044083Y1662519D01*
G01X1033465Y1653071D02*
X1034449Y1652087D01*
G01X1033524Y1653602D02*
X1034449Y1652677D01*
G01X1033465Y1658071D02*
X1034449Y1657087D01*
G01X1033524Y1658602D02*
X1034449Y1657677D01*
G01Y1662087D02*
X1033465Y1663071D01*
G01X1033524Y1663602D02*
X1034449Y1662677D01*
G01X1038741Y1650315D02*
G03X1038446Y1650236I0J-591D01*
G01Y1651969D02*
G03X1038741Y1651890I295J511D01*
G01X1039764Y1649724D02*
G03X1039173Y1650315I-591J0D01*
G01Y1651890D02*
G03X1039764Y1652480I0J591D01*
G01X1038741Y1655315D02*
G03X1038446Y1655236I0J-591D01*
G01Y1656969D02*
G03X1038741Y1656890I295J511D01*
G01Y1660315D02*
G03X1038446Y1660236I0J-591D01*
G01Y1661969D02*
G03X1038741Y1661890I295J511D01*
G01Y1665315D02*
G03X1038446Y1665236I0J-591D01*
G01X1039764Y1654724D02*
G03X1039173Y1655315I-591J0D01*
G01Y1656890D02*
G03X1039764Y1657480I0J591D01*
G01Y1659724D02*
G03X1039173Y1660315I-591J0D01*
G01Y1661890D02*
G03X1039764Y1662480I0J591D01*
G01Y1664724D02*
G03X1039173Y1665315I-591J0D01*
G01X1043787Y1649606D02*
G03X1044083Y1649685I1J591D01*
G01Y1652519D02*
G03X1043787Y1652598I-295J-511D01*
G01X1045434Y1650374D02*
G03X1045139Y1650295I0J-591D01*
G01Y1651910D02*
G03X1045434Y1651831I295J511D01*
G01X1043787Y1654606D02*
G03X1044083Y1654685I1J591D01*
G01Y1657519D02*
G03X1043787Y1657598I-295J-511D01*
G01Y1659606D02*
G03X1044083Y1659685I1J591D01*
G01Y1662519D02*
G03X1043787Y1662598I-295J-511D01*
G01Y1664606D02*
G03X1044083Y1664685I1J591D01*
G01X1045434Y1655374D02*
G03X1045139Y1655295I0J-591D01*
G01Y1656910D02*
G03X1045434Y1656831I295J511D01*
G01Y1660374D02*
G03X1045139Y1660295I0J-591D01*
G01Y1661910D02*
G03X1045434Y1661831I295J511D01*
G01X1008032Y1662087D02*
X1007839Y1661890D01*
G01X1008275Y1662087D02*
X1008083Y1661890D01*
G01X1008032Y1657087D02*
X1007839Y1656890D01*
G01X1008275Y1657087D02*
X1008083Y1656890D01*
G01X1008032Y1652087D02*
X1007839Y1651890D01*
G01X1008275Y1652087D02*
X1008083Y1651890D01*
G01X996890Y1661890D02*
Y1660315D01*
G01Y1656890D02*
Y1655315D01*
G01Y1651890D02*
Y1650315D01*
G01X997480Y1661890D02*
Y1660315D01*
G01Y1656890D02*
Y1655315D01*
G01Y1651890D02*
Y1650315D01*
G01X1002362Y1661890D02*
Y1660315D01*
G01Y1656890D02*
Y1655315D01*
G01Y1651890D02*
Y1650315D01*
G01X1002953Y1661890D02*
Y1660315D01*
G01Y1656890D02*
Y1655315D01*
G01Y1651890D02*
Y1650315D01*
G01X1004899Y1661890D02*
Y1660315D01*
G01Y1656890D02*
Y1655315D01*
G01Y1651890D02*
Y1650315D01*
G01X1005142Y1661890D02*
Y1660315D01*
G01Y1656890D02*
Y1655315D01*
G01Y1651890D02*
Y1650315D01*
G01X1033465Y1650118D02*
X1008032D01*
G01X1008083Y1650315D02*
X996890D01*
G01X1008083Y1651890D02*
X996890D01*
G01X1033465Y1652087D02*
X1008032D01*
G01X1033465Y1655118D02*
X1008032D01*
G01X1008083Y1655315D02*
X996890D01*
G01X1008083Y1656890D02*
X996890D01*
G01X1033465Y1657087D02*
X1008032D01*
G01X1033465Y1660118D02*
X1008032D01*
G01X1008083Y1660315D02*
X996890D01*
G01X1008083Y1661890D02*
X996890D01*
G01X1033465Y1662087D02*
X1008032D01*
G01X1033465Y1665118D02*
X1008032D01*
G01X1007839Y1650315D02*
X1008032Y1650118D01*
G01X1008083Y1650315D02*
X1008275Y1650118D01*
G01X1007839Y1655315D02*
X1008032Y1655118D01*
G01X1008083Y1655315D02*
X1008275Y1655118D01*
G01X1007839Y1660315D02*
X1008032Y1660118D01*
G01X1008083Y1660315D02*
X1008275Y1660118D01*
G01X1007839Y1665315D02*
X1008032Y1665118D01*
G01X1008083Y1665315D02*
X1008275Y1665118D01*
G01X1045276Y1732598D02*
X1112953D01*
G03X1127953Y1747598I0J15000D01*
G01Y1977126D01*
G03X1112953Y1992126I-15000J0D01*
G01X1045276D01*
G01X1037402Y1767835D02*
G03X1045276I3937J0D01*
G01Y1737126D02*
G03X1037402I-3937J0D01*
G01X1045276Y1767835D02*
Y1956890D01*
G01Y1732598D02*
Y1737126D01*
G01X991008Y1896639D02*
G03X1005066I7029J-6890D01*
G01X1004041Y1912223D02*
G03I-984J0D01*
G01X1003940Y1899395D02*
G03X1005066Y1896639I3937J0D01*
G01X994001Y1912223D02*
G03I-984J0D01*
G01X1003940Y1903529D02*
G03X992134I-5903J0D01*
G01X1003942D02*
G03X992131I-5905J0D01*
G01X1005911D02*
G03X990163I-7874J0D01*
G01X988982D02*
G03I-985J0D01*
G01X990327Y1908548D02*
G03I-984J0D01*
G01X991008Y1896639D02*
G03X992134Y1899395I-2811J2757D01*
G01X1003942Y1901166D02*
X1011816D01*
G01X1003942Y1903529D02*
Y1901166D01*
G01X1003940Y1899395D02*
Y1903529D01*
G01X992134D02*
Y1899395D01*
G01X992131Y1901166D02*
Y1903529D01*
G01X990163D02*
Y1901166D01*
G01X1009060Y1903529D02*
G03I-984J0D01*
G01X1007715Y1908548D02*
G03I-984J0D01*
G01X1013785Y1889749D02*
Y1903529D01*
G01Y1889749D02*
Y1903529D01*
G01Y1889749D02*
Y1903529D01*
G01X1011816Y1901166D02*
Y1903529D01*
G01X1005911Y1901166D02*
Y1903529D01*
G01X1014799Y1950500D02*
G03I-4299J0D01*
G01X1037402Y1991535D02*
Y2043323D01*
G01Y1987598D02*
G03X1045276I3937J0D01*
G01Y1956890D02*
G03X1037402I-3937J0D01*
G01X1045276Y1987598D02*
Y1992126D01*
G01X1054991Y2437400D02*
Y2418463D01*
G01X1105433Y15000D02*
G03I-4291J0D01*
G01X1089741Y22661D02*
G03I-4000J0D01*
G01X1087741D02*
G03I-2000J0D01*
G01X1126553Y308225D02*
X1129353D01*
G01X1126553Y339720D02*
X1129353D01*
G01X1126553Y371215D02*
X1129353D01*
G01X1126553Y402711D02*
X1129353D01*
G01X1126553Y434206D02*
X1129353D01*
G01X1126553Y465701D02*
X1129353D01*
G01X1127461Y497196D02*
X1128445D01*
G01X1127953Y501133D02*
G03Y493259I0J-3937D01*
G01Y497196D02*
Y496802D01*
G01Y497196D02*
Y497589D01*
G01X1083228Y1428425D02*
X1075354D01*
G01Y1686220D02*
Y1428425D01*
G01X1079882Y1427835D02*
Y1433248D01*
G01X1082652D02*
Y1425065D01*
G01X1083228Y1693307D02*
Y1421339D01*
G01Y1424488D02*
X1078504Y1429213D01*
G01X1076971Y1463700D02*
X1077147Y1463757D01*
G01X1076971Y1453700D02*
X1077147Y1453757D01*
G01X1076971Y1443700D02*
X1077147Y1443757D01*
G01X1076971Y1433700D02*
X1077147Y1433757D01*
G01X1077144Y1463755D02*
X1077306Y1463847D01*
G01X1077144Y1453755D02*
X1077306Y1453847D01*
G01X1077144Y1443755D02*
X1077306Y1443847D01*
G01X1077144Y1433755D02*
X1077306Y1433847D01*
G01X1077303Y1463845D02*
X1077446Y1463969D01*
X1077560Y1464118D01*
X1077646Y1464290D01*
G01X1077303Y1453845D02*
X1077446Y1453969D01*
G01X1077303Y1443845D02*
X1077446Y1443969D01*
G01X1077303Y1433845D02*
X1077446Y1433969D01*
G01X1077562Y1464120D02*
X1077446Y1463969D01*
G01X1077562Y1454120D02*
X1077446Y1453969D01*
G01X1077562Y1444120D02*
X1077446Y1443969D01*
G01X1077562Y1434120D02*
X1077446Y1433969D01*
G01X1077560Y1454118D02*
X1077646Y1454290D01*
G01X1077560Y1444118D02*
X1077646Y1444290D01*
G01X1077560Y1434118D02*
X1077646Y1434290D01*
G01X1076974Y1433700D02*
X1076791Y1433681D01*
G01X1076974Y1443700D02*
X1076791Y1443681D01*
G01X1077645Y1464287D02*
X1077699Y1464474D01*
G01X1077645Y1454287D02*
X1077699Y1454474D01*
G01X1077645Y1444287D02*
X1077699Y1444474D01*
G01X1077645Y1434287D02*
X1077699Y1434474D01*
G01X1076974Y1453700D02*
X1076791Y1453681D01*
G01X1076974Y1463700D02*
X1076791Y1463681D01*
G01X1077717Y1434665D02*
X1077313D01*
G01X1072402Y1434862D02*
X1058622D01*
G01X1072402Y1439783D02*
X1058622D01*
G01X1077717Y1439980D02*
X1077313D01*
G01X1077717Y1444665D02*
X1077313D01*
G01X1072402Y1444862D02*
X1058622D01*
G01X1072402Y1449783D02*
X1058622D01*
G01X1077717Y1449980D02*
X1077313D01*
G01X1077717Y1454665D02*
X1077313D01*
G01X1072402Y1454862D02*
X1058622D01*
G01X1072402Y1459783D02*
X1058622D01*
G01X1077717Y1459980D02*
X1077313D01*
G01X1077717Y1464665D02*
X1077313D01*
G01X1072402Y1464862D02*
X1058622D01*
G01X1077698Y1464471D02*
X1077717Y1464665D01*
G01X1077698Y1454471D02*
X1077717Y1454665D01*
G01X1077698Y1444471D02*
X1077717Y1444665D01*
G01X1077698Y1434471D02*
X1077717Y1434665D01*
G01X1076974Y1440945D02*
X1076791Y1440965D01*
G01X1076974Y1450945D02*
X1076791Y1450965D01*
G01X1076974Y1460945D02*
X1076791Y1460965D01*
G01X1077698Y1440175D02*
X1077717Y1439980D01*
G01X1077698Y1450175D02*
X1077717Y1449980D01*
G01X1077698Y1460175D02*
X1077717Y1459980D01*
G01X1057638Y1458799D02*
Y1455846D01*
G01Y1448799D02*
Y1445846D01*
G01Y1438799D02*
Y1435846D01*
G01X1070257Y1470965D02*
Y1463681D01*
G01Y1460965D02*
Y1453681D01*
G01Y1450965D02*
Y1443681D01*
G01Y1440965D02*
Y1433681D01*
G01X1070410Y1470965D02*
Y1463681D01*
G01Y1460965D02*
Y1453681D01*
G01Y1450965D02*
Y1443681D01*
G01Y1440965D02*
Y1433681D01*
G01X1071050Y1470965D02*
Y1463681D01*
G01Y1460965D02*
Y1453681D01*
G01Y1450965D02*
Y1443681D01*
G01Y1440965D02*
Y1433681D01*
G01X1071417Y1464862D02*
Y1463248D01*
G01Y1461398D02*
Y1459783D01*
G01Y1454862D02*
Y1453248D01*
G01Y1451398D02*
Y1449783D01*
G01Y1444862D02*
Y1443248D01*
G01Y1441398D02*
Y1439783D01*
G01Y1434862D02*
Y1433248D01*
G01X1071858Y1470965D02*
Y1463681D01*
G01Y1460965D02*
Y1453681D01*
G01Y1450965D02*
Y1443681D01*
G01Y1440965D02*
Y1433681D01*
G01X1072402Y1461398D02*
Y1459783D01*
G01Y1454862D02*
Y1453248D01*
G01Y1451398D02*
Y1449783D01*
G01Y1444862D02*
Y1443248D01*
G01Y1441398D02*
Y1439783D01*
G01Y1434862D02*
Y1433248D01*
G01Y1463248D02*
Y1464862D01*
G01X1073386Y1458799D02*
Y1455846D01*
G01Y1448799D02*
Y1445846D01*
G01Y1438799D02*
Y1435846D01*
G01X1073859Y1470965D02*
Y1463681D01*
G01Y1450965D02*
Y1443681D01*
G01Y1433681D02*
Y1440965D01*
G01Y1453681D02*
Y1460965D01*
G01X1077313Y1469980D02*
Y1464665D01*
G01Y1449980D02*
Y1444665D01*
G01Y1434665D02*
Y1439980D01*
G01Y1454665D02*
Y1459980D01*
G01X1077717Y1469980D02*
Y1464665D01*
G01Y1449980D02*
Y1444665D01*
G01Y1439980D02*
Y1434665D01*
G01Y1454665D02*
Y1459980D01*
G01X1080669Y1463248D02*
Y1461398D01*
G01Y1453248D02*
Y1451398D01*
G01Y1443248D02*
Y1441398D01*
G01X1082652Y1463248D02*
Y1461398D01*
G01Y1453248D02*
Y1451398D01*
G01Y1443248D02*
Y1441398D01*
G01X1077147Y1440889D02*
X1076971Y1440946D01*
G01X1077147Y1450889D02*
X1076971Y1450946D01*
G01X1077147Y1460889D02*
X1076971Y1460946D01*
G01X1077306Y1440798D02*
X1077144Y1440890D01*
G01X1077306Y1450798D02*
X1077144Y1450890D01*
G01X1077306Y1460798D02*
X1077144Y1460890D01*
G01X1077699Y1440171D02*
X1077645Y1440358D01*
G01X1077699Y1450171D02*
X1077645Y1450358D01*
G01X1077699Y1460171D02*
X1077645Y1460358D01*
G01X1077303Y1440800D02*
X1077446Y1440676D01*
G01X1077303Y1450800D02*
X1077446Y1450676D01*
G01X1077303Y1460800D02*
X1077446Y1460676D01*
G01X1077562Y1440525D02*
X1077446Y1440676D01*
G01X1077562Y1450525D02*
X1077446Y1450676D01*
G01X1077562Y1460525D02*
X1077446Y1460676D01*
G01X1077646Y1440355D02*
X1077560Y1440528D01*
G01X1077646Y1450355D02*
X1077560Y1450528D01*
G01X1077646Y1460355D02*
X1077560Y1460528D01*
G01X1073386Y1438799D02*
G03X1072402Y1439783I-984J0D01*
G01Y1434862D02*
G03X1073386Y1435846I0J984D01*
G01X1057638Y1445846D02*
G03X1058622Y1444862I984J0D01*
G01X1072402D02*
G03X1073386Y1445846I0J984D01*
G01X1057638Y1435846D02*
G03X1058622Y1434862I984J0D01*
G01Y1439783D02*
G03X1057638Y1438799I0J-984D01*
G01X1058622Y1449783D02*
G03X1057638Y1448799I0J-984D01*
G01Y1455846D02*
G03X1058622Y1454862I984J0D01*
G01Y1459783D02*
G03X1057638Y1458799I0J-984D01*
G01Y1465846D02*
G03X1058622Y1464862I984J0D01*
G01X1073386Y1448799D02*
G03X1072402Y1449783I-984J0D01*
G01Y1464862D02*
G03X1073386Y1465846I0J984D01*
G01X1072402Y1454862D02*
G03X1073386Y1455846I0J984D01*
G01Y1458799D02*
G03X1072402Y1459783I-984J0D01*
G01X1076971Y1493700D02*
X1077147Y1493757D01*
G01X1077144Y1493755D02*
X1077306Y1493847D01*
G01X1077303Y1493845D02*
X1077446Y1493969D01*
G01X1077562Y1494120D02*
X1077446Y1493969D01*
G01X1077560Y1494118D02*
X1077646Y1494290D01*
G01X1077645Y1494287D02*
X1077699Y1494474D01*
G01X1076974Y1493700D02*
X1076791Y1493681D01*
G01X1077698Y1494471D02*
X1077717Y1494665D01*
G01X1072402Y1489783D02*
X1058622D01*
G01X1077717Y1489980D02*
X1077313D01*
G01X1077717Y1494665D02*
X1077313D01*
G01X1072402Y1494862D02*
X1058622D01*
G01X1072402Y1499783D02*
X1058622D01*
G01X1077717Y1499980D02*
X1077313D01*
G01X1077698Y1490175D02*
X1077717Y1489980D01*
G01X1077698Y1500175D02*
X1077717Y1499980D01*
G01X1057638Y1498799D02*
Y1495846D01*
G01Y1488799D02*
Y1485846D01*
G01X1070257Y1500965D02*
Y1493681D01*
G01X1070410Y1500965D02*
Y1493681D01*
G01X1071050Y1500965D02*
Y1493681D01*
G01X1071417Y1501398D02*
Y1499783D01*
G01Y1494862D02*
Y1493248D01*
G01Y1491398D02*
Y1489783D01*
G01X1071858Y1500965D02*
Y1493681D01*
G01X1072402Y1501398D02*
Y1499783D01*
G01Y1494862D02*
Y1493248D01*
G01Y1491398D02*
Y1489783D01*
G01X1073386Y1498799D02*
Y1495846D01*
G01Y1488799D02*
Y1485846D01*
G01X1073859Y1493681D02*
Y1500965D01*
G01X1077313Y1494665D02*
Y1499980D01*
G01X1077717Y1494665D02*
Y1499980D01*
G01X1080669Y1503248D02*
Y1501398D01*
G01Y1493248D02*
Y1491398D01*
G01X1082652Y1503248D02*
Y1501398D01*
G01Y1493248D02*
Y1491398D01*
G01X1076974Y1490945D02*
X1076791Y1490965D01*
G01X1076974Y1500945D02*
X1076791Y1500965D01*
G01X1077147Y1490889D02*
X1076971Y1490946D01*
G01X1077147Y1500889D02*
X1076971Y1500946D01*
G01X1077699Y1490171D02*
X1077645Y1490358D01*
G01X1077699Y1500171D02*
X1077645Y1500358D01*
G01X1077306Y1490798D02*
X1077144Y1490890D01*
G01X1077306Y1500798D02*
X1077144Y1500890D01*
G01X1077303Y1490800D02*
X1077446Y1490676D01*
G01X1077303Y1500800D02*
X1077446Y1500676D01*
G01X1077562Y1490525D02*
X1077446Y1490676D01*
G01X1077562Y1500525D02*
X1077446Y1500676D01*
G01X1077646Y1490355D02*
X1077560Y1490528D01*
G01X1077646Y1500355D02*
X1077560Y1500528D01*
G01X1058622Y1489783D02*
G03X1057638Y1488799I0J-984D01*
G01X1073386D02*
G03X1072402Y1489783I-984J0D01*
G01X1057638Y1495846D02*
G03X1058622Y1494862I984J0D01*
G01Y1499783D02*
G03X1057638Y1498799I0J-984D01*
G01X1072402Y1494862D02*
G03X1073386Y1495846I0J984D01*
G01Y1498799D02*
G03X1072402Y1499783I-984J0D01*
G01X1076971Y1483700D02*
X1077147Y1483757D01*
G01X1076971Y1473700D02*
X1077147Y1473757D01*
G01X1077144Y1483755D02*
X1077303Y1483845D01*
X1077446Y1483969D01*
G01X1077306Y1483847D02*
X1077147Y1483757D01*
G01X1077144Y1473755D02*
X1077306Y1473847D01*
G01X1077303Y1473845D02*
X1077446Y1473969D01*
G01X1077562Y1484120D02*
X1077446Y1483969D01*
G01X1077562Y1474120D02*
X1077446Y1473969D01*
G01X1077560Y1484118D02*
X1077646Y1484290D01*
G01X1077560Y1474118D02*
X1077646Y1474290D01*
G01X1077645Y1484287D02*
X1077699Y1484474D01*
G01X1077645Y1474287D02*
X1077699Y1474474D01*
G01X1076974Y1473700D02*
X1076791Y1473681D01*
G01X1076974Y1483700D02*
X1076791Y1483681D01*
G01X1077698Y1484471D02*
X1077717Y1484665D01*
G01X1077698Y1474471D02*
X1077717Y1474665D01*
G01X1072402Y1469783D02*
X1058622D01*
G01X1077717Y1469980D02*
X1077313D01*
G01X1077717Y1474665D02*
X1077313D01*
G01X1072402Y1474862D02*
X1058622D01*
G01X1072402Y1479783D02*
X1058622D01*
G01X1077717Y1479980D02*
X1077313D01*
G01X1077717Y1484665D02*
X1077313D01*
G01X1072402Y1484862D02*
X1058622D01*
G01X1076974Y1470945D02*
X1076791Y1470965D01*
G01X1076974Y1480945D02*
X1076791Y1480965D01*
G01X1077698Y1470175D02*
X1077717Y1469980D01*
G01X1077698Y1480175D02*
X1077717Y1479980D01*
G01X1057638Y1478799D02*
Y1475846D01*
G01Y1468799D02*
Y1465846D01*
G01X1070257Y1490965D02*
Y1483681D01*
G01Y1480965D02*
Y1473681D01*
G01X1070410Y1490965D02*
Y1483681D01*
G01Y1480965D02*
Y1473681D01*
G01X1071050Y1490965D02*
Y1483681D01*
G01Y1480965D02*
Y1473681D01*
G01X1071417Y1484862D02*
Y1483248D01*
G01Y1481398D02*
Y1479783D01*
G01Y1474862D02*
Y1473248D01*
G01Y1471398D02*
Y1469783D01*
G01X1071858Y1490965D02*
Y1483681D01*
G01Y1480965D02*
Y1473681D01*
G01X1072402Y1484862D02*
Y1483248D01*
G01Y1481398D02*
Y1479783D01*
G01Y1471398D02*
Y1469783D01*
G01Y1474862D02*
Y1473248D01*
G01X1073386Y1478799D02*
Y1475846D01*
G01Y1468799D02*
Y1465846D01*
G01X1073859Y1490965D02*
Y1483681D01*
G01Y1473681D02*
Y1480965D01*
G01X1077313Y1489980D02*
Y1484665D01*
G01Y1474665D02*
Y1479980D01*
G01X1077717Y1489980D02*
Y1484665D01*
G01Y1479980D02*
Y1474665D01*
G01X1079882Y1473248D02*
Y1471398D01*
G01X1080669Y1483248D02*
Y1481398D01*
G01X1082652Y1483248D02*
Y1481398D01*
G01Y1473248D02*
Y1471398D01*
G01X1077147Y1470889D02*
X1076971Y1470946D01*
G01X1077147Y1480889D02*
X1076971Y1480946D01*
G01X1077306Y1470798D02*
X1077144Y1470890D01*
G01X1077699Y1470171D02*
X1077645Y1470358D01*
G01X1077699Y1480171D02*
X1077645Y1480358D01*
G01X1077306Y1480798D02*
X1077144Y1480890D01*
G01X1077303Y1470800D02*
X1077446Y1470676D01*
G01X1077303Y1480800D02*
X1077446Y1480676D01*
G01X1077562Y1470525D02*
X1077446Y1470676D01*
G01X1077562Y1480525D02*
X1077446Y1480676D01*
G01X1077646Y1470355D02*
X1077560Y1470528D01*
G01X1077646Y1480355D02*
X1077560Y1480528D01*
G01X1057638Y1485846D02*
G03X1058622Y1484862I984J0D01*
G01X1057638Y1475846D02*
G03X1058622Y1474862I984J0D01*
G01Y1479783D02*
G03X1057638Y1478799I0J-984D01*
G01X1058622Y1469783D02*
G03X1057638Y1468799I0J-984D01*
G01X1073386D02*
G03X1072402Y1469783I-984J0D01*
G01X1073386Y1478799D02*
G03X1072402Y1479783I-984J0D01*
G01Y1474862D02*
G03X1073386Y1475846I0J984D01*
G01X1072402Y1484862D02*
G03X1073386Y1485846I0J984D01*
G01X1076971Y1573700D02*
X1077147Y1573757D01*
G01X1076971Y1563700D02*
X1077147Y1563757D01*
G01X1076971Y1553700D02*
X1077147Y1553757D01*
G01X1077144Y1573755D02*
X1077306Y1573847D01*
G01X1077144Y1563755D02*
X1077306Y1563847D01*
G01X1077144Y1553755D02*
X1077306Y1553847D01*
G01X1077303Y1573845D02*
X1077446Y1573969D01*
G01X1077303Y1563845D02*
X1077446Y1563969D01*
G01X1077303Y1553845D02*
X1077446Y1553969D01*
G01X1077562Y1574120D02*
X1077446Y1573969D01*
G01X1077562Y1564120D02*
X1077446Y1563969D01*
G01X1077562Y1554120D02*
X1077446Y1553969D01*
G01X1077560Y1574118D02*
X1077646Y1574290D01*
G01X1077560Y1564118D02*
X1077646Y1564290D01*
G01X1077560Y1554118D02*
X1077646Y1554290D01*
G01X1077645Y1574287D02*
X1077699Y1574474D01*
G01X1077645Y1564287D02*
X1077699Y1564474D01*
G01X1077645Y1554287D02*
X1077699Y1554474D01*
G01X1077698Y1574471D02*
X1077717Y1574665D01*
G01X1077698Y1564471D02*
X1077717Y1564665D01*
G01X1077698Y1554471D02*
X1077717Y1554665D01*
G01X1076974Y1553700D02*
X1076791Y1553681D01*
G01X1076974Y1563700D02*
X1076791Y1563681D01*
G01X1076974Y1573700D02*
X1076791Y1573681D01*
G01X1077698Y1550175D02*
X1077717Y1549980D01*
G01X1077698Y1570175D02*
X1077717Y1569980D01*
G01X1057638Y1568799D02*
Y1565846D01*
G01Y1558799D02*
Y1555846D01*
G01Y1548799D02*
Y1545846D01*
G01X1070257Y1580965D02*
Y1573681D01*
G01Y1570965D02*
Y1563681D01*
G01Y1560965D02*
Y1553681D01*
G01X1070410Y1580965D02*
Y1573681D01*
G01Y1570965D02*
Y1563681D01*
G01Y1560965D02*
Y1553681D01*
G01X1071050Y1580965D02*
Y1573681D01*
G01Y1570965D02*
Y1563681D01*
G01Y1560965D02*
Y1553681D01*
G01X1071417Y1574862D02*
Y1573248D01*
G01Y1571398D02*
Y1569783D01*
G01Y1564862D02*
Y1563248D01*
G01Y1561398D02*
Y1559783D01*
G01Y1554862D02*
Y1553248D01*
G01Y1551398D02*
Y1549783D01*
G01X1071858Y1580965D02*
Y1573681D01*
G01Y1570965D02*
Y1563681D01*
G01Y1560965D02*
Y1553681D01*
G01X1072402Y1574862D02*
Y1573248D01*
G01Y1571398D02*
Y1569783D01*
G01Y1561398D02*
Y1559783D01*
G01Y1551398D02*
Y1549783D01*
G01Y1554862D02*
Y1553248D01*
G01Y1563248D02*
Y1564862D01*
G01X1073386Y1568799D02*
Y1565846D01*
G01Y1558799D02*
Y1555846D01*
G01Y1548799D02*
Y1545846D01*
G01X1073859Y1580965D02*
Y1573681D01*
G01Y1570965D02*
Y1563681D01*
G01Y1553681D02*
Y1560965D01*
G01X1077313Y1579980D02*
Y1574665D01*
G01Y1569980D02*
Y1564665D01*
G01Y1554665D02*
Y1559980D01*
G01X1077717Y1579980D02*
Y1574665D01*
G01Y1569980D02*
Y1564665D01*
G01Y1559980D02*
Y1554665D01*
G01X1079882Y1553248D02*
Y1551398D01*
G01X1080669Y1573248D02*
Y1571398D01*
G01Y1563248D02*
Y1561398D01*
G01X1082652Y1573248D02*
Y1571398D01*
G01Y1563248D02*
Y1561398D01*
G01Y1553248D02*
Y1551398D01*
G01X1072402Y1549783D02*
X1058622D01*
G01X1077717Y1549980D02*
X1077313D01*
G01X1077717Y1554665D02*
X1077313D01*
G01X1072402Y1554862D02*
X1058622D01*
G01X1072402Y1559783D02*
X1058622D01*
G01X1077717Y1559980D02*
X1077313D01*
G01X1077717Y1564665D02*
X1077313D01*
G01X1072402Y1564862D02*
X1058622D01*
G01X1072402Y1569783D02*
X1058622D01*
G01X1077717Y1569980D02*
X1077313D01*
G01X1077717Y1574665D02*
X1077313D01*
G01X1072402Y1574862D02*
X1058622D01*
G01X1076974Y1550945D02*
X1076791Y1550965D01*
G01X1076974Y1560945D02*
X1076791Y1560965D01*
G01X1076974Y1570945D02*
X1076791Y1570965D01*
G01X1077699Y1550171D02*
X1077645Y1550358D01*
G01X1077699Y1560171D02*
X1077646Y1560355D01*
X1077560Y1560528D01*
G01X1077147Y1550889D02*
X1076971Y1550946D01*
G01X1077147Y1560889D02*
X1076971Y1560946D01*
G01X1077147Y1570889D02*
X1076971Y1570946D01*
G01X1077306Y1550798D02*
X1077144Y1550890D01*
G01X1077306Y1560798D02*
X1077144Y1560890D01*
G01X1077646Y1550355D02*
X1077560Y1550528D01*
G01X1077646Y1570355D02*
X1077560Y1570528D01*
G01X1077645Y1560358D02*
X1077698Y1560175D01*
X1077717Y1559980D01*
G01X1077699Y1570171D02*
X1077645Y1570358D01*
G01X1077306Y1570798D02*
X1077144Y1570890D01*
G01X1077303Y1550800D02*
X1077446Y1550676D01*
G01X1077303Y1560800D02*
X1077446Y1560676D01*
G01X1077303Y1570800D02*
X1077446Y1570676D01*
G01X1077562Y1550525D02*
X1077446Y1550676D01*
G01X1077562Y1560525D02*
X1077446Y1560676D01*
G01X1077562Y1570525D02*
X1077446Y1570676D01*
G01X1058622Y1549783D02*
G03X1057638Y1548799I0J-984D01*
G01Y1565846D02*
G03X1058622Y1564862I984J0D01*
G01Y1569783D02*
G03X1057638Y1568799I0J-984D01*
G01Y1575846D02*
G03X1058622Y1574862I984J0D01*
G01X1057638Y1555846D02*
G03X1058622Y1554862I984J0D01*
G01Y1559783D02*
G03X1057638Y1558799I0J-984D01*
G01X1073386Y1548799D02*
G03X1072402Y1549783I-984J0D01*
G01X1073386Y1558799D02*
G03X1072402Y1559783I-984J0D01*
G01Y1554862D02*
G03X1073386Y1555846I0J984D01*
G01X1072402Y1564862D02*
G03X1073386Y1565846I0J984D01*
G01Y1568799D02*
G03X1072402Y1569783I-984J0D01*
G01Y1574862D02*
G03X1073386Y1575846I0J984D01*
G01X1076971Y1543700D02*
X1077147Y1543757D01*
G01X1076971Y1533700D02*
X1077147Y1533757D01*
G01X1076971Y1523700D02*
X1077147Y1523757D01*
G01X1076971Y1513700D02*
X1077147Y1513757D01*
G01X1076971Y1503700D02*
X1077147Y1503757D01*
G01X1077144Y1543755D02*
X1077306Y1543847D01*
G01X1077144Y1533755D02*
X1077306Y1533847D01*
G01X1077144Y1523755D02*
X1077306Y1523847D01*
G01X1077144Y1513755D02*
X1077306Y1513847D01*
G01X1077144Y1503755D02*
X1077306Y1503847D01*
G01X1077303Y1543845D02*
X1077446Y1543969D01*
G01X1077303Y1533845D02*
X1077446Y1533969D01*
G01X1077303Y1523845D02*
X1077446Y1523969D01*
G01X1077303Y1513845D02*
X1077446Y1513969D01*
G01X1077303Y1503845D02*
X1077446Y1503969D01*
G01X1077562Y1544120D02*
X1077446Y1543969D01*
G01X1077562Y1534120D02*
X1077446Y1533969D01*
G01X1077562Y1524120D02*
X1077446Y1523969D01*
G01X1077562Y1514120D02*
X1077446Y1513969D01*
G01X1077562Y1504120D02*
X1077446Y1503969D01*
G01X1077560Y1544118D02*
X1077646Y1544290D01*
G01X1077560Y1534118D02*
X1077646Y1534290D01*
G01X1077560Y1524118D02*
X1077646Y1524290D01*
G01X1077560Y1514118D02*
X1077646Y1514290D01*
G01X1077560Y1504118D02*
X1077646Y1504290D01*
G01X1077645Y1544287D02*
X1077699Y1544474D01*
G01X1077645Y1534287D02*
X1077699Y1534474D01*
G01X1077645Y1524287D02*
X1077699Y1524474D01*
G01X1077645Y1514287D02*
X1077699Y1514474D01*
G01X1077645Y1504287D02*
X1077699Y1504474D01*
G01X1076974Y1503700D02*
X1076791Y1503681D01*
G01X1076974Y1513700D02*
X1076791Y1513681D01*
G01X1076974Y1523700D02*
X1076791Y1523681D01*
G01X1077698Y1544471D02*
X1077717Y1544665D01*
G01X1077698Y1534471D02*
X1077717Y1534665D01*
G01X1077698Y1524471D02*
X1077717Y1524665D01*
G01X1077698Y1514471D02*
X1077717Y1514665D01*
G01X1077698Y1504471D02*
X1077717Y1504665D01*
G01X1076974Y1533700D02*
X1076791Y1533681D01*
G01X1076974Y1543700D02*
X1076791Y1543681D01*
G01X1077717Y1504665D02*
X1077313D01*
G01X1072402Y1504862D02*
X1058622D01*
G01X1072402Y1509783D02*
X1058622D01*
G01X1077717Y1509980D02*
X1077313D01*
G01X1077717Y1514665D02*
X1077313D01*
G01X1072402Y1514862D02*
X1058622D01*
G01X1072402Y1519783D02*
X1058622D01*
G01X1077717Y1519980D02*
X1077313D01*
G01X1077717Y1524665D02*
X1077313D01*
G01X1072402Y1524862D02*
X1058622D01*
G01X1072402Y1529783D02*
X1058622D01*
G01X1077717Y1529980D02*
X1077313D01*
G01X1077717Y1534665D02*
X1077313D01*
G01X1072402Y1534862D02*
X1058622D01*
G01X1072402Y1539783D02*
X1058622D01*
G01X1077717Y1539980D02*
X1077313D01*
G01X1077698Y1510175D02*
X1077717Y1509980D01*
G01X1077698Y1520175D02*
X1077717Y1519980D01*
G01X1077698Y1530175D02*
X1077717Y1529980D01*
G01X1077698Y1540175D02*
X1077717Y1539980D01*
G01X1057638Y1538799D02*
Y1535846D01*
G01Y1528799D02*
Y1525846D01*
G01Y1518799D02*
Y1515846D01*
G01Y1508799D02*
Y1505846D01*
G01X1070257Y1550965D02*
Y1543681D01*
G01Y1540965D02*
Y1533681D01*
G01Y1530965D02*
Y1523681D01*
G01Y1520965D02*
Y1513681D01*
G01Y1510965D02*
Y1503681D01*
G01X1070410Y1550965D02*
Y1543681D01*
G01Y1540965D02*
Y1533681D01*
G01Y1530965D02*
Y1523681D01*
G01Y1520965D02*
Y1513681D01*
G01Y1510965D02*
Y1503681D01*
G01X1071050Y1550965D02*
Y1543681D01*
G01Y1540965D02*
Y1533681D01*
G01Y1530965D02*
Y1523681D01*
G01Y1520965D02*
Y1513681D01*
G01Y1510965D02*
Y1503681D01*
G01X1071417Y1544862D02*
Y1543248D01*
G01Y1541398D02*
Y1539783D01*
G01Y1534862D02*
Y1533248D01*
G01Y1531398D02*
Y1529783D01*
G01Y1524862D02*
Y1523248D01*
G01Y1521398D02*
Y1519783D01*
G01Y1514862D02*
Y1513248D01*
G01Y1511398D02*
Y1509783D01*
G01Y1504862D02*
Y1503248D01*
G01X1071858Y1550965D02*
Y1543681D01*
G01Y1540965D02*
Y1533681D01*
G01Y1530965D02*
Y1523681D01*
G01Y1520965D02*
Y1513681D01*
G01Y1510965D02*
Y1503681D01*
G01X1072402Y1541398D02*
Y1539783D01*
G01Y1534862D02*
Y1533248D01*
G01Y1531398D02*
Y1529783D01*
G01Y1524862D02*
Y1523248D01*
G01Y1521398D02*
Y1519783D01*
G01Y1514862D02*
Y1513248D01*
G01Y1511398D02*
Y1509783D01*
G01Y1503248D02*
Y1504862D01*
G01Y1543248D02*
Y1544862D01*
G01X1073386Y1538799D02*
Y1535846D01*
G01Y1528799D02*
Y1525846D01*
G01Y1518799D02*
Y1515846D01*
G01Y1508799D02*
Y1505846D01*
G01X1073859Y1550965D02*
Y1543681D01*
G01Y1530965D02*
Y1523681D01*
G01Y1510965D02*
Y1503681D01*
G01Y1513681D02*
Y1520965D01*
G01Y1533681D02*
Y1540965D01*
G01X1077313Y1549980D02*
Y1544665D01*
G01Y1529980D02*
Y1524665D01*
G01Y1509980D02*
Y1504665D01*
G01Y1514665D02*
Y1519980D01*
G01Y1534665D02*
Y1539980D01*
G01X1077717Y1549980D02*
Y1544665D01*
G01Y1529980D02*
Y1524665D01*
G01Y1519980D02*
Y1514665D01*
G01Y1509980D02*
Y1504665D01*
G01Y1534665D02*
Y1539980D01*
G01X1079882Y1513248D02*
Y1511398D01*
G01X1080669Y1543248D02*
Y1541398D01*
G01Y1533248D02*
Y1531398D01*
G01Y1523248D02*
Y1521398D01*
G01X1082652Y1543248D02*
Y1541398D01*
G01Y1533248D02*
Y1531398D01*
G01Y1523248D02*
Y1521398D01*
G01Y1513248D02*
Y1511398D01*
G01X1077717Y1544665D02*
X1077313D01*
G01X1072402Y1544862D02*
X1058622D01*
G01X1076974Y1510945D02*
X1076791Y1510965D01*
G01X1076974Y1520945D02*
X1076791Y1520965D01*
G01X1076974Y1530945D02*
X1076791Y1530965D01*
G01X1076974Y1540945D02*
X1076791Y1540965D01*
G01X1077147Y1510889D02*
X1076971Y1510946D01*
G01X1077147Y1520889D02*
X1076971Y1520946D01*
G01X1077147Y1530889D02*
X1076971Y1530946D01*
G01X1077147Y1540889D02*
X1076971Y1540946D01*
G01X1077699Y1510171D02*
X1077645Y1510358D01*
G01X1077699Y1520171D02*
X1077645Y1520358D01*
G01X1077699Y1530171D02*
X1077645Y1530358D01*
G01X1077699Y1540171D02*
X1077645Y1540358D01*
G01X1077306Y1510798D02*
X1077144Y1510890D01*
G01X1077306Y1520798D02*
X1077144Y1520890D01*
G01X1077306Y1530798D02*
X1077144Y1530890D01*
G01X1077306Y1540798D02*
X1077144Y1540890D01*
G01X1077303Y1510800D02*
X1077446Y1510676D01*
G01X1077303Y1520800D02*
X1077446Y1520676D01*
G01X1077303Y1530800D02*
X1077446Y1530676D01*
G01X1077562Y1510525D02*
X1077446Y1510676D01*
G01X1077562Y1520525D02*
X1077446Y1520676D01*
G01X1077562Y1530525D02*
X1077446Y1530676D01*
G01X1077646Y1510355D02*
X1077560Y1510528D01*
G01X1077646Y1520355D02*
X1077560Y1520528D01*
G01X1077646Y1530355D02*
X1077560Y1530528D01*
G01X1077646Y1540355D02*
X1077560Y1540528D01*
G01X1077303Y1540800D02*
X1077446Y1540676D01*
G01X1077562Y1540525D02*
X1077446Y1540676D01*
G01X1057638Y1505846D02*
G03X1058622Y1504862I984J0D01*
G01Y1509783D02*
G03X1057638Y1508799I0J-984D01*
G01Y1515846D02*
G03X1058622Y1514862I984J0D01*
G01Y1519783D02*
G03X1057638Y1518799I0J-984D01*
G01Y1535846D02*
G03X1058622Y1534862I984J0D01*
G01Y1539783D02*
G03X1057638Y1538799I0J-984D01*
G01Y1525846D02*
G03X1058622Y1524862I984J0D01*
G01Y1529783D02*
G03X1057638Y1528799I0J-984D01*
G01Y1545846D02*
G03X1058622Y1544862I984J0D01*
G01X1072402Y1504862D02*
G03X1073386Y1505846I0J984D01*
G01Y1508799D02*
G03X1072402Y1509783I-984J0D01*
G01X1073386Y1518799D02*
G03X1072402Y1519783I-984J0D01*
G01Y1514862D02*
G03X1073386Y1515846I0J984D01*
G01X1072402Y1534862D02*
G03X1073386Y1535846I0J984D01*
G01Y1538799D02*
G03X1072402Y1539783I-984J0D01*
G01Y1524862D02*
G03X1073386Y1525846I0J984D01*
G01Y1528799D02*
G03X1072402Y1529783I-984J0D01*
G01Y1544862D02*
G03X1073386Y1545846I0J984D01*
G01X1076971Y1583700D02*
X1077147Y1583757D01*
G01X1077144Y1583755D02*
X1077306Y1583847D01*
G01X1077303Y1583845D02*
X1077446Y1583969D01*
G01X1077562Y1584120D02*
X1077446Y1583969D01*
G01X1077560Y1584118D02*
X1077646Y1584290D01*
G01X1077645Y1584287D02*
X1077699Y1584474D01*
G01X1077698Y1584471D02*
X1077717Y1584665D01*
G01X1076974Y1583700D02*
X1076791Y1583681D01*
G01X1077698Y1580175D02*
X1077717Y1579980D01*
G01X1057638Y1578799D02*
Y1575846D01*
G01X1070257Y1590965D02*
Y1583681D01*
G01X1070410Y1590965D02*
Y1583681D01*
G01X1071050Y1590965D02*
Y1583681D01*
G01X1071417Y1584862D02*
Y1583248D01*
G01Y1581398D02*
Y1579783D01*
G01X1071858Y1590965D02*
Y1583681D01*
G01X1072402Y1581398D02*
Y1579783D01*
G01Y1583248D02*
Y1584862D01*
G01X1073386Y1578799D02*
Y1575846D01*
G01X1073859Y1590965D02*
Y1583681D01*
G01X1077313Y1589980D02*
Y1584665D01*
G01X1077717Y1589980D02*
Y1584665D01*
G01X1080669Y1583248D02*
Y1581398D01*
G01X1082652Y1583248D02*
Y1581398D01*
G01X1072402Y1579783D02*
X1058622D01*
G01X1077717Y1579980D02*
X1077313D01*
G01X1077717Y1584665D02*
X1077313D01*
G01X1072402Y1584862D02*
X1058622D01*
G01X1076974Y1580945D02*
X1076791Y1580965D01*
G01X1077147Y1580889D02*
X1076971Y1580946D01*
G01X1077646Y1580355D02*
X1077560Y1580528D01*
G01X1077699Y1580171D02*
X1077645Y1580358D01*
G01X1077306Y1580798D02*
X1077144Y1580890D01*
G01X1077303Y1580800D02*
X1077446Y1580676D01*
G01X1077562Y1580525D02*
X1077446Y1580676D01*
G01X1058622Y1579783D02*
G03X1057638Y1578799I0J-984D01*
G01Y1585846D02*
G03X1058622Y1584862I984J0D01*
G01X1073386Y1578799D02*
G03X1072402Y1579783I-984J0D01*
G01Y1584862D02*
G03X1073386Y1585846I0J984D01*
G01X1080472Y1645571D02*
X1079931Y1645374D01*
G01X1080472Y1640571D02*
X1079931Y1640374D01*
G01X1080472Y1635571D02*
X1079931Y1635374D01*
G01X1080472Y1630571D02*
X1079931Y1630374D01*
G01X1080472Y1625571D02*
X1079931Y1625374D01*
G01X1080472Y1620571D02*
X1079931Y1620374D01*
G01X1083228Y1612382D02*
X1082244Y1611398D01*
G01X1077698Y1610175D02*
X1077717Y1609980D01*
G01X1057638Y1608799D02*
Y1605846D01*
G01X1058015Y1646831D02*
Y1645374D01*
G01Y1641831D02*
Y1640374D01*
G01Y1636831D02*
Y1635374D01*
G01Y1631831D02*
Y1630374D01*
G01Y1626831D02*
Y1625374D01*
G01Y1621831D02*
Y1620374D01*
G01X1058578Y1646831D02*
Y1645374D01*
G01Y1641831D02*
Y1640374D01*
G01Y1636831D02*
Y1635374D01*
G01Y1631831D02*
Y1630374D01*
G01Y1626831D02*
Y1625374D01*
G01Y1621831D02*
Y1620374D01*
G01X1071417Y1611398D02*
Y1609783D01*
G01X1072402Y1611398D02*
Y1609783D01*
G01X1072795Y1646831D02*
Y1645374D01*
G01Y1641831D02*
Y1640374D01*
G01Y1636831D02*
Y1635374D01*
G01Y1631831D02*
Y1630374D01*
G01Y1626831D02*
Y1625374D01*
G01Y1621831D02*
Y1620374D01*
G01X1073386Y1646831D02*
Y1645374D01*
G01Y1641831D02*
Y1640374D01*
G01Y1636831D02*
Y1635374D01*
G01Y1631831D02*
Y1630374D01*
G01Y1626831D02*
Y1625374D01*
G01Y1621831D02*
Y1620374D01*
G01Y1608799D02*
Y1605846D01*
G01X1075162Y1646831D02*
Y1645374D01*
G01Y1641831D02*
Y1640374D01*
G01Y1636831D02*
Y1635374D01*
G01Y1631831D02*
Y1630374D01*
G01Y1626831D02*
Y1625374D01*
G01Y1621831D02*
Y1620374D01*
G01X1075753Y1646831D02*
Y1645374D01*
G01Y1641831D02*
Y1640374D01*
G01Y1636831D02*
Y1635374D01*
G01Y1631831D02*
Y1630374D01*
G01Y1626831D02*
Y1625374D01*
G01Y1621831D02*
Y1620374D01*
G01X1076737Y1646831D02*
Y1645374D01*
G01Y1641831D02*
Y1640374D01*
G01Y1636831D02*
Y1635374D01*
G01Y1631831D02*
Y1630374D01*
G01Y1626831D02*
Y1625374D01*
G01Y1621831D02*
Y1620374D01*
G01X1077717Y1647087D02*
Y1645118D01*
G01Y1642087D02*
Y1640118D01*
G01Y1637087D02*
Y1635118D01*
G01Y1632087D02*
Y1630118D01*
G01Y1627087D02*
Y1625118D01*
G01Y1622087D02*
Y1620118D01*
G01X1079094Y1642087D02*
Y1640118D01*
G01Y1632087D02*
Y1630118D01*
G01Y1622087D02*
Y1620118D01*
G01Y1625118D02*
Y1627087D01*
G01Y1635118D02*
Y1637087D01*
G01Y1645118D02*
Y1647087D01*
G01X1079882Y1614744D02*
Y1686811D01*
G01X1080472Y1646634D02*
Y1645571D01*
G01Y1641634D02*
Y1640571D01*
G01Y1636634D02*
Y1635571D01*
G01Y1631634D02*
Y1630571D01*
G01Y1626634D02*
Y1625571D01*
G01Y1621634D02*
Y1620571D01*
G01X1082244Y1647087D02*
Y1645118D01*
G01Y1642087D02*
Y1640118D01*
G01Y1637087D02*
Y1635118D01*
G01Y1632087D02*
Y1630118D01*
G01Y1627087D02*
Y1625118D01*
G01Y1622087D02*
Y1620118D01*
G01X1082652Y1650118D02*
Y1647087D01*
G01Y1645118D02*
Y1642087D01*
G01Y1640118D02*
Y1637087D01*
G01Y1635118D02*
Y1632087D01*
G01Y1630118D02*
Y1627087D01*
G01Y1625118D02*
Y1622087D01*
G01Y1620118D02*
Y1614336D01*
G01X1072402Y1609783D02*
X1058622D01*
G01X1077717Y1609980D02*
X1077313D01*
G01X1082244Y1614744D02*
X1079882D01*
G01X1076974Y1610945D02*
X1076791Y1610965D01*
G01X1077147Y1610889D02*
X1076971Y1610946D01*
G01X1077699Y1610171D02*
X1077645Y1610358D01*
G01X1080472Y1621634D02*
X1079931Y1621831D01*
G01X1080472Y1626634D02*
X1079931Y1626831D01*
G01X1080472Y1631634D02*
X1079931Y1631831D01*
G01X1080472Y1636634D02*
X1079931Y1636831D01*
G01X1080472Y1641634D02*
X1079931Y1641831D01*
G01X1080472Y1646634D02*
X1079931Y1646831D01*
G01X1077306Y1610798D02*
X1077144Y1610890D01*
G01X1077303Y1610800D02*
X1077446Y1610676D01*
G01X1082244Y1614744D02*
X1083228Y1613760D01*
G01X1077562Y1610525D02*
X1077446Y1610676D01*
G01X1077646Y1610355D02*
X1077560Y1610528D01*
G01X1058622Y1609783D02*
G03X1057638Y1608799I0J-984D01*
G01X1073386D02*
G03X1072402Y1609783I-984J0D01*
G01X1076971Y1603700D02*
X1077147Y1603757D01*
G01X1076971Y1593700D02*
X1077147Y1593757D01*
G01X1077144Y1603755D02*
X1077306Y1603847D01*
G01X1077144Y1593755D02*
X1077306Y1593847D01*
G01X1077303Y1603845D02*
X1077446Y1603969D01*
G01X1077303Y1593845D02*
X1077446Y1593969D01*
G01X1077562Y1604120D02*
X1077446Y1603969D01*
G01X1077562Y1594120D02*
X1077446Y1593969D01*
G01X1077560Y1604118D02*
X1077646Y1604290D01*
G01X1077560Y1594118D02*
X1077646Y1594290D01*
G01X1077645Y1604287D02*
X1077699Y1604474D01*
G01X1077645Y1594287D02*
X1077699Y1594474D01*
G01X1077698Y1604471D02*
X1077717Y1604665D01*
G01X1077698Y1594471D02*
X1077717Y1594665D01*
G01X1076974Y1593700D02*
X1076791Y1593681D01*
G01X1076974Y1603700D02*
X1076791Y1603681D01*
G01X1077698Y1590175D02*
X1077717Y1589980D01*
G01X1077698Y1600175D02*
X1077717Y1599980D01*
G01X1057638Y1598799D02*
Y1595846D01*
G01Y1588799D02*
Y1585846D01*
G01X1070257Y1610965D02*
Y1603681D01*
G01Y1600965D02*
Y1593681D01*
G01X1070410Y1610965D02*
Y1603681D01*
G01Y1600965D02*
Y1593681D01*
G01X1071050Y1610965D02*
Y1603681D01*
G01Y1600965D02*
Y1593681D01*
G01X1071417Y1604862D02*
Y1603248D01*
G01Y1601398D02*
Y1599783D01*
G01Y1594862D02*
Y1593248D01*
G01Y1591398D02*
Y1589783D01*
G01X1071858Y1610965D02*
Y1603681D01*
G01Y1600965D02*
Y1593681D01*
G01X1072402Y1604862D02*
Y1603248D01*
G01Y1601398D02*
Y1599783D01*
G01Y1594862D02*
Y1593248D01*
G01Y1591398D02*
Y1589783D01*
G01X1073386Y1598799D02*
Y1595846D01*
G01Y1588799D02*
Y1585846D01*
G01X1073859Y1610965D02*
Y1603681D01*
G01Y1593681D02*
Y1600965D01*
G01X1077313Y1609980D02*
Y1604665D01*
G01Y1594665D02*
Y1599980D01*
G01X1077717Y1609980D02*
Y1604665D01*
G01Y1594665D02*
Y1599980D01*
G01X1079882Y1593248D02*
Y1591398D01*
G01X1080669Y1603248D02*
Y1601398D01*
G01X1082652Y1603248D02*
Y1601398D01*
G01Y1593248D02*
Y1591398D01*
G01X1072402Y1589783D02*
X1058622D01*
G01X1077717Y1589980D02*
X1077313D01*
G01X1077717Y1594665D02*
X1077313D01*
G01X1072402Y1594862D02*
X1058622D01*
G01X1072402Y1599783D02*
X1058622D01*
G01X1077717Y1599980D02*
X1077313D01*
G01X1077717Y1604665D02*
X1077313D01*
G01X1072402Y1604862D02*
X1058622D01*
G01X1076974Y1590945D02*
X1076791Y1590965D01*
G01X1076974Y1600945D02*
X1076791Y1600965D01*
G01X1077147Y1590889D02*
X1076971Y1590946D01*
G01X1077147Y1600889D02*
X1076971Y1600946D01*
G01X1077646Y1590355D02*
X1077560Y1590528D01*
G01X1077699Y1590171D02*
X1077645Y1590358D01*
G01X1077699Y1600171D02*
X1077645Y1600358D01*
G01X1077306Y1590798D02*
X1077144Y1590890D01*
G01X1077306Y1600798D02*
X1077144Y1600890D01*
G01X1077303Y1590800D02*
X1077446Y1590676D01*
G01X1077303Y1600800D02*
X1077446Y1600676D01*
G01X1077562Y1590525D02*
X1077446Y1590676D01*
G01X1077562Y1600525D02*
X1077446Y1600676D01*
G01X1077646Y1600355D02*
X1077560Y1600528D01*
G01X1058622Y1589783D02*
G03X1057638Y1588799I0J-984D01*
G01Y1595846D02*
G03X1058622Y1594862I984J0D01*
G01Y1599783D02*
G03X1057638Y1598799I0J-984D01*
G01X1073386Y1588799D02*
G03X1072402Y1589783I-984J0D01*
G01X1073386Y1598799D02*
G03X1072402Y1599783I-984J0D01*
G01Y1594862D02*
G03X1073386Y1595846I0J984D01*
G01X1057638Y1605846D02*
G03X1058622Y1604862I984J0D01*
G01X1072402D02*
G03X1073386Y1605846I0J984D01*
G01X1080472Y1675571D02*
X1079931Y1675374D01*
G01X1080472Y1670571D02*
X1079931Y1670374D01*
G01X1080472Y1665571D02*
X1079931Y1665374D01*
G01X1083228Y1690157D02*
X1078504Y1685433D01*
G01X1058015Y1676831D02*
Y1675374D01*
G01Y1671831D02*
Y1670374D01*
G01Y1666831D02*
Y1665374D01*
G01X1058578Y1676831D02*
Y1675374D01*
G01Y1671831D02*
Y1670374D01*
G01Y1666831D02*
Y1665374D01*
G01X1072795Y1676831D02*
Y1675374D01*
G01Y1671831D02*
Y1670374D01*
G01Y1666831D02*
Y1665374D01*
G01X1073386Y1676831D02*
Y1675374D01*
G01Y1671831D02*
Y1670374D01*
G01Y1666831D02*
Y1665374D01*
G01X1075162Y1676831D02*
Y1675374D01*
G01Y1671831D02*
Y1670374D01*
G01Y1666831D02*
Y1665374D01*
G01X1075753Y1676831D02*
Y1675374D01*
G01Y1671831D02*
Y1670374D01*
G01Y1666831D02*
Y1665374D01*
G01X1076737Y1676831D02*
Y1675374D01*
G01Y1671831D02*
Y1670374D01*
G01Y1666831D02*
Y1665374D01*
G01X1077717Y1677087D02*
Y1675118D01*
G01Y1672087D02*
Y1670118D01*
G01X1079094Y1677087D02*
Y1675118D01*
G01Y1672087D02*
Y1670118D01*
G01X1080472Y1676634D02*
Y1675571D01*
G01Y1671634D02*
Y1670571D01*
G01Y1666634D02*
Y1665571D01*
G01X1082244Y1677087D02*
Y1675118D01*
G01Y1672087D02*
Y1670118D01*
G01X1082652Y1689581D02*
Y1677087D01*
G01Y1675118D02*
Y1672087D01*
G01Y1670118D02*
Y1667087D01*
G01X1083228Y1686220D02*
X1075354D01*
G01X1080472Y1666634D02*
X1079931Y1666831D01*
G01X1080472Y1671634D02*
X1079931Y1671831D01*
G01X1080472Y1676634D02*
X1079931Y1676831D01*
G01X1080472Y1660571D02*
X1079931Y1660374D01*
G01X1080472Y1655571D02*
X1079931Y1655374D01*
G01X1080472Y1650571D02*
X1079931Y1650374D01*
G01X1058015Y1661831D02*
Y1660374D01*
G01Y1656831D02*
Y1655374D01*
G01Y1651831D02*
Y1650374D01*
G01X1058578Y1661831D02*
Y1660374D01*
G01Y1656831D02*
Y1655374D01*
G01Y1651831D02*
Y1650374D01*
G01X1072795Y1661831D02*
Y1660374D01*
G01Y1656831D02*
Y1655374D01*
G01Y1651831D02*
Y1650374D01*
G01X1073386Y1661831D02*
Y1660374D01*
G01Y1656831D02*
Y1655374D01*
G01Y1651831D02*
Y1650374D01*
G01X1075162Y1661831D02*
Y1660374D01*
G01Y1656831D02*
Y1655374D01*
G01Y1651831D02*
Y1650374D01*
G01X1075753Y1661831D02*
Y1660374D01*
G01Y1656831D02*
Y1655374D01*
G01Y1651831D02*
Y1650374D01*
G01X1076737Y1661831D02*
Y1660374D01*
G01Y1656831D02*
Y1655374D01*
G01Y1651831D02*
Y1650374D01*
G01X1077717Y1667087D02*
Y1665118D01*
G01Y1662087D02*
Y1660118D01*
G01Y1657087D02*
Y1655118D01*
G01Y1652087D02*
Y1650118D01*
G01X1079094Y1667087D02*
Y1665118D01*
G01Y1662087D02*
Y1660118D01*
G01Y1657087D02*
Y1655118D01*
G01Y1652087D02*
Y1650118D01*
G01X1080472Y1661634D02*
Y1660571D01*
G01Y1656634D02*
Y1655571D01*
G01Y1651634D02*
Y1650571D01*
G01X1082244Y1667087D02*
Y1665118D01*
G01Y1662087D02*
Y1660118D01*
G01Y1652087D02*
Y1650118D01*
G01Y1655118D02*
Y1657087D01*
G01X1082652Y1665118D02*
Y1662087D01*
G01Y1660118D02*
Y1657087D01*
G01Y1655118D02*
Y1652087D01*
G01X1080472Y1651634D02*
X1079931Y1651831D01*
G01X1080472Y1656634D02*
X1079931Y1656831D01*
G01X1080472Y1661634D02*
X1079931Y1661831D01*
G01X1089741Y1967598D02*
G03I-4000J0D01*
G01X1087741D02*
G03I-2000J0D01*
G01X1105433Y1977126D02*
G03I-4291J0D01*
G01X1127953D02*
Y2039006D01*
G01X1274660Y-172119D02*
Y-191056D01*
G01X1262451Y2249512D02*
X1263172Y2251677D01*
X1264616Y2253121D01*
X1266781Y2253843D01*
X1268947Y2253121D01*
X1270390Y2251677D01*
X1271112Y2249512D01*
X1270390Y2247347D01*
X1268947Y2245903D01*
X1266781Y2245181D01*
X1264616Y2245903D01*
X1263172Y2247347D01*
X1262451Y2249512D01*
G01X1263172Y2243016D02*
X1270390Y2256008D01*
G01X1360613Y2243016D02*
X1253789D01*
G01X1274660Y2437400D02*
Y2418463D01*
G01X1342004Y320666D02*
X1342491Y322109D01*
X1343953Y322831D01*
X1345414Y322109D01*
X1345901Y320666D01*
X1345414Y319222D01*
X1344927Y318500D01*
X1343953Y317778D01*
X1342978Y318500D01*
X1342491Y319222D01*
X1342004Y320666D01*
Y323553D01*
X1342491Y324996D01*
X1342978Y325718D01*
X1343953Y326440D01*
X1344927Y325718D01*
X1345414Y324996D01*
G01X1320567Y326440D02*
Y317778D01*
G01X1336157D02*
X1335670D01*
Y318500D01*
X1336157Y317778D01*
G01Y275777D02*
X1335670D01*
Y276499D01*
X1336157Y275777D01*
G01D02*
X1335670D01*
Y276499D01*
X1336157Y275777D01*
G01X1328362Y317778D02*
X1327388Y318500D01*
X1326900Y319222D01*
X1326413Y320666D01*
Y323553D01*
X1326900Y324996D01*
X1327388Y325718D01*
X1328362Y326440D01*
X1329337Y325718D01*
X1329824Y324996D01*
X1330311Y323553D01*
Y320666D01*
X1329824Y319222D01*
X1329337Y318500D01*
X1328362Y317778D01*
G01X1343953Y275777D02*
X1342978Y276499D01*
X1342491Y277221D01*
X1342004Y278665D01*
Y281552D01*
X1342491Y282995D01*
X1342978Y283717D01*
X1343953Y284439D01*
X1344927Y283717D01*
X1345414Y282995D01*
X1345901Y281552D01*
Y278665D01*
X1345414Y277221D01*
X1344927Y276499D01*
X1343953Y275777D01*
G01D02*
X1342978Y276499D01*
X1342491Y277221D01*
X1342004Y278665D01*
Y281552D01*
X1342491Y282995D01*
X1342978Y283717D01*
X1343953Y284439D01*
X1344927Y283717D01*
X1345414Y282995D01*
X1345901Y281552D01*
Y278665D01*
X1345414Y277221D01*
X1344927Y276499D01*
X1343953Y275777D01*
G01X1328362D02*
X1327388Y276499D01*
X1326900Y277221D01*
X1326413Y278665D01*
Y281552D01*
X1326900Y282995D01*
X1327388Y283717D01*
X1328362Y284439D01*
X1329337Y283717D01*
X1329824Y282995D01*
X1330311Y281552D01*
Y278665D01*
X1329824Y277221D01*
X1329337Y276499D01*
X1328362Y275777D01*
G01D02*
X1327388Y276499D01*
X1326900Y277221D01*
X1326413Y278665D01*
Y281552D01*
X1326900Y282995D01*
X1327388Y283717D01*
X1328362Y284439D01*
X1329337Y283717D01*
X1329824Y282995D01*
X1330311Y281552D01*
Y278665D01*
X1329824Y277221D01*
X1329337Y276499D01*
X1328362Y275777D01*
G01X1342491Y485797D02*
X1343465Y486519D01*
X1344440D01*
X1345414Y485797D01*
X1345901Y485075D01*
Y484353D01*
X1345414Y483631D01*
X1344440Y482910D01*
X1345414Y482188D01*
G01X1328362Y486519D02*
Y477857D01*
G01X1322516Y486519D02*
X1319592D01*
X1319105Y482910D01*
X1320080Y483631D01*
X1321054D01*
X1322028Y482910D01*
X1322516Y482188D01*
X1323003Y480744D01*
X1322516Y479301D01*
X1322028Y478579D01*
X1321054Y477857D01*
X1320080D01*
X1319105Y478579D01*
X1318618Y479301D01*
G01X1343465Y482910D02*
X1344440D01*
G01X1345414Y482188D02*
X1346389Y480744D01*
Y480023D01*
X1345901Y479301D01*
X1345414Y478579D01*
X1344440Y477857D01*
X1343465D01*
X1342491Y478579D01*
X1342004Y479301D01*
G01X1336157Y477857D02*
X1335670D01*
Y478579D01*
X1336157Y477857D01*
G01X1318618Y546381D02*
X1319105Y547825D01*
X1320567Y548546D01*
X1322028Y547825D01*
X1322516Y546381D01*
X1322028Y544938D01*
X1321541Y544216D01*
X1320567Y543494D01*
X1319592Y544216D01*
X1319105Y544938D01*
X1318618Y546381D01*
Y549268D01*
X1319105Y550712D01*
X1319592Y551434D01*
X1320567Y552155D01*
X1321541Y551434D01*
X1322028Y550712D01*
G01X1336157Y543494D02*
X1335670D01*
Y544216D01*
X1336157Y543494D01*
G01X1329824Y547825D02*
X1330798Y546381D01*
Y545659D01*
X1330311Y544938D01*
X1329824Y544216D01*
X1328849Y543494D01*
X1327875D01*
G01X1326900Y544216D02*
X1325926Y545659D01*
Y546381D01*
X1326413Y547103D01*
X1326900Y547825D01*
X1327875Y548546D01*
X1328849D01*
X1329824Y547825D01*
G01X1343953Y543494D02*
X1342978Y544216D01*
X1342491Y544938D01*
X1342004Y546381D01*
Y549268D01*
X1342491Y550712D01*
X1342978Y551434D01*
X1343953Y552155D01*
X1344927Y551434D01*
X1345414Y550712D01*
X1345901Y549268D01*
Y546381D01*
X1345414Y544938D01*
X1344927Y544216D01*
X1343953Y543494D01*
G01X1327875Y548546D02*
X1326900Y549268D01*
X1326413Y549990D01*
Y550712D01*
X1326900Y551434D01*
X1327875Y552155D01*
X1328849D01*
X1329824Y551434D01*
X1330311Y550712D01*
Y549990D01*
X1329824Y549268D01*
X1328849Y548546D01*
G01X1327875Y543494D02*
X1326900Y544216D01*
G01X1345901Y1313966D02*
X1342978D01*
X1342491Y1310357D01*
X1343465Y1311079D01*
X1344440D01*
X1345414Y1310357D01*
X1345901Y1309636D01*
X1346389Y1308192D01*
X1345901Y1306749D01*
X1345414Y1306027D01*
X1344440Y1305305D01*
X1343465D01*
X1342491Y1306027D01*
X1342004Y1306749D01*
G01X1336157Y1305305D02*
X1335670D01*
Y1306027D01*
X1336157Y1305305D01*
G01X1312284Y1308914D02*
X1311310Y1307470D01*
X1310823Y1305305D01*
X1314720D01*
G01X1310823Y1312523D02*
X1311310Y1313245D01*
X1312284Y1313966D01*
X1313259D01*
X1314233Y1313245D01*
X1314720Y1312523D01*
Y1311079D01*
X1314233Y1310357D01*
X1312284Y1308914D01*
G01X1318618Y1308192D02*
X1319105Y1309636D01*
X1320567Y1310357D01*
X1322028Y1309636D01*
X1322516Y1308192D01*
X1322028Y1306749D01*
X1321541Y1306027D01*
X1320567Y1305305D01*
X1319592Y1306027D01*
X1319105Y1306749D01*
X1318618Y1308192D01*
Y1311079D01*
X1319105Y1312523D01*
X1319592Y1313245D01*
X1320567Y1313966D01*
X1321541Y1313245D01*
X1322028Y1312523D01*
G01X1328362Y1313966D02*
Y1305305D01*
G01X1336157Y2036289D02*
X1335670D01*
Y2037011D01*
X1336157Y2036289D01*
G01X1343953Y2044951D02*
Y2036289D01*
G01X1322028D02*
Y2044951D01*
X1318618Y2038455D01*
X1323003D01*
G01X1314233Y2036289D02*
Y2044951D01*
X1310823Y2038455D01*
X1315208D01*
G01X1328362Y2036289D02*
X1328849Y2039898D01*
X1329337Y2042063D01*
G01D02*
X1330311Y2044951D01*
X1326413D01*
G01X1336157Y2116171D02*
X1335670D01*
Y2116893D01*
X1336157Y2116171D01*
G01X1345414D02*
Y2124833D01*
X1342004Y2118336D01*
X1346389D01*
G01X1314233Y2116171D02*
Y2124833D01*
X1310823Y2118336D01*
X1315208D01*
G01X1328362Y2116171D02*
X1328849Y2119780D01*
X1329337Y2121946D01*
X1329824Y2123389D01*
X1330311Y2124833D01*
X1326413D01*
G01X1318618Y2119058D02*
X1319105Y2120502D01*
X1320567Y2121224D01*
X1322028Y2120502D01*
X1322516Y2119058D01*
X1322028Y2117615D01*
X1321541Y2116893D01*
X1320567Y2116171D01*
X1319592Y2116893D01*
X1319105Y2117615D01*
X1318618Y2119058D01*
Y2121946D01*
X1319105Y2123389D01*
X1319592Y2124111D01*
X1320567Y2124833D01*
X1321541Y2124111D01*
X1322028Y2123389D01*
G01X1330311Y2234951D02*
X1327388D01*
X1326900Y2231342D01*
X1327875Y2232063D01*
X1328849D01*
X1329824Y2231342D01*
X1330311Y2230620D01*
X1330798Y2229176D01*
X1330311Y2227733D01*
X1329824Y2227011D01*
X1328849Y2226289D01*
X1327875D01*
X1326900Y2227011D01*
X1326413Y2227733D01*
G01X1336157Y2226289D02*
X1335670D01*
Y2227011D01*
X1336157Y2226289D01*
G01Y2184832D02*
X1335670D01*
Y2185554D01*
X1336157Y2184832D01*
G01X1320080Y2189885D02*
X1319105Y2190607D01*
X1318618Y2191329D01*
Y2192050D01*
X1319105Y2192772D01*
X1320080Y2193494D01*
X1321054D01*
X1322028Y2192772D01*
X1322516Y2192050D01*
Y2191329D01*
X1322028Y2190607D01*
X1321054Y2189885D01*
G01X1320080Y2184832D02*
X1319105Y2185554D01*
G01X1322028Y2189163D02*
X1323003Y2187720D01*
Y2186998D01*
G01X1319105Y2185554D02*
X1318131Y2186998D01*
Y2187720D01*
G01X1345414Y2226289D02*
Y2234951D01*
X1342004Y2228455D01*
X1346389D01*
G01X1329824Y2184832D02*
Y2193494D01*
X1326413Y2186998D01*
X1330798D01*
G01X1314233Y2226289D02*
Y2234951D01*
X1310823Y2228455D01*
X1315208D01*
G01X1314233Y2184832D02*
Y2193494D01*
X1310823Y2186998D01*
X1315208D01*
G01X1345901Y2190607D02*
X1345414Y2189163D01*
X1343953Y2188442D01*
X1342491Y2189163D01*
X1342004Y2190607D01*
X1342491Y2192050D01*
X1342978Y2192772D01*
X1343953Y2193494D01*
X1344927Y2192772D01*
X1345414Y2192050D01*
X1345901Y2190607D01*
Y2187720D01*
X1345414Y2186276D01*
X1344927Y2185554D01*
X1343953Y2184832D01*
X1342978Y2185554D01*
X1342491Y2186276D01*
G01X1322516Y2232063D02*
X1322028Y2230620D01*
X1320567Y2229898D01*
X1319105Y2230620D01*
X1318618Y2232063D01*
X1319105Y2233507D01*
X1319592Y2234229D01*
X1320567Y2234951D01*
X1321541Y2234229D01*
X1322028Y2233507D01*
X1322516Y2232063D01*
Y2229176D01*
X1322028Y2227733D01*
X1321541Y2227011D01*
X1320567Y2226289D01*
X1319592Y2227011D01*
X1319105Y2227733D01*
G01X1323003Y2186998D02*
X1322028Y2185554D01*
X1321054Y2184832D01*
X1320080D01*
G01X1318131Y2187720D02*
X1319105Y2189163D01*
X1320080Y2189885D01*
X1321054D01*
X1322028Y2189163D01*
G01X1285692Y2245181D02*
X1285205D01*
Y2245903D01*
X1285692Y2245181D01*
G01X1293487Y2253843D02*
Y2245181D01*
G01X1275948Y2252399D02*
X1276435Y2253121D01*
X1277409Y2253843D01*
X1278384D01*
X1279358Y2253121D01*
X1279846Y2252399D01*
Y2250956D01*
X1279358Y2250234D01*
G01D02*
X1277409Y2248790D01*
X1276435Y2247347D01*
X1275948Y2245181D01*
X1279846D01*
G01X1314720Y2276565D02*
X1311797D01*
X1311310Y2272956D01*
X1312284Y2273678D01*
X1313259D01*
X1314233Y2272956D01*
X1314720Y2272234D01*
X1315208Y2270791D01*
X1314720Y2269347D01*
X1314233Y2268625D01*
X1313259Y2267903D01*
X1312284D01*
X1311310Y2268625D01*
X1310823Y2269347D01*
G01X1336157Y2267903D02*
X1335670D01*
Y2268625D01*
X1336157Y2267903D01*
G01X1314720Y2267392D02*
X1311797D01*
X1311310Y2263783D01*
X1312284Y2264505D01*
X1313259D01*
X1314233Y2263783D01*
X1314720Y2263061D01*
X1315208Y2261617D01*
X1314720Y2260174D01*
X1314233Y2259452D01*
X1313259Y2258730D01*
X1312284D01*
X1311310Y2259452D01*
X1310823Y2260174D01*
G01X1327875Y2263783D02*
X1328849D01*
G01X1336157Y2258730D02*
X1335670D01*
Y2259452D01*
X1336157Y2258730D01*
G01X1330028Y2253843D02*
X1334900D01*
G01X1338310Y2249512D02*
X1342208D01*
G01X1320567Y2258730D02*
X1319592Y2259452D01*
X1319105Y2260174D01*
X1318618Y2261617D01*
Y2264505D01*
X1319105Y2265948D01*
X1319592Y2266670D01*
X1320567Y2267392D01*
X1321541Y2266670D01*
X1322028Y2265948D01*
X1322516Y2264505D01*
Y2261617D01*
X1322028Y2260174D01*
X1321541Y2259452D01*
X1320567Y2258730D01*
G01X1300795Y2250234D02*
X1299821Y2250956D01*
X1299334Y2251677D01*
Y2252399D01*
X1299821Y2253121D01*
X1300795Y2253843D01*
X1301770D01*
X1302744Y2253121D01*
X1303231Y2252399D01*
Y2251677D01*
X1302744Y2250956D01*
X1301770Y2250234D01*
G01X1343953Y2267903D02*
X1342978Y2268625D01*
X1342491Y2269347D01*
X1342004Y2270791D01*
Y2273678D01*
X1342491Y2275121D01*
X1342978Y2275843D01*
X1343953Y2276565D01*
X1344927Y2275843D01*
X1345414Y2275121D01*
X1345901Y2273678D01*
Y2270791D01*
X1345414Y2269347D01*
X1344927Y2268625D01*
X1343953Y2267903D01*
G01X1320567D02*
X1319592Y2268625D01*
X1319105Y2269347D01*
X1318618Y2270791D01*
Y2273678D01*
X1319105Y2275121D01*
X1319592Y2275843D01*
X1320567Y2276565D01*
X1321541Y2275843D01*
X1322028Y2275121D01*
X1322516Y2273678D01*
Y2270791D01*
X1322028Y2269347D01*
X1321541Y2268625D01*
X1320567Y2267903D01*
G01X1300795Y2245181D02*
X1299821Y2245903D01*
G01X1347567Y2253843D02*
X1348541Y2252399D01*
X1349029Y2250234D01*
Y2248790D01*
X1348541Y2246625D01*
X1347567Y2245181D01*
G01X1329824Y2263061D02*
X1330798Y2261617D01*
Y2260896D01*
G01X1299821Y2245903D02*
X1298846Y2247347D01*
Y2248068D01*
G01X1342208Y2253843D02*
Y2245181D01*
G01X1338310Y2253843D02*
Y2245181D01*
G01X1332464Y2253843D02*
Y2245181D01*
G01X1322719D02*
Y2253843D01*
X1325156D01*
X1326130Y2253121D01*
X1326617Y2252399D01*
Y2250956D01*
X1326130Y2250234D01*
X1325156Y2249512D01*
X1322719D01*
G01X1314924Y2245181D02*
Y2253843D01*
X1318822Y2245181D01*
Y2253843D01*
G01X1342004Y2261617D02*
X1342491Y2263061D01*
X1343953Y2263783D01*
X1345414Y2263061D01*
X1345901Y2261617D01*
X1345414Y2260174D01*
X1344927Y2259452D01*
X1343953Y2258730D01*
X1342978Y2259452D01*
X1342491Y2260174D01*
X1342004Y2261617D01*
Y2264505D01*
X1342491Y2265948D01*
X1342978Y2266670D01*
X1343953Y2267392D01*
X1344927Y2266670D01*
X1345414Y2265948D01*
G01X1326413Y2270791D02*
X1326900Y2272234D01*
X1328362Y2272956D01*
X1329824Y2272234D01*
X1330311Y2270791D01*
X1329824Y2269347D01*
X1329337Y2268625D01*
X1328362Y2267903D01*
X1327388Y2268625D01*
X1326900Y2269347D01*
X1326413Y2270791D01*
Y2273678D01*
X1326900Y2275121D01*
X1327388Y2275843D01*
X1328362Y2276565D01*
X1329337Y2275843D01*
X1329824Y2275121D01*
G01X1330798Y2260896D02*
X1329824Y2259452D01*
X1328849Y2258730D01*
X1327875D01*
X1326900Y2259452D01*
X1326413Y2260174D01*
G01X1309565Y2253843D02*
X1308591Y2252399D01*
X1308103Y2250234D01*
Y2248790D01*
X1308591Y2246625D01*
X1309565Y2245181D01*
G01X1298846Y2248068D02*
X1299821Y2249512D01*
X1300795Y2250234D01*
X1301770D01*
X1302744Y2249512D01*
X1303231Y2248790D01*
X1303719Y2248068D01*
Y2247347D01*
X1303231Y2246625D01*
X1302744Y2245903D01*
X1301770Y2245181D01*
X1300795D01*
G01X1326900Y2266670D02*
X1327875Y2267392D01*
X1328849D01*
X1329824Y2266670D01*
X1330311Y2265948D01*
Y2265226D01*
X1329824Y2264505D01*
X1328849Y2263783D01*
X1329824Y2263061D01*
G01X1352722Y323553D02*
X1353697Y326440D01*
X1349799D01*
G01X1351748Y317778D02*
X1352235Y321387D01*
X1352722Y323553D01*
G01X1351748Y275777D02*
X1350774Y276499D01*
X1350286Y277221D01*
X1349799Y278665D01*
Y281552D01*
X1350286Y282995D01*
X1350774Y283717D01*
X1351748Y284439D01*
X1352722Y283717D01*
X1353210Y282995D01*
X1353697Y281552D01*
Y278665D01*
X1353210Y277221D01*
X1352722Y276499D01*
X1351748Y275777D01*
G01D02*
X1350774Y276499D01*
X1350286Y277221D01*
X1349799Y278665D01*
Y281552D01*
X1350286Y282995D01*
X1350774Y283717D01*
X1351748Y284439D01*
X1352722Y283717D01*
X1353210Y282995D01*
X1353697Y281552D01*
Y278665D01*
X1353210Y277221D01*
X1352722Y276499D01*
X1351748Y275777D01*
G01X1453283Y273612D02*
X1359976D01*
G01X1555646Y315613D02*
X1359976D01*
G01X1453283Y273612D02*
X1359976D01*
G01X1350286Y485797D02*
X1351261Y486519D01*
X1352235D01*
X1353210Y485797D01*
X1353697Y485075D01*
Y484353D01*
X1353210Y483631D01*
X1352235Y482910D01*
X1353210Y482188D01*
G01X1351261Y482910D02*
X1352235D01*
G01X1353210Y482188D02*
X1354184Y480744D01*
Y480023D01*
G01D02*
X1353210Y478579D01*
X1352235Y477857D01*
X1351261D01*
X1350286Y478579D01*
X1349799Y479301D01*
G01X1520212Y475692D02*
X1359976D01*
G01X1351748Y543494D02*
X1350774Y544216D01*
X1350286Y544938D01*
X1349799Y546381D01*
Y549268D01*
X1350286Y550712D01*
X1350774Y551434D01*
X1351748Y552155D01*
X1352722Y551434D01*
X1353210Y550712D01*
X1353697Y549268D01*
Y546381D01*
X1353210Y544938D01*
X1352722Y544216D01*
X1351748Y543494D01*
G01X1486748Y541329D02*
X1359976D01*
G01X1457220Y869840D02*
X1395016D01*
G01X1426512Y860785D02*
X1400921D01*
G01X1448165Y854880D02*
X1395016D01*
G01X1448165Y852124D02*
X1396984D01*
G01X1448165Y850155D02*
X1395016D01*
G01X1400921Y860785D02*
X1395016Y857376D01*
G01X1400921Y869840D02*
Y860785D01*
G01X1396984Y852124D02*
Y850155D01*
G01X1395016Y869840D02*
Y850155D01*
G01Y854092D02*
X1396984Y852124D01*
G01X1426512Y1207242D02*
X1400921D01*
G01X1457220Y1198187D02*
X1395016D01*
G01Y1210652D02*
X1400921Y1207242D01*
G01D02*
Y1198187D01*
G01X1395016Y1217872D02*
Y1198187D01*
G01X1396984Y1215903D02*
X1395016Y1213935D01*
G01X1448165Y1217872D02*
X1395016D01*
G01X1448165Y1215903D02*
X1396984D01*
G01Y1217872D02*
Y1215903D01*
G01X1351748Y1305305D02*
X1350774Y1306027D01*
X1350286Y1306749D01*
X1349799Y1308192D01*
Y1311079D01*
X1350286Y1312523D01*
X1350774Y1313245D01*
X1351748Y1313966D01*
X1352722Y1313245D01*
X1353210Y1312523D01*
X1353697Y1311079D01*
Y1308192D01*
X1353210Y1306749D01*
X1352722Y1306027D01*
X1351748Y1305305D01*
G01X1486748Y1303140D02*
X1359976D01*
G01X1426512Y1356848D02*
X1400921D01*
G01X1448165Y1350943D02*
X1395016D01*
G01X1448165Y1348187D02*
X1396984D01*
G01X1448165Y1346218D02*
X1395016D01*
G01Y1350155D02*
X1396984Y1348187D01*
G01X1400921Y1356848D02*
X1395016Y1353439D01*
G01X1400921Y1365903D02*
Y1356848D01*
G01X1396984Y1348187D02*
Y1346218D01*
G01X1395016Y1365903D02*
Y1346218D01*
G01X1457220Y1365903D02*
X1395016D01*
G01X1448165Y1713935D02*
X1395016D01*
G01X1448165Y1711966D02*
X1396984D01*
G01X1426512Y1703305D02*
X1400921D01*
G01X1457220Y1694250D02*
X1395016D01*
G01Y1706715D02*
X1400921Y1703305D01*
G01D02*
Y1694250D01*
G01X1396984Y1713935D02*
Y1711966D01*
G01X1395016Y1713935D02*
Y1694250D01*
G01X1396984Y1711966D02*
X1395016Y1709998D01*
G01X1457220Y1783226D02*
X1395016D01*
G01X1426512Y1774171D02*
X1400921D01*
G01X1448165Y1768266D02*
X1395016D01*
G01X1448165Y1765510D02*
X1396984D01*
G01X1448165Y1763541D02*
X1395016D01*
G01Y1767478D02*
X1396984Y1765510D01*
G01X1400921Y1783226D02*
Y1774171D01*
G01X1396984Y1765510D02*
Y1763541D01*
G01X1395016Y1783226D02*
Y1763541D01*
G01X1400921Y1774171D02*
X1395016Y1770762D01*
G01X1351748Y2036289D02*
X1352235Y2039898D01*
X1352722Y2042063D01*
G01D02*
X1353697Y2044951D01*
X1349799D01*
G01X1557614Y2034124D02*
X1359976D01*
G01X1349799Y2119058D02*
X1350286Y2120502D01*
X1351748Y2121224D01*
X1353210Y2120502D01*
X1353697Y2119058D01*
X1353210Y2117615D01*
X1352722Y2116893D01*
X1351748Y2116171D01*
X1350774Y2116893D01*
X1350286Y2117615D01*
X1349799Y2119058D01*
Y2121946D01*
X1350286Y2123389D01*
X1350774Y2124111D01*
X1351748Y2124833D01*
X1352722Y2124111D01*
X1353210Y2123389D01*
G01X1520212Y2114006D02*
X1359976D01*
G01X1448165Y2131258D02*
X1395016D01*
G01X1448165Y2129289D02*
X1396984D01*
G01X1426512Y2120628D02*
X1400921D01*
G01X1457220Y2111573D02*
X1395016D01*
G01Y2124037D02*
X1400921Y2120628D01*
G01D02*
Y2111573D01*
G01X1396984Y2131258D02*
Y2129289D01*
G01X1395016Y2131258D02*
Y2111573D01*
G01X1396984Y2129289D02*
X1395016Y2127321D01*
G01X1351748Y2184832D02*
X1350774Y2185554D01*
X1350286Y2186276D01*
X1349799Y2187720D01*
Y2190607D01*
X1350286Y2192050D01*
X1350774Y2192772D01*
X1351748Y2193494D01*
X1352722Y2192772D01*
X1353210Y2192050D01*
X1353697Y2190607D01*
Y2187720D01*
X1353210Y2186276D01*
X1352722Y2185554D01*
X1351748Y2184832D01*
G01X1354184Y2229176D02*
Y2228455D01*
X1353210Y2227011D01*
G01D02*
X1352235Y2226289D01*
X1351261D01*
X1350286Y2227011D01*
X1349799Y2227733D01*
G01X1350286Y2234229D02*
X1351261Y2234951D01*
X1352235D01*
X1353210Y2234229D01*
X1353697Y2233507D01*
Y2232785D01*
X1353210Y2232063D01*
X1352235Y2231342D01*
X1353210Y2230620D01*
X1354184Y2229176D01*
G01X1478795Y2224124D02*
X1359976D01*
G01X1474937Y2182667D02*
X1359976D01*
G01X1351261Y2231342D02*
X1352235D01*
G01X1351748Y2267903D02*
X1350774Y2268625D01*
X1350286Y2269347D01*
X1349799Y2270791D01*
Y2273678D01*
X1350286Y2275121D01*
X1350774Y2275843D01*
X1351748Y2276565D01*
X1352722Y2275843D01*
X1353210Y2275121D01*
X1353697Y2273678D01*
Y2270791D01*
X1353210Y2269347D01*
X1352722Y2268625D01*
X1351748Y2267903D01*
G01Y2258730D02*
X1352235Y2262339D01*
X1352722Y2264505D01*
X1353210Y2265948D01*
X1353697Y2267392D01*
X1349799D01*
G01X1520212Y2256565D02*
X1359976D01*
G01X1363763Y2243016D02*
X1360613D01*
G01X1478494Y2224797D02*
X1363763Y2243016D01*
G01X1457220Y2265738D02*
X1359976D01*
G01X1487798Y193686D02*
X1486354Y192711D01*
X1485632D01*
G01X1483467Y194660D02*
X1482745Y193686D01*
X1482024Y193199D01*
X1481302D01*
X1480580Y193686D01*
X1479858Y194660D01*
Y195635D01*
X1480580Y196609D01*
X1481302Y197096D01*
X1482024D01*
X1482745Y196609D01*
X1483467Y195635D01*
G01X1485632Y192711D02*
X1484189Y193686D01*
X1483467Y194660D01*
Y195635D01*
X1484189Y196609D01*
G01X1490685Y541090D02*
Y226762D01*
G01X1488520Y194660D02*
X1487798Y193686D01*
G01X1455055Y195148D02*
X1454333Y194173D01*
X1453611Y193686D01*
X1452168Y193199D01*
X1449281D01*
X1447837Y193686D01*
X1447115Y194173D01*
X1446394Y195148D01*
X1447115Y196122D01*
X1447837Y196609D01*
X1449281Y197096D01*
X1452168D01*
X1453611Y196609D01*
X1454333Y196122D01*
X1455055Y195148D01*
G01D02*
X1454333Y194173D01*
X1453611Y193686D01*
X1452168Y193199D01*
X1449281D01*
X1447837Y193686D01*
X1447115Y194173D01*
X1446394Y195148D01*
X1447115Y196122D01*
X1447837Y196609D01*
X1449281Y197096D01*
X1452168D01*
X1453611Y196609D01*
X1454333Y196122D01*
X1455055Y195148D01*
G01X1484189Y196609D02*
X1485632Y197584D01*
X1486354D01*
G01X1488520Y218533D02*
X1487798Y217559D01*
X1487076Y217072D01*
X1485632Y216585D01*
X1482745D01*
X1481302Y217072D01*
X1480580Y217559D01*
X1479858Y218533D01*
X1480580Y219508D01*
X1481302Y219995D01*
X1482745Y220482D01*
X1485632D01*
X1487076Y219995D01*
X1487798Y219508D01*
X1488520Y218533D01*
G01X1455055Y210738D02*
X1454333Y209764D01*
X1453611Y209276D01*
X1452168Y208789D01*
X1449281D01*
X1447837Y209276D01*
X1447115Y209764D01*
X1446394Y210738D01*
X1447115Y211713D01*
X1447837Y212200D01*
X1449281Y212687D01*
X1452168D01*
X1453611Y212200D01*
X1454333Y211713D01*
X1455055Y210738D01*
G01D02*
X1454333Y209764D01*
X1453611Y209276D01*
X1452168Y208789D01*
X1449281D01*
X1447837Y209276D01*
X1447115Y209764D01*
X1446394Y210738D01*
X1447115Y211713D01*
X1447837Y212200D01*
X1449281Y212687D01*
X1452168D01*
X1453611Y212200D01*
X1454333Y211713D01*
X1455055Y210738D01*
G01Y218533D02*
X1454333Y217559D01*
X1453611Y217072D01*
X1452168Y216585D01*
X1449281D01*
X1447837Y217072D01*
X1447115Y217559D01*
X1446394Y218533D01*
X1447115Y219508D01*
X1447837Y219995D01*
X1449281Y220482D01*
X1452168D01*
X1453611Y219995D01*
X1454333Y219508D01*
X1455055Y218533D01*
G01D02*
X1454333Y217559D01*
X1453611Y217072D01*
X1452168Y216585D01*
X1449281D01*
X1447837Y217072D01*
X1447115Y217559D01*
X1446394Y218533D01*
X1447115Y219508D01*
X1447837Y219995D01*
X1449281Y220482D01*
X1452168D01*
X1453611Y219995D01*
X1454333Y219508D01*
X1455055Y218533D01*
G01X1488520Y202943D02*
Y202456D01*
X1487798D01*
X1488520Y202943D01*
G01X1479858Y212687D02*
Y209764D01*
X1483467Y209276D01*
X1482745Y210251D01*
Y211225D01*
X1483467Y212200D01*
X1484189Y212687D01*
X1485632Y213174D01*
X1487076Y212687D01*
X1487798Y212200D01*
X1488520Y211225D01*
Y210251D01*
X1487798Y209276D01*
X1487076Y208789D01*
G01X1455055Y202943D02*
Y202456D01*
X1454333D01*
X1455055Y202943D01*
G01D02*
Y202456D01*
X1454333D01*
X1455055Y202943D01*
G01X1486354Y197584D02*
X1487798Y196609D01*
X1488520Y195635D01*
Y194660D01*
G01X1457220Y269675D02*
Y226762D01*
G01Y269675D02*
Y226762D01*
G01Y1008817D02*
Y277549D01*
G01D02*
G03X1461157Y273612I3937J0D01*
G01X1496457Y306033D02*
X1493047Y304065D01*
G01Y302333D02*
Y304065D01*
G01X1457220Y273612D02*
Y274747D01*
G01X1493047Y303436D02*
X1497767Y298794D01*
G01X1493047Y302333D02*
X1497772Y297687D01*
G01X1457220Y273612D02*
X1458355D01*
G01X1578480D02*
X1461157D01*
G01X1497767Y455753D02*
X1493047Y451111D01*
G01Y452214D02*
X1497772Y456860D01*
G01X1493047Y450482D02*
Y452214D01*
G01X1496457Y448514D02*
X1493047Y450482D01*
G01X1496588Y555108D02*
G03X1484782I-5903J0D01*
G01X1496590D02*
G03X1484779I-5906J0D01*
G01X1498559D02*
G03X1482811I-7874J0D01*
G01X1504464D02*
G03X1476905I-13780J0D01*
G01X1506433D02*
G03X1474937I-15748J0D01*
G01X1506433D02*
G03X1474937I-15748J0D01*
G01X1506433D02*
G03X1474937I-15748J0D01*
G01X1483656Y548219D02*
G03X1497714I7029J-6890D01*
G01X1474937Y541329D02*
G03X1506433I15748J0D01*
G01X1474937D02*
G03X1506433I15748J0D01*
G01X1474937D02*
G03X1506433I15748J0D01*
G01X1481630Y555108D02*
G03I-984J0D01*
G01X1483656Y548219D02*
G03X1484782Y550975I-2811J2756D01*
G01Y555108D02*
Y550975D01*
G01X1484779Y552746D02*
Y555108D01*
G01X1482811D02*
Y552746D01*
G01X1476905Y555108D02*
Y552746D01*
G01X1474937Y541329D02*
Y555108D01*
G01Y541329D02*
Y555108D01*
G01Y541329D02*
Y555108D01*
G01X1476905Y552746D02*
X1484779D01*
G01X1486649Y563803D02*
G03I-984J0D01*
G01X1482975Y560128D02*
G03I-984J0D01*
G01X1493047Y707844D02*
X1497772Y703199D01*
G01X1496457Y711545D02*
X1493047Y709577D01*
G01Y707844D02*
Y709577D01*
G01Y708948D02*
X1497767Y704306D01*
G01X1457220Y1236770D02*
Y831258D01*
G01X1469048Y849368D02*
G03Y840707I-17J-4331D01*
G01X1469081D02*
G03Y849368I-50J4331D01*
G01X1473362Y845037D02*
G03I-4331J0D01*
G01X1479661Y840707D02*
X1469031D01*
G01X1479661Y831258D02*
X1448165D01*
G01Y840313D02*
X1469034Y840706D01*
G01X1469113Y840707D02*
X1448165Y840313D01*
G01X1479661Y860785D02*
Y831258D01*
G01X1448165Y854880D02*
Y831258D01*
G01X1426512Y1198187D02*
Y869840D01*
G01X1430449Y867872D02*
X1426512Y865903D01*
G01X1429239Y871809D02*
X1426512Y870234D01*
G01X1439047Y918599D02*
X1442543Y918561D01*
G01X1437751Y918613D02*
X1441007Y918577D01*
G01X1439047Y915449D02*
X1442543Y915411D01*
G01X1437751Y915464D02*
X1441007Y915428D01*
G01X1439047Y912300D02*
X1442543Y912262D01*
G01X1437751Y912314D02*
X1441007Y912278D01*
G01X1439047Y909150D02*
X1442543Y909112D01*
G01X1437751Y909164D02*
X1441007Y909129D01*
G01X1439047Y906000D02*
X1442543Y905963D01*
G01X1437751Y906015D02*
X1441007Y905979D01*
G01X1439047Y902851D02*
X1442543Y902813D01*
G01X1437751Y902865D02*
X1441007Y902829D01*
G01X1439047Y899701D02*
X1442543Y899663D01*
G01X1437751Y899716D02*
X1441007Y899680D01*
G01X1439047Y896552D02*
X1442543Y896514D01*
G01X1437751Y896566D02*
X1441007Y896530D01*
G01X1438785Y918599D02*
X1436420Y918625D01*
G01X1438785Y915449D02*
X1436420Y915475D01*
G01X1438785Y912300D02*
X1436420Y912326D01*
G01X1438785Y909150D02*
X1436420Y909176D01*
G01X1438785Y906001D02*
X1436420Y906027D01*
G01X1438785Y902851D02*
X1436420Y902877D01*
G01X1438785Y899701D02*
X1436420Y899727D01*
G01X1438785Y896552D02*
X1436420Y896578D01*
G01X1441235Y918577D02*
X1442772Y918561D01*
G01X1441235Y915428D02*
X1442772Y915411D01*
G01X1441235Y912278D02*
X1442772Y912262D01*
G01X1441235Y909129D02*
X1442772Y909112D01*
G01X1441235Y905979D02*
X1442772Y905963D01*
G01X1441235Y902829D02*
X1442772Y902813D01*
G01X1441235Y899680D02*
X1442772Y899663D01*
G01X1441235Y896530D02*
X1442772Y896514D01*
G01X1441235Y918577D02*
X1438785Y918599D01*
G01X1437751Y918613D02*
X1436420Y918625D01*
G01X1441235Y915428D02*
X1438785Y915449D01*
G01X1437751Y915464D02*
X1436420Y915475D01*
G01X1441235Y912278D02*
X1438785Y912300D01*
G01X1437751Y912314D02*
X1436420Y912326D01*
G01X1441235Y909129D02*
X1438785Y909150D01*
G01X1437751Y909164D02*
X1436420Y909176D01*
G01X1441235Y905979D02*
X1438785Y906001D01*
G01X1437751Y906015D02*
X1436420Y906027D01*
G01X1441235Y902829D02*
X1438785Y902851D01*
G01X1437751Y902865D02*
X1436420Y902877D01*
G01X1441235Y899680D02*
X1438785Y899701D01*
G01X1437751Y899716D02*
X1436420Y899727D01*
G01X1441235Y896530D02*
X1438785Y896552D01*
G01X1437751Y896566D02*
X1436420Y896578D01*
G01X1441235Y919529D02*
X1441007D01*
G01X1439047Y919507D02*
X1438785D01*
G01X1439047Y918599D02*
X1438785D01*
G01X1441235Y918577D02*
X1441007D01*
G01X1441235Y916379D02*
X1441007D01*
G01X1439047Y916358D02*
X1438785D01*
G01X1439047Y915449D02*
X1438785D01*
G01X1441235Y915428D02*
X1441007D01*
G01X1441235Y913230D02*
X1441007D01*
G01X1439047Y913208D02*
X1438785D01*
G01X1439047Y912300D02*
X1438785D01*
G01X1441235Y912278D02*
X1441007D01*
G01X1441235Y910080D02*
X1441007D01*
G01X1439047Y910058D02*
X1438785D01*
G01X1439047Y909150D02*
X1438785D01*
G01X1441235Y909129D02*
X1441007D01*
G01X1441235Y906930D02*
X1441007D01*
G01X1439047Y906909D02*
X1438785D01*
G01X1439047Y906001D02*
X1438785D01*
G01X1441235Y905979D02*
X1441007D01*
G01X1441235Y903781D02*
X1441007D01*
G01X1439047Y903759D02*
X1438785D01*
G01X1439047Y902851D02*
X1438785D01*
G01X1441235Y902829D02*
X1441007D01*
G01X1441235Y900631D02*
X1441007D01*
G01X1439047Y900610D02*
X1438785D01*
G01X1439047Y899701D02*
X1438785D01*
G01X1441235Y899680D02*
X1441007D01*
G01X1441235Y897481D02*
X1441007D01*
G01X1439047Y897460D02*
X1438785D01*
G01X1439047Y896552D02*
X1438785D01*
G01X1441235Y896530D02*
X1441007D01*
G01X1441235Y894332D02*
X1441007D01*
G01X1439047Y894310D02*
X1438785D01*
G01X1439047Y893402D02*
X1438785D01*
G01X1441235Y893381D02*
X1441007D01*
G01X1441235Y891182D02*
X1441007D01*
G01X1439047Y891161D02*
X1438785D01*
G01X1439047Y890253D02*
X1438785D01*
G01X1441235Y890231D02*
X1441007D01*
G01X1440094Y919519D02*
X1438785Y919507D01*
G01X1441235Y919529D02*
X1440094Y919519D01*
G01Y916369D02*
X1438785Y916358D01*
G01X1441235Y916379D02*
X1440094Y916369D01*
G01Y913220D02*
X1438785Y913208D01*
G01X1441235Y913230D02*
X1440094Y913220D01*
G01Y910070D02*
X1438785Y910058D01*
G01X1441235Y910080D02*
X1440094Y910070D01*
G01Y906920D02*
X1438785Y906909D01*
G01X1441235Y906930D02*
X1440094Y906920D01*
G01Y903771D02*
X1438785Y903759D01*
G01X1441235Y903781D02*
X1440094Y903771D01*
G01Y900621D02*
X1438785Y900610D01*
G01X1441235Y900631D02*
X1440094Y900621D01*
G01Y897471D02*
X1438785Y897460D01*
G01X1441235Y897481D02*
X1440094Y897471D01*
G01Y894322D02*
X1438785Y894310D01*
G01X1441235Y894332D02*
X1440094Y894322D01*
G01Y891172D02*
X1438785Y891161D01*
G01X1441235Y891182D02*
X1440094Y891172D01*
G01Y888023D02*
X1438785Y888011D01*
G01X1441235Y888033D02*
X1440094Y888023D01*
G01Y884873D02*
X1438785Y884861D01*
G01X1441235Y884883D02*
X1440094Y884873D01*
G01X1437751Y919493D02*
X1436420Y919481D01*
G01X1437751Y916343D02*
X1436420Y916331D01*
G01X1437751Y913194D02*
X1436420Y913182D01*
G01X1437751Y910044D02*
X1436420Y910032D01*
G01X1437751Y906894D02*
X1436420Y906883D01*
G01X1437751Y903745D02*
X1436420Y903733D01*
G01X1437751Y900595D02*
X1436420Y900583D01*
G01X1437751Y897446D02*
X1436420Y897434D01*
G01X1437751Y894296D02*
X1436420Y894284D01*
G01X1437751Y891146D02*
X1436420Y891135D01*
G01X1437751Y887997D02*
X1436420Y887985D01*
G01X1437751Y884847D02*
X1436420Y884835D01*
G01X1442543Y919545D02*
X1441007Y919529D01*
G01X1442543Y919545D02*
X1439047Y919507D01*
G01X1441235Y919529D02*
X1442772Y919545D01*
G01X1442543Y916396D02*
X1441007Y916379D01*
G01X1442543Y916396D02*
X1439047Y916358D01*
G01X1441235Y916379D02*
X1442772Y916396D01*
G01X1442543Y913246D02*
X1441007Y913230D01*
G01X1442543Y913246D02*
X1439047Y913208D01*
G01X1441235Y913230D02*
X1442772Y913246D01*
G01X1442543Y910096D02*
X1441007Y910080D01*
G01X1442543Y910096D02*
X1439047Y910058D01*
G01X1441235Y910080D02*
X1442772Y910096D01*
G01X1442543Y906947D02*
X1441007Y906930D01*
G01X1442543Y906947D02*
X1439047Y906909D01*
G01X1441235Y906930D02*
X1442772Y906947D01*
G01X1442543Y903797D02*
X1441007Y903781D01*
G01X1442543Y903797D02*
X1439047Y903759D01*
G01X1441235Y903781D02*
X1442772Y903797D01*
G01X1442543Y900648D02*
X1441007Y900631D01*
G01X1442543Y900648D02*
X1439047Y900610D01*
G01X1441235Y900631D02*
X1442772Y900648D01*
G01X1442543Y897498D02*
X1441007Y897481D01*
G01X1442543Y897498D02*
X1439047Y897460D01*
G01X1441235Y897481D02*
X1442772Y897498D01*
G01X1442543Y894348D02*
X1441007Y894332D01*
G01X1442543Y894348D02*
X1439047Y894310D01*
G01X1441235Y894332D02*
X1442772Y894348D01*
G01X1442543Y891199D02*
X1441007Y891182D01*
G01X1442543Y891199D02*
X1439047Y891161D01*
G01X1441235Y891182D02*
X1442772Y891199D01*
G01X1442543Y888049D02*
X1441007Y888033D01*
G01X1442543Y888049D02*
X1439047Y888011D01*
G01X1441235Y888033D02*
X1442772Y888049D01*
G01X1442543Y884900D02*
X1441007Y884883D01*
G01X1442543Y884900D02*
X1439047Y884862D01*
G01X1441235Y884883D02*
X1442772Y884900D01*
G01X1439047Y919507D02*
X1440094Y919519D01*
G01X1438785Y919507D02*
X1436420Y919481D01*
G01X1437751Y919493D02*
X1439047Y919507D01*
G01Y916358D02*
X1440094Y916369D01*
G01X1438785Y916358D02*
X1436420Y916331D01*
G01X1437751Y916343D02*
X1439047Y916358D01*
G01Y913208D02*
X1440094Y913220D01*
G01X1438785Y913208D02*
X1436420Y913182D01*
G01X1437751Y913194D02*
X1439047Y913208D01*
G01Y910058D02*
X1440094Y910070D01*
G01X1438785Y910058D02*
X1436420Y910032D01*
G01X1437751Y910044D02*
X1439047Y910058D01*
G01Y906909D02*
X1440094Y906920D01*
G01X1438785Y906909D02*
X1436420Y906883D01*
G01X1437751Y906894D02*
X1439047Y906909D01*
G01Y903759D02*
X1440094Y903771D01*
G01X1438785Y903759D02*
X1436420Y903733D01*
G01X1437751Y903745D02*
X1439047Y903759D01*
G01Y900610D02*
X1440094Y900621D01*
G01X1438785Y900610D02*
X1436420Y900583D01*
G01X1437751Y900595D02*
X1439047Y900610D01*
G01Y897460D02*
X1440094Y897471D01*
G01X1438785Y897460D02*
X1436420Y897434D01*
G01X1437751Y897446D02*
X1439047Y897460D01*
G01Y894310D02*
X1440094Y894322D01*
G01X1438785Y894310D02*
X1436420Y894284D01*
G01X1437751Y894296D02*
X1439047Y894310D01*
G01Y891161D02*
X1440094Y891172D01*
G01X1438785Y891161D02*
X1436420Y891135D01*
G01X1437751Y891146D02*
X1439047Y891161D01*
G01Y888011D02*
X1440094Y888023D01*
G01X1438785Y888011D02*
X1436420Y887985D01*
G01X1437751Y887997D02*
X1439047Y888011D01*
G01Y884861D02*
X1440094Y884873D01*
G01X1438785Y884861D02*
X1436420Y884835D01*
G01X1437751Y884847D02*
X1439047Y884861D01*
G01Y893402D02*
X1442543Y893364D01*
G01X1437751Y893416D02*
X1441007Y893381D01*
G01X1439047Y890252D02*
X1442543Y890214D01*
G01X1437751Y890267D02*
X1441007Y890231D01*
G01X1439047Y887103D02*
X1442543Y887065D01*
G01X1437751Y887117D02*
X1441007Y887081D01*
G01X1439047Y883953D02*
X1442543Y883915D01*
G01X1437751Y883968D02*
X1441007Y883932D01*
G01X1439047Y880804D02*
X1442543Y880766D01*
G01X1437751Y880818D02*
X1441007Y880782D01*
G01X1439047Y877654D02*
X1442543Y877616D01*
G01X1437751Y877668D02*
X1441007Y877633D01*
G01X1439047Y874504D02*
X1442543Y874466D01*
G01X1437751Y874519D02*
X1441007Y874483D01*
G01X1439047Y871355D02*
X1442543Y871317D01*
G01X1437751Y871369D02*
X1441007Y871333D01*
G01X1438785Y893402D02*
X1436420Y893428D01*
G01X1438785Y890253D02*
X1436420Y890279D01*
G01X1438785Y887103D02*
X1436420Y887129D01*
G01X1438785Y883953D02*
X1436420Y883979D01*
G01X1438785Y880804D02*
X1436420Y880830D01*
G01X1438785Y877654D02*
X1436420Y877680D01*
G01X1438785Y874504D02*
X1436420Y874531D01*
G01X1438785Y871355D02*
X1436420Y871381D01*
G01X1441235Y893381D02*
X1442772Y893364D01*
G01X1441235Y890231D02*
X1442772Y890214D01*
G01X1441235Y887081D02*
X1442772Y887065D01*
G01X1441235Y883932D02*
X1442772Y883915D01*
G01X1441235Y880782D02*
X1442772Y880766D01*
G01X1441235Y877633D02*
X1442772Y877616D01*
G01X1441235Y874483D02*
X1442772Y874466D01*
G01X1441235Y871333D02*
X1442772Y871317D01*
G01X1441235Y893381D02*
X1438785Y893402D01*
G01X1437751Y893416D02*
X1436420Y893428D01*
G01X1441235Y890231D02*
X1438785Y890253D01*
G01X1437751Y890267D02*
X1436420Y890279D01*
G01X1441235Y887081D02*
X1438785Y887103D01*
G01X1437751Y887117D02*
X1436420Y887129D01*
G01X1441235Y883932D02*
X1438785Y883953D01*
G01X1437751Y883968D02*
X1436420Y883979D01*
G01X1441235Y880782D02*
X1438785Y880804D01*
G01X1437751Y880818D02*
X1436420Y880830D01*
G01X1441235Y877633D02*
X1438785Y877654D01*
G01X1437751Y877668D02*
X1436420Y877680D01*
G01X1441235Y874483D02*
X1438785Y874504D01*
G01X1437751Y874519D02*
X1436420Y874531D01*
G01X1441235Y871333D02*
X1438785Y871355D01*
G01X1437751Y871369D02*
X1436420Y871381D01*
G01X1441235Y888033D02*
X1441007D01*
G01X1439047Y888011D02*
X1438785D01*
G01X1439047Y887103D02*
X1438785D01*
G01X1441235Y887081D02*
X1441007D01*
G01X1441235Y884883D02*
X1441007D01*
G01X1439047Y884861D02*
X1438785D01*
G01X1439047Y883953D02*
X1438785D01*
G01X1441235Y883932D02*
X1441007D01*
G01X1441235Y881733D02*
X1441007D01*
G01X1439047Y881712D02*
X1438785D01*
G01X1439047Y880804D02*
X1438785D01*
G01X1441235Y880782D02*
X1441007D01*
G01X1441235Y878584D02*
X1441007D01*
G01X1439047Y878562D02*
X1438785D01*
G01X1439047Y877654D02*
X1438785D01*
G01X1441235Y877633D02*
X1441007D01*
G01X1441235Y875434D02*
X1441007D01*
G01X1439047Y875413D02*
X1438785D01*
G01X1439047Y874504D02*
X1438785D01*
G01X1441235Y874483D02*
X1441007D01*
G01X1441235Y872285D02*
X1441007D01*
G01X1439047Y872263D02*
X1438785D01*
G01X1439047Y871355D02*
X1438785D01*
G01X1441235Y871333D02*
X1441007D01*
G01X1449937Y867872D02*
X1430449D01*
G01X1440094Y881723D02*
X1438785Y881712D01*
G01X1441235Y881733D02*
X1440094Y881723D01*
G01Y878574D02*
X1438785Y878562D01*
G01X1441235Y878584D02*
X1440094Y878574D01*
G01Y875424D02*
X1438785Y875413D01*
G01X1441235Y875434D02*
X1440094Y875424D01*
G01Y872275D02*
X1438785Y872263D01*
G01X1441235Y872285D02*
X1440094Y872275D01*
G01X1437751Y881698D02*
X1436420Y881686D01*
G01X1437751Y878548D02*
X1436420Y878536D01*
G01X1437751Y875398D02*
X1436420Y875387D01*
G01X1437751Y872249D02*
X1436420Y872237D01*
G01X1442543Y881750D02*
X1441007Y881733D01*
G01X1442543Y881750D02*
X1439047Y881712D01*
G01X1441235Y881733D02*
X1442772Y881750D01*
G01X1442543Y878600D02*
X1441007Y878584D01*
G01X1442543Y878600D02*
X1439047Y878562D01*
G01X1441235Y878584D02*
X1442772Y878600D01*
G01X1442543Y875451D02*
X1441007Y875434D01*
G01X1442543Y875451D02*
X1439047Y875413D01*
G01X1441235Y875434D02*
X1442772Y875451D01*
G01X1442543Y872301D02*
X1441007Y872285D01*
G01X1442543Y872301D02*
X1439047Y872263D01*
G01X1441235Y872285D02*
X1442772Y872301D01*
G01X1439047Y881712D02*
X1440094Y881723D01*
G01X1438785Y881712D02*
X1436420Y881686D01*
G01X1437751Y881698D02*
X1439047Y881712D01*
G01Y878562D02*
X1440094Y878574D01*
G01X1438785Y878562D02*
X1436420Y878536D01*
G01X1437751Y878548D02*
X1439047Y878562D01*
G01Y875413D02*
X1440094Y875424D01*
G01X1438785Y875413D02*
X1436420Y875387D01*
G01X1437751Y875398D02*
X1439047Y875413D01*
G01Y872263D02*
X1440094Y872275D01*
G01X1438785Y872263D02*
X1436420Y872237D01*
G01X1437751Y872249D02*
X1439047Y872263D01*
G01X1441235Y872285D02*
Y871333D01*
G01Y878584D02*
Y877633D01*
G01Y875434D02*
Y874483D01*
G01Y881733D02*
Y880782D01*
G01Y888033D02*
Y887081D01*
G01Y884883D02*
Y883932D01*
G01Y891182D02*
Y890231D01*
G01Y897481D02*
Y896530D01*
G01Y894332D02*
Y893381D01*
G01Y900631D02*
Y899680D01*
G01Y906930D02*
Y905979D01*
G01Y903781D02*
Y902829D01*
G01Y910080D02*
Y909129D01*
G01Y913229D02*
Y912278D01*
G01Y919529D02*
Y918577D01*
G01Y916379D02*
Y915428D01*
G01X1441007Y872285D02*
Y871333D01*
G01Y878584D02*
Y877633D01*
G01Y875434D02*
Y874483D01*
G01Y881733D02*
Y880782D01*
G01Y888033D02*
Y887081D01*
G01Y884883D02*
Y883932D01*
G01Y891182D02*
Y890231D01*
G01Y897481D02*
Y896530D01*
G01Y894332D02*
Y893381D01*
G01Y900631D02*
Y899680D01*
G01Y906930D02*
Y905979D01*
G01Y903781D02*
Y902829D01*
G01Y910080D02*
Y909129D01*
G01Y913230D02*
Y912278D01*
G01Y919529D02*
Y918577D01*
G01Y916379D02*
Y915428D01*
G01X1439047Y872263D02*
Y871355D01*
G01Y878562D02*
Y877654D01*
G01Y875413D02*
Y874504D01*
G01Y881712D02*
Y880804D01*
G01Y888011D02*
Y887103D01*
G01Y884862D02*
Y883953D01*
G01Y891161D02*
Y890252D01*
G01Y897460D02*
Y896552D01*
G01Y894310D02*
Y893402D01*
G01Y900610D02*
Y899701D01*
G01Y906909D02*
Y906000D01*
G01Y903759D02*
Y902851D01*
G01Y910058D02*
Y909150D01*
G01Y913208D02*
Y912300D01*
G01Y919507D02*
Y918599D01*
G01Y916358D02*
Y915449D01*
G01X1438785Y872263D02*
Y871355D01*
G01Y878562D02*
Y877654D01*
G01Y875413D02*
Y874504D01*
G01Y881712D02*
Y880804D01*
G01Y888011D02*
Y887103D01*
G01Y884862D02*
Y883953D01*
G01Y891161D02*
Y890253D01*
G01Y897460D02*
Y896552D01*
G01Y894310D02*
Y893402D01*
G01Y900610D02*
Y899701D01*
G01Y906909D02*
Y906001D01*
G01Y903759D02*
Y902851D01*
G01Y910058D02*
Y909150D01*
G01Y913208D02*
Y912300D01*
G01Y919507D02*
Y918599D01*
G01Y916358D02*
Y915449D01*
G01X1437751Y872243D02*
Y871375D01*
G01Y878542D02*
Y877674D01*
G01Y875392D02*
Y874525D01*
G01Y881692D02*
Y880824D01*
G01Y887991D02*
Y887123D01*
G01Y884841D02*
Y883973D01*
G01Y891141D02*
Y890273D01*
G01Y897440D02*
Y896572D01*
G01Y894290D02*
Y893422D01*
G01Y900589D02*
Y899721D01*
G01Y906889D02*
Y906021D01*
G01Y903739D02*
Y902871D01*
G01Y910038D02*
Y909170D01*
G01Y913188D02*
Y912320D01*
G01Y919487D02*
Y918619D01*
G01Y916337D02*
Y915470D01*
G01X1436420Y872237D02*
Y871381D01*
G01Y878536D02*
Y877680D01*
G01Y875387D02*
Y874531D01*
G01Y881686D02*
Y880830D01*
G01Y887985D02*
Y887129D01*
G01Y884835D02*
Y883979D01*
G01Y891135D02*
Y890279D01*
G01Y897434D02*
Y896578D01*
G01Y894284D02*
Y893428D01*
G01Y900583D02*
Y899727D01*
G01Y906883D02*
Y906027D01*
G01Y903733D02*
Y902877D01*
G01Y910032D02*
Y909176D01*
G01Y913182D02*
Y912326D01*
G01Y919481D02*
Y918625D01*
G01Y916331D02*
Y915475D01*
G01X1430449Y1011179D02*
Y869840D01*
G01X1426512Y865903D02*
Y860785D01*
G01Y873384D02*
X1429239Y871809D01*
G01X1469113Y849367D02*
X1448165Y849762D01*
G01X1469038Y849368D02*
X1448165Y849762D01*
G01X1479661Y849368D02*
X1469031D01*
G01X1475110Y872144D02*
X1473889Y871745D01*
G01X1473165Y871524D02*
X1473708Y871701D01*
G01X1475291Y871966D02*
X1473165Y871258D01*
G01X1443073Y872596D02*
X1442684Y872389D01*
G01X1443073Y875746D02*
X1442684Y875539D01*
G01X1443073Y878896D02*
X1442684Y878688D01*
G01X1443073Y882045D02*
X1442684Y881838D01*
G01X1443073Y885195D02*
X1442684Y884987D01*
G01X1443073Y888344D02*
X1442684Y888137D01*
G01X1443073Y891494D02*
X1442684Y891287D01*
G01X1443073Y894644D02*
X1442684Y894436D01*
G01X1443073Y897793D02*
X1442684Y897586D01*
G01X1443073Y900943D02*
X1442684Y900735D01*
G01X1443073Y904092D02*
X1442684Y903885D01*
G01X1443073Y907242D02*
X1442684Y907035D01*
G01X1443073Y910392D02*
X1442684Y910184D01*
G01X1443073Y913541D02*
X1442684Y913334D01*
G01X1443073Y916691D02*
X1442684Y916483D01*
G01X1443073Y919840D02*
X1442684Y919633D01*
G01X1443243Y872596D02*
X1442772Y872301D01*
G01X1442684Y872389D02*
X1442543Y872301D01*
G01X1443243Y875746D02*
X1442772Y875451D01*
G01X1442684Y875539D02*
X1442543Y875451D01*
G01X1443243Y878896D02*
X1442772Y878600D01*
G01X1442684Y878688D02*
X1442543Y878600D01*
G01X1443243Y882045D02*
X1442772Y881750D01*
G01X1442684Y881838D02*
X1442543Y881750D01*
G01X1443243Y885195D02*
X1442772Y884900D01*
G01X1442684Y884987D02*
X1442543Y884900D01*
G01X1443243Y888344D02*
X1442772Y888049D01*
G01X1442684Y888137D02*
X1442543Y888049D01*
G01X1443243Y891494D02*
X1442772Y891199D01*
G01X1442684Y891287D02*
X1442543Y891199D01*
G01X1443243Y894644D02*
X1442772Y894348D01*
G01X1442684Y894436D02*
X1442543Y894348D01*
G01X1443243Y897793D02*
X1442772Y897498D01*
G01X1442684Y897586D02*
X1442543Y897498D01*
G01X1443243Y900943D02*
X1442772Y900648D01*
G01X1442684Y900735D02*
X1442543Y900648D01*
G01X1443243Y904092D02*
X1442772Y903797D01*
G01X1442684Y903885D02*
X1442543Y903797D01*
G01X1443243Y907242D02*
X1442772Y906947D01*
G01X1442684Y907035D02*
X1442543Y906947D01*
G01X1443243Y910392D02*
X1442772Y910096D01*
G01X1442684Y910184D02*
X1442543Y910096D01*
G01X1443243Y913541D02*
X1442772Y913246D01*
G01X1442684Y913334D02*
X1442543Y913246D01*
G01X1443243Y916691D02*
X1442772Y916396D01*
G01X1442684Y916483D02*
X1442543Y916396D01*
G01X1443243Y919840D02*
X1442772Y919545D01*
G01X1442684Y919633D02*
X1442543Y919545D01*
G01X1497767Y861264D02*
X1493047Y856623D01*
G01Y857726D02*
X1497772Y862372D01*
G01X1469507Y871474D02*
X1469278Y871218D01*
G01X1469507Y874624D02*
X1469278Y874368D01*
G01X1469507Y877774D02*
X1469278Y877518D01*
G01X1469507Y880923D02*
X1469278Y880667D01*
G01X1469507Y884073D02*
X1469278Y883817D01*
G01X1469507Y887222D02*
X1469278Y886966D01*
G01X1469507Y890372D02*
X1469278Y890116D01*
G01X1469507Y893522D02*
X1469278Y893266D01*
G01X1469507Y896671D02*
X1469278Y896415D01*
G01X1469507Y899821D02*
X1469278Y899565D01*
G01X1469507Y902970D02*
X1469278Y902714D01*
G01X1469507Y906120D02*
X1469278Y905864D01*
G01X1469507Y909270D02*
X1469278Y909014D01*
G01X1469507Y912419D02*
X1469278Y912163D01*
G01X1469507Y915569D02*
X1469278Y915313D01*
G01X1469507Y918718D02*
X1469278Y918463D01*
G01X1469855Y871474D02*
X1469636Y871204D01*
G01X1469855Y874624D02*
X1469636Y874354D01*
G01X1469855Y877774D02*
X1469636Y877503D01*
G01X1469855Y880923D02*
X1469636Y880653D01*
G01X1469855Y884073D02*
X1469636Y883803D01*
G01X1469855Y887222D02*
X1469636Y886952D01*
G01X1469855Y890372D02*
X1469636Y890102D01*
G01X1469855Y893522D02*
X1469636Y893252D01*
G01X1469855Y896671D02*
X1469636Y896401D01*
G01X1469855Y899821D02*
X1469636Y899551D01*
G01X1469855Y902970D02*
X1469636Y902700D01*
G01X1469855Y906120D02*
X1469636Y905850D01*
G01X1469855Y909270D02*
X1469636Y909000D01*
G01X1469855Y912419D02*
X1469636Y912149D01*
G01X1469855Y915569D02*
X1469636Y915299D01*
G01X1469855Y918718D02*
X1469636Y918448D01*
G01X1457732Y920234D02*
X1457220D01*
G01X1444212Y919840D02*
X1443073D01*
G01X1469631Y919644D02*
X1457535D01*
G01X1442772Y919545D02*
X1442543D01*
G01X1470921Y919388D02*
X1469507D01*
G01X1470921Y918718D02*
X1469507D01*
G01X1442772Y918561D02*
X1442543D01*
G01X1469631Y918463D02*
X1457535D01*
G01X1444212Y918266D02*
X1443073D01*
G01X1457732Y917872D02*
X1457220D01*
G01X1457732Y917085D02*
X1457220D01*
G01X1444212Y916691D02*
X1443073D01*
G01X1469631Y916494D02*
X1457535D01*
G01X1442772Y916396D02*
X1442543D01*
G01X1470921Y916238D02*
X1469507D01*
G01X1470921Y915569D02*
X1469507D01*
G01X1442772Y915411D02*
X1442543D01*
G01X1469631Y915313D02*
X1457535D01*
G01X1444212Y915116D02*
X1443073D01*
G01X1457732Y914722D02*
X1457220D01*
G01X1457732Y913935D02*
X1457220D01*
G01X1444212Y913541D02*
X1443073D01*
G01X1469631Y913344D02*
X1457535D01*
G01X1442772Y913246D02*
X1442543D01*
G01X1470921Y913088D02*
X1469507D01*
G01X1470921Y912419D02*
X1469507D01*
G01X1442772Y912262D02*
X1442543D01*
G01X1469631Y912163D02*
X1457535D01*
G01X1444212Y911966D02*
X1443073D01*
G01X1457732Y911573D02*
X1457220D01*
G01X1457732Y910785D02*
X1457220D01*
G01X1444212Y910392D02*
X1443073D01*
G01X1469631Y910195D02*
X1457535D01*
G01X1442772Y910096D02*
X1442543D01*
G01X1470921Y909939D02*
X1469507D01*
G01X1470921Y909270D02*
X1469507D01*
G01X1442772Y909112D02*
X1442543D01*
G01X1469631Y909014D02*
X1457535D01*
G01X1444212Y908817D02*
X1443073D01*
G01X1457732Y908423D02*
X1457220D01*
G01X1457732Y907636D02*
X1457220D01*
G01X1444212Y907242D02*
X1443073D01*
G01X1469631Y907045D02*
X1457535D01*
G01X1442772Y906947D02*
X1442543D01*
G01X1470921Y906789D02*
X1469507D01*
G01X1470921Y906120D02*
X1469507D01*
G01X1442772Y905963D02*
X1442543D01*
G01X1469631Y905864D02*
X1457535D01*
G01X1444212Y905667D02*
X1443073D01*
G01X1457732Y905274D02*
X1457220D01*
G01X1457732Y904486D02*
X1457220D01*
G01X1444212Y904092D02*
X1443073D01*
G01X1469631Y903896D02*
X1457535D01*
G01X1442772Y903797D02*
X1442543D01*
G01X1470921Y903640D02*
X1469507D01*
G01X1470921Y902970D02*
X1469507D01*
G01X1442772Y902813D02*
X1442543D01*
G01X1469631Y902714D02*
X1457535D01*
G01X1444212Y902518D02*
X1443073D01*
G01X1457732Y902124D02*
X1457220D01*
G01X1457732Y901337D02*
X1457220D01*
G01X1444212Y900943D02*
X1443073D01*
G01X1469631Y900746D02*
X1457535D01*
G01X1442772Y900648D02*
X1442543D01*
G01X1470921Y900490D02*
X1469507D01*
G01X1470921Y899821D02*
X1469507D01*
G01X1442772Y899663D02*
X1442543D01*
G01X1469631Y899565D02*
X1457535D01*
G01X1444212Y899368D02*
X1443073D01*
G01X1457732Y898974D02*
X1457220D01*
G01X1457732Y898187D02*
X1457220D01*
G01X1444212Y897793D02*
X1443073D01*
G01X1469631Y897596D02*
X1457535D01*
G01X1442772Y897498D02*
X1442543D01*
G01X1470921Y897340D02*
X1469507D01*
G01X1470921Y896671D02*
X1469507D01*
G01X1442772Y896514D02*
X1442543D01*
G01X1469631Y896415D02*
X1457535D01*
G01X1444212Y896218D02*
X1443073D01*
G01X1457732Y895825D02*
X1457220D01*
G01X1457732Y895037D02*
X1457220D01*
G01X1444212Y894644D02*
X1443073D01*
G01X1469631Y894447D02*
X1457535D01*
G01X1442772Y894348D02*
X1442543D01*
G01X1470921Y894191D02*
X1469507D01*
G01X1470921Y893522D02*
X1469507D01*
G01X1442772Y893364D02*
X1442543D01*
G01X1469631Y893266D02*
X1457535D01*
G01X1444212Y893069D02*
X1443073D01*
G01X1457732Y892675D02*
X1457220D01*
G01X1457732Y891888D02*
X1457220D01*
G01X1444212Y891494D02*
X1443073D01*
G01X1469631Y891297D02*
X1457535D01*
G01X1442772Y891199D02*
X1442543D01*
G01X1470921Y891041D02*
X1469507D01*
G01X1470921Y890372D02*
X1469507D01*
G01X1442772Y890214D02*
X1442543D01*
G01X1469631Y890116D02*
X1457535D01*
G01X1444212Y889919D02*
X1443073D01*
G01X1457732Y889525D02*
X1457220D01*
G01X1457732Y888738D02*
X1457220D01*
G01X1444212Y888344D02*
X1443073D01*
G01X1469631Y888148D02*
X1457535D01*
G01X1442772Y888049D02*
X1442543D01*
G01X1470921Y887892D02*
X1469507D01*
G01X1470921Y887222D02*
X1469507D01*
G01X1442772Y887065D02*
X1442543D01*
G01X1469631Y886966D02*
X1457535D01*
G01X1444212Y886770D02*
X1443073D01*
G01X1457732Y886376D02*
X1457220D01*
G01X1457732Y885588D02*
X1457220D01*
G01X1444212Y885195D02*
X1443073D01*
G01X1469631Y884998D02*
X1457535D01*
G01X1442772Y884900D02*
X1442543D01*
G01X1470921Y884742D02*
X1469507D01*
G01X1470921Y884073D02*
X1469507D01*
G01X1442772Y883915D02*
X1442543D01*
G01X1469631Y883817D02*
X1457535D01*
G01X1444212Y883620D02*
X1443073D01*
G01X1457732Y883226D02*
X1457220D01*
G01X1457732Y882439D02*
X1457220D01*
G01X1444212Y882045D02*
X1443073D01*
G01X1469631Y881848D02*
X1457535D01*
G01X1442772Y881750D02*
X1442543D01*
G01X1470921Y881592D02*
X1469507D01*
G01X1470921Y880923D02*
X1469507D01*
G01X1442772Y880766D02*
X1442543D01*
G01X1469631Y880667D02*
X1457535D01*
G01X1444212Y880470D02*
X1443073D01*
G01X1457732Y880077D02*
X1457220D01*
G01X1457732Y879289D02*
X1457220D01*
G01X1444212Y878896D02*
X1443073D01*
G01X1469631Y878699D02*
X1457535D01*
G01X1442772Y878600D02*
X1442543D01*
G01X1470921Y878443D02*
X1469507D01*
G01X1470921Y877774D02*
X1469507D01*
G01X1442772Y877616D02*
X1442543D01*
G01X1469631Y877518D02*
X1457535D01*
G01X1444212Y877321D02*
X1443073D01*
G01X1457732Y876927D02*
X1457220D01*
G01X1457732Y876140D02*
X1457220D01*
G01X1444212Y875746D02*
X1443073D01*
G01X1469631Y875549D02*
X1457535D01*
G01X1442772Y875451D02*
X1442543D01*
G01X1470921Y875293D02*
X1469507D01*
G01X1470921Y874624D02*
X1469507D01*
G01X1442772Y874466D02*
X1442543D01*
G01X1469631Y874368D02*
X1457535D01*
G01X1444212Y874171D02*
X1443073D01*
G01X1457732Y873777D02*
X1457220D01*
G01X1457732Y872990D02*
X1457220D01*
G01X1461157Y872793D02*
X1471000D01*
G01X1444212Y872596D02*
X1443073D01*
G01X1469631Y872400D02*
X1457535D01*
G01X1442772Y872301D02*
X1442543D01*
G01X1470921Y872144D02*
X1469507D01*
G01X1470921Y871474D02*
X1469507D01*
G01X1442772Y871317D02*
X1442543D01*
G01X1469631Y871218D02*
X1457535D01*
G01X1444212Y871022D02*
X1443073D01*
G01X1474613Y870903D02*
X1474975D01*
G01X1471000Y870825D02*
X1461157D01*
G01X1473165Y870638D02*
X1474929D01*
G01X1457732Y870628D02*
X1457220D01*
G01X1475291Y870372D02*
X1473165D01*
G01X1479661Y860785D02*
X1461157D01*
G01X1473165Y873029D02*
X1475291Y872321D01*
G01X1473889Y872542D02*
X1475110Y872144D01*
G01X1473708Y872587D02*
X1473165Y872764D01*
G01X1493047Y855994D02*
Y857726D01*
G01X1475291Y870638D02*
Y870372D01*
G01Y872321D02*
Y871966D01*
G01X1473889Y871745D02*
Y872542D01*
G01X1473708Y871701D02*
Y872587D01*
G01X1473165Y870372D02*
Y870638D01*
G01Y871258D02*
Y871524D01*
G01Y872764D02*
Y873029D01*
G01X1471000Y872793D02*
Y870825D01*
G01X1470921Y872144D02*
Y871474D01*
G01Y878443D02*
Y877774D01*
G01Y875293D02*
Y874624D01*
G01Y881592D02*
Y880923D01*
G01Y887892D02*
Y887222D01*
G01Y884742D02*
Y884073D01*
G01Y891041D02*
Y890372D01*
G01Y897340D02*
Y896671D01*
G01Y894191D02*
Y893522D01*
G01Y900490D02*
Y899821D01*
G01Y906789D02*
Y906120D01*
G01Y903640D02*
Y902970D01*
G01Y909939D02*
Y909270D01*
G01Y916238D02*
Y915569D01*
G01Y913088D02*
Y912419D01*
G01Y919388D02*
Y918718D01*
G01X1470574Y872144D02*
Y871474D01*
G01Y878443D02*
Y877774D01*
G01Y875293D02*
Y874624D01*
G01Y881592D02*
Y880923D01*
G01Y887892D02*
Y887222D01*
G01Y884742D02*
Y884073D01*
G01Y891041D02*
Y890372D01*
G01Y897340D02*
Y896671D01*
G01Y894191D02*
Y893522D01*
G01Y900490D02*
Y899821D01*
G01Y906789D02*
Y906120D01*
G01Y903640D02*
Y902970D01*
G01Y909939D02*
Y909270D01*
G01Y916238D02*
Y915569D01*
G01Y913088D02*
Y912419D01*
G01Y919388D02*
Y918718D01*
G01X1469631Y872400D02*
Y871218D01*
G01Y878699D02*
Y877518D01*
G01Y875549D02*
Y874368D01*
G01Y881848D02*
Y880667D01*
G01Y888148D02*
Y886966D01*
G01Y884998D02*
Y883817D01*
G01Y891297D02*
Y890116D01*
G01Y894447D02*
Y893266D01*
G01Y900746D02*
Y899565D01*
G01Y897596D02*
Y896415D01*
G01Y903896D02*
Y902714D01*
G01Y910195D02*
Y909014D01*
G01Y907045D02*
Y905864D01*
G01Y913344D02*
Y912163D01*
G01Y919644D02*
Y918463D01*
G01Y916494D02*
Y915313D01*
G01X1469278Y872400D02*
Y871218D01*
G01Y878699D02*
Y877518D01*
G01Y875549D02*
Y874368D01*
G01Y881848D02*
Y880667D01*
G01Y888148D02*
Y886966D01*
G01Y884998D02*
Y883817D01*
G01Y891297D02*
Y890116D01*
G01Y894447D02*
Y893266D01*
G01Y900746D02*
Y899565D01*
G01Y897596D02*
Y896415D01*
G01Y903896D02*
Y902714D01*
G01Y910195D02*
Y909014D01*
G01Y907045D02*
Y905864D01*
G01Y913344D02*
Y912163D01*
G01Y919644D02*
Y918463D01*
G01Y916494D02*
Y915313D01*
G01X1467296Y872400D02*
Y871218D01*
G01Y878699D02*
Y877518D01*
G01Y875549D02*
Y874368D01*
G01Y881848D02*
Y880667D01*
G01Y888148D02*
Y886966D01*
G01Y884998D02*
Y883817D01*
G01Y891297D02*
Y890116D01*
G01Y894447D02*
Y893266D01*
G01Y900746D02*
Y899565D01*
G01Y897596D02*
Y896415D01*
G01Y903896D02*
Y902714D01*
G01Y910195D02*
Y909014D01*
G01Y907045D02*
Y905864D01*
G01Y913344D02*
Y912163D01*
G01Y919644D02*
Y918463D01*
G01Y916494D02*
Y915313D01*
G01X1467186Y872400D02*
Y871218D01*
G01Y878699D02*
Y877518D01*
G01Y875549D02*
Y874368D01*
G01Y881848D02*
Y880667D01*
G01Y888148D02*
Y886966D01*
G01Y884998D02*
Y883817D01*
G01Y891297D02*
Y890116D01*
G01Y894447D02*
Y893266D01*
G01Y900746D02*
Y899565D01*
G01Y897596D02*
Y896415D01*
G01Y903896D02*
Y902714D01*
G01Y910195D02*
Y909014D01*
G01Y907045D02*
Y905864D01*
G01Y913344D02*
Y912163D01*
G01Y919644D02*
Y918463D01*
G01Y916494D02*
Y915313D01*
G01X1461157Y870825D02*
Y872793D01*
G01X1458405Y872400D02*
Y871218D01*
G01Y878699D02*
Y877518D01*
G01Y875549D02*
Y874368D01*
G01Y881848D02*
Y880667D01*
G01Y888148D02*
Y886966D01*
G01Y884998D02*
Y883817D01*
G01Y891297D02*
Y890116D01*
G01Y894447D02*
Y893266D01*
G01Y900746D02*
Y899565D01*
G01Y897596D02*
Y896415D01*
G01Y903896D02*
Y902714D01*
G01Y910195D02*
Y909014D01*
G01Y907045D02*
Y905864D01*
G01Y913344D02*
Y912163D01*
G01Y919644D02*
Y918463D01*
G01Y916494D02*
Y915313D01*
G01X1458295Y872400D02*
Y871218D01*
G01Y878699D02*
Y877518D01*
G01Y875549D02*
Y874368D01*
G01Y881848D02*
Y880667D01*
G01Y888148D02*
Y886966D01*
G01Y884998D02*
Y883817D01*
G01Y891297D02*
Y890116D01*
G01Y894447D02*
Y893266D01*
G01Y900746D02*
Y899565D01*
G01Y897596D02*
Y896415D01*
G01Y903896D02*
Y902714D01*
G01Y910195D02*
Y909014D01*
G01Y907045D02*
Y905864D01*
G01Y913344D02*
Y912163D01*
G01Y919644D02*
Y918463D01*
G01Y916494D02*
Y915313D01*
G01X1457929Y872400D02*
Y871218D01*
G01Y878699D02*
Y877518D01*
G01Y875549D02*
Y874368D01*
G01Y881848D02*
Y880667D01*
G01Y888148D02*
Y886966D01*
G01Y884998D02*
Y883817D01*
G01Y891297D02*
Y890116D01*
G01Y894447D02*
Y893266D01*
G01Y900746D02*
Y899565D01*
G01Y897596D02*
Y896415D01*
G01Y903896D02*
Y902714D01*
G01Y910195D02*
Y909014D01*
G01Y907045D02*
Y905864D01*
G01Y913344D02*
Y912163D01*
G01Y919644D02*
Y918463D01*
G01Y916494D02*
Y915313D01*
G01X1457732Y871218D02*
Y870628D01*
G01Y872990D02*
Y872400D01*
G01Y877518D02*
Y876927D01*
G01Y874368D02*
Y873777D01*
G01Y876140D02*
Y875549D01*
G01Y880667D02*
Y880077D01*
G01Y882439D02*
Y881848D01*
G01Y879289D02*
Y878699D01*
G01Y886966D02*
Y886376D01*
G01Y883817D02*
Y883226D01*
G01Y885588D02*
Y884998D01*
G01Y890116D02*
Y889525D01*
G01Y891888D02*
Y891297D01*
G01Y888738D02*
Y888148D01*
G01Y896415D02*
Y895825D01*
G01Y893266D02*
Y892675D01*
G01Y895037D02*
Y894447D01*
G01Y899565D02*
Y898974D01*
G01Y901337D02*
Y900746D01*
G01Y898187D02*
Y897596D01*
G01Y905864D02*
Y905274D01*
G01Y902714D02*
Y902124D01*
G01Y904486D02*
Y903896D01*
G01Y909014D02*
Y908423D01*
G01Y910785D02*
Y910195D01*
G01Y907636D02*
Y907045D01*
G01Y915313D02*
Y914722D01*
G01Y912163D02*
Y911573D01*
G01Y913935D02*
Y913344D01*
G01Y918463D02*
Y917872D01*
G01Y920234D02*
Y919644D01*
G01Y917085D02*
Y916494D01*
G01X1457535Y871218D02*
Y870628D01*
G01Y872990D02*
Y872400D01*
G01Y877518D02*
Y876927D01*
G01Y874368D02*
Y873777D01*
G01Y876140D02*
Y875549D01*
G01Y880667D02*
Y880077D01*
G01Y882439D02*
Y881848D01*
G01Y879289D02*
Y878699D01*
G01Y886966D02*
Y886376D01*
G01Y883817D02*
Y883226D01*
G01Y885588D02*
Y884998D01*
G01Y890116D02*
Y889525D01*
G01Y891888D02*
Y891297D01*
G01Y888738D02*
Y888148D01*
G01Y896415D02*
Y895825D01*
G01Y893266D02*
Y892675D01*
G01Y895037D02*
Y894447D01*
G01Y899565D02*
Y898974D01*
G01Y901337D02*
Y900746D01*
G01Y898187D02*
Y897596D01*
G01Y905864D02*
Y905274D01*
G01Y902714D02*
Y902124D01*
G01Y904486D02*
Y903896D01*
G01Y909014D02*
Y908423D01*
G01Y910785D02*
Y910195D01*
G01Y907636D02*
Y907045D01*
G01Y915313D02*
Y914722D01*
G01Y912163D02*
Y911573D01*
G01Y913935D02*
Y913344D01*
G01Y918463D02*
Y917872D01*
G01Y920234D02*
Y919644D01*
G01Y917085D02*
Y916494D01*
G01X1449937Y1011179D02*
Y867872D01*
G01X1444212Y872596D02*
Y871022D01*
G01Y875746D02*
Y874171D01*
G01Y882045D02*
Y880470D01*
G01Y878896D02*
Y877321D01*
G01Y885195D02*
Y883620D01*
G01Y891494D02*
Y889919D01*
G01Y888344D02*
Y886770D01*
G01Y894644D02*
Y893069D01*
G01Y900943D02*
Y899368D01*
G01Y897793D02*
Y896218D01*
G01Y904092D02*
Y902518D01*
G01Y910392D02*
Y908817D01*
G01Y907242D02*
Y905667D01*
G01Y913541D02*
Y911966D01*
G01Y919840D02*
Y918266D01*
G01Y916691D02*
Y915116D01*
G01X1442684Y872389D02*
Y871229D01*
G01Y878688D02*
Y877528D01*
G01Y875539D02*
Y874379D01*
G01Y881838D02*
Y880678D01*
G01Y888137D02*
Y886977D01*
G01Y884987D02*
Y883827D01*
G01Y891287D02*
Y890127D01*
G01Y894436D02*
Y893276D01*
G01Y900735D02*
Y899575D01*
G01Y897586D02*
Y896426D01*
G01Y903885D02*
Y902725D01*
G01Y910184D02*
Y909024D01*
G01Y907035D02*
Y905875D01*
G01Y913334D02*
Y912174D01*
G01Y919633D02*
Y918473D01*
G01Y916483D02*
Y915324D01*
G01X1469636Y919658D02*
X1469855Y919388D01*
G01X1469278Y919644D02*
X1469507Y919388D01*
G01X1469278Y916494D02*
X1469507Y916238D01*
G01X1469278Y913344D02*
X1469507Y913088D01*
G01X1442772Y918561D02*
X1443243Y918266D01*
G01X1442543Y918561D02*
X1442684Y918473D01*
G01X1442772Y915411D02*
X1443243Y915116D01*
G01X1442543Y915411D02*
X1442684Y915324D01*
G01X1442772Y912262D02*
X1443243Y911966D01*
G01X1442543Y912262D02*
X1442684Y912174D01*
G01X1442772Y909112D02*
X1443243Y908817D01*
G01X1442543Y909112D02*
X1442684Y909024D01*
G01X1442772Y905963D02*
X1443243Y905667D01*
G01X1442543Y905963D02*
X1442684Y905875D01*
G01X1442772Y902813D02*
X1443243Y902518D01*
G01X1442543Y902813D02*
X1442684Y902725D01*
G01X1442772Y899663D02*
X1443243Y899368D01*
G01X1442543Y899663D02*
X1442684Y899575D01*
G01X1442772Y896514D02*
X1443243Y896218D01*
G01X1442543Y896514D02*
X1442684Y896426D01*
G01X1442772Y893364D02*
X1443243Y893069D01*
G01X1442543Y893364D02*
X1442684Y893276D01*
G01X1442772Y890214D02*
X1443243Y889919D01*
G01X1442543Y890214D02*
X1442684Y890127D01*
G01X1442772Y887065D02*
X1443243Y886770D01*
G01X1442543Y887065D02*
X1442684Y886977D01*
G01X1442772Y883915D02*
X1443243Y883620D01*
G01X1442543Y883915D02*
X1442684Y883827D01*
G01X1442772Y880766D02*
X1443243Y880470D01*
G01X1442543Y880766D02*
X1442684Y880678D01*
G01X1496457Y854025D02*
X1493047Y855994D01*
G01X1442684Y918473D02*
X1443073Y918266D01*
G01X1442684Y915324D02*
X1443073Y915116D01*
G01X1442684Y912174D02*
X1443073Y911966D01*
G01X1442684Y909024D02*
X1443073Y908817D01*
G01X1442684Y905875D02*
X1443073Y905667D01*
G01X1442684Y902725D02*
X1443073Y902518D01*
G01X1442684Y899575D02*
X1443073Y899368D01*
G01X1442684Y896426D02*
X1443073Y896218D01*
G01X1442684Y893276D02*
X1443073Y893069D01*
G01X1442684Y890127D02*
X1443073Y889919D01*
G01X1442684Y886977D02*
X1443073Y886770D01*
G01X1442684Y883827D02*
X1443073Y883620D01*
G01X1442684Y880678D02*
X1443073Y880470D01*
G01X1442684Y877528D02*
X1443073Y877321D01*
G01X1442684Y874379D02*
X1443073Y874171D01*
G01X1442684Y871229D02*
X1443073Y871022D01*
G01X1469636Y916508D02*
X1469855Y916238D01*
G01X1469636Y913359D02*
X1469855Y913088D01*
G01X1469636Y910209D02*
X1469855Y909939D01*
G01X1469636Y907059D02*
X1469855Y906789D01*
G01X1469636Y903910D02*
X1469855Y903640D01*
G01X1469636Y900760D02*
X1469855Y900490D01*
G01X1469636Y897610D02*
X1469855Y897340D01*
G01X1469636Y894461D02*
X1469855Y894191D01*
G01X1469636Y891311D02*
X1469855Y891041D01*
G01X1469636Y888162D02*
X1469855Y887892D01*
G01X1469636Y885012D02*
X1469855Y884742D01*
G01X1469636Y881862D02*
X1469855Y881592D01*
G01X1469636Y878713D02*
X1469855Y878443D01*
G01X1469636Y875563D02*
X1469855Y875293D01*
G01X1469636Y872414D02*
X1469855Y872144D01*
G01X1469278Y910195D02*
X1469507Y909939D01*
G01X1469278Y907045D02*
X1469507Y906789D01*
G01X1469278Y903896D02*
X1469507Y903640D01*
G01X1469278Y900746D02*
X1469507Y900490D01*
G01X1469278Y897596D02*
X1469507Y897340D01*
G01X1469278Y894447D02*
X1469507Y894191D01*
G01X1469278Y891297D02*
X1469507Y891041D01*
G01X1469278Y888148D02*
X1469507Y887892D01*
G01X1469278Y884998D02*
X1469507Y884742D01*
G01X1469278Y881848D02*
X1469507Y881592D01*
G01X1469278Y878699D02*
X1469507Y878443D01*
G01X1469278Y875549D02*
X1469507Y875293D01*
G01X1469278Y872400D02*
X1469507Y872144D01*
G01X1457220Y864722D02*
X1461157Y860785D01*
G01X1474975Y870903D02*
X1475291Y870638D01*
G01X1474929D02*
X1474613Y870903D01*
G01X1442772Y877616D02*
X1443243Y877321D01*
G01X1442543Y877616D02*
X1442684Y877528D01*
G01X1442772Y874466D02*
X1443243Y874171D01*
G01X1442543Y874466D02*
X1442684Y874379D01*
G01X1442772Y871317D02*
X1443243Y871022D01*
G01X1442543Y871317D02*
X1442684Y871229D01*
G01X1439047Y921749D02*
X1442543Y921711D01*
G01X1437751Y921763D02*
X1441007Y921727D01*
G01X1438785Y921749D02*
X1436420Y921775D01*
G01X1441235Y921727D02*
X1442772Y921711D01*
G01X1441235Y921727D02*
X1438785Y921749D01*
G01X1437751Y921763D02*
X1436420Y921775D01*
G01X1439047Y921749D02*
X1438785D01*
G01X1441235Y921727D02*
X1441007D01*
G01X1441235Y922678D02*
Y921727D01*
G01X1441007Y922678D02*
Y921727D01*
G01X1439047Y922657D02*
Y921749D01*
G01X1438785Y922657D02*
Y921749D01*
G01X1437751Y922637D02*
Y921769D01*
G01X1436420Y922631D02*
Y921775D01*
G01X1439047Y991040D02*
X1442543Y991002D01*
G01X1437751Y991054D02*
X1441007Y991018D01*
G01X1439047Y987890D02*
X1442543Y987852D01*
G01X1437751Y987905D02*
X1441007Y987869D01*
G01X1439047Y984741D02*
X1442543Y984703D01*
G01X1437751Y984755D02*
X1441007Y984719D01*
G01X1439047Y981591D02*
X1442543Y981553D01*
G01X1437751Y981605D02*
X1441007Y981570D01*
G01X1439047Y978441D02*
X1442543Y978403D01*
G01X1437751Y978456D02*
X1441007Y978420D01*
G01X1439047Y975292D02*
X1442543Y975254D01*
G01X1437751Y975306D02*
X1441007Y975270D01*
G01X1438785Y991040D02*
X1436420Y991066D01*
G01X1438785Y987890D02*
X1436420Y987916D01*
G01X1438785Y984741D02*
X1436420Y984767D01*
G01X1438785Y981591D02*
X1436420Y981617D01*
G01X1438785Y978441D02*
X1436420Y978468D01*
G01X1438785Y975292D02*
X1436420Y975318D01*
G01X1440094Y972131D02*
X1441007Y972121D01*
G01X1440094Y972131D02*
X1442543Y972104D01*
G01X1441235Y991018D02*
X1442772Y991002D01*
G01X1441235Y987869D02*
X1442772Y987852D01*
G01X1441235Y984719D02*
X1442772Y984703D01*
G01X1441235Y981570D02*
X1442772Y981553D01*
G01X1441235Y978420D02*
X1442772Y978403D01*
G01X1441235Y975270D02*
X1442772Y975254D01*
G01X1441235Y972121D02*
X1442772Y972104D01*
G01X1441235Y991018D02*
X1438785Y991040D01*
G01X1437751Y991054D02*
X1436420Y991066D01*
G01X1441235Y987869D02*
X1438785Y987890D01*
G01X1437751Y987905D02*
X1436420Y987916D01*
G01X1441235Y984719D02*
X1438785Y984741D01*
G01X1437751Y984755D02*
X1436420Y984767D01*
G01X1441235Y981570D02*
X1438785Y981591D01*
G01X1437751Y981605D02*
X1436420Y981617D01*
G01X1441235Y978420D02*
X1438785Y978441D01*
G01X1437751Y978456D02*
X1436420Y978468D01*
G01X1441235Y975270D02*
X1438785Y975292D01*
G01X1437751Y975306D02*
X1436420Y975318D01*
G01X1441235Y972121D02*
X1438785Y972142D01*
G01X1437751Y972157D02*
X1436420Y972168D01*
G01X1441235Y991970D02*
X1441007D01*
G01X1439047Y991948D02*
X1438785D01*
G01X1439047Y991040D02*
X1438785D01*
G01X1441235Y991018D02*
X1441007D01*
G01X1441235Y988820D02*
X1441007D01*
G01X1439047Y988798D02*
X1438785D01*
G01X1439047Y987890D02*
X1438785D01*
G01X1441235Y987869D02*
X1441007D01*
G01X1441235Y985670D02*
X1441007D01*
G01X1439047Y985649D02*
X1438785D01*
G01X1439047Y984741D02*
X1438785D01*
G01X1441235Y984719D02*
X1441007D01*
G01X1441235Y982521D02*
X1441007D01*
G01X1439047Y982499D02*
X1438785D01*
G01X1439047Y981591D02*
X1438785D01*
G01X1441235Y981570D02*
X1441007D01*
G01X1441235Y979371D02*
X1441007D01*
G01X1439047Y979350D02*
X1438785D01*
G01X1439047Y978441D02*
X1438785D01*
G01X1441235Y978420D02*
X1441007D01*
G01X1441235Y976222D02*
X1441007D01*
G01X1439047Y976200D02*
X1438785D01*
G01X1439047Y975292D02*
X1438785D01*
G01X1441235Y975270D02*
X1441007D01*
G01X1441235Y973072D02*
X1441007D01*
G01X1439047Y973050D02*
X1438785D01*
G01X1439047Y972142D02*
X1438785D01*
G01X1441235Y972121D02*
X1441007D01*
G01X1441235Y969922D02*
X1441007D01*
G01X1439047Y969901D02*
X1438785D01*
G01X1439047Y968993D02*
X1438785D01*
G01X1441235Y968971D02*
X1441007D01*
G01X1441235Y966773D02*
X1441007D01*
G01X1439047Y966751D02*
X1438785D01*
G01X1440094Y991960D02*
X1438785Y991948D01*
G01X1441235Y991970D02*
X1440094Y991960D01*
G01Y988810D02*
X1438785Y988798D01*
G01X1441235Y988820D02*
X1440094Y988810D01*
G01Y985660D02*
X1438785Y985649D01*
G01X1441235Y985670D02*
X1440094Y985660D01*
G01Y982511D02*
X1438785Y982499D01*
G01X1441235Y982521D02*
X1440094Y982511D01*
G01Y979361D02*
X1438785Y979350D01*
G01X1441235Y979371D02*
X1440094Y979361D01*
G01Y976212D02*
X1438785Y976200D01*
G01X1441235Y976222D02*
X1440094Y976212D01*
G01Y973062D02*
X1438785Y973050D01*
G01X1441235Y973072D02*
X1440094Y973062D01*
G01Y969912D02*
X1438785Y969901D01*
G01X1441235Y969922D02*
X1440094Y969912D01*
G01Y966763D02*
X1438785Y966751D01*
G01X1441235Y966773D02*
X1440094Y966763D01*
G01Y963613D02*
X1438785Y963602D01*
G01X1441235Y963623D02*
X1440094Y963613D01*
G01X1437751Y991934D02*
X1436420Y991922D01*
G01X1437751Y988784D02*
X1436420Y988772D01*
G01X1437751Y985635D02*
X1436420Y985623D01*
G01X1437751Y982485D02*
X1436420Y982473D01*
G01X1437751Y979335D02*
X1436420Y979324D01*
G01X1437751Y976186D02*
X1436420Y976174D01*
G01X1437751Y973036D02*
X1436420Y973024D01*
G01X1437751Y969887D02*
X1436420Y969875D01*
G01X1437751Y966737D02*
X1436420Y966725D01*
G01X1437751Y963587D02*
X1436420Y963576D01*
G01X1442543Y991986D02*
X1441007Y991970D01*
G01X1442543Y991986D02*
X1439047Y991948D01*
G01X1441235Y991970D02*
X1442772Y991986D01*
G01X1442543Y988837D02*
X1441007Y988820D01*
G01X1442543Y988837D02*
X1439047Y988799D01*
G01X1441235Y988820D02*
X1442772Y988837D01*
G01X1442543Y985687D02*
X1441007Y985670D01*
G01X1442543Y985687D02*
X1439047Y985649D01*
G01X1441235Y985670D02*
X1442772Y985687D01*
G01X1442543Y982537D02*
X1441007Y982521D01*
G01X1442543Y982537D02*
X1439047Y982499D01*
G01X1441235Y982521D02*
X1442772Y982537D01*
G01X1442543Y979388D02*
X1441007Y979371D01*
G01X1442543Y979388D02*
X1439047Y979350D01*
G01X1441235Y979371D02*
X1442772Y979388D01*
G01X1442543Y976238D02*
X1441007Y976222D01*
G01X1442543Y976238D02*
X1439047Y976200D01*
G01X1441235Y976222D02*
X1442772Y976238D01*
G01X1442543Y973088D02*
X1441007Y973072D01*
G01X1442543Y973088D02*
X1439047Y973051D01*
G01X1441235Y973072D02*
X1442772Y973088D01*
G01X1442543Y969939D02*
X1441007Y969922D01*
G01X1442543Y969939D02*
X1439047Y969901D01*
G01X1441235Y969922D02*
X1442772Y969939D01*
G01X1442543Y966789D02*
X1441007Y966773D01*
G01X1442543Y966789D02*
X1439047Y966751D01*
G01X1441235Y966773D02*
X1442772Y966789D01*
G01X1442543Y963640D02*
X1441007Y963623D01*
G01X1442543Y963640D02*
X1439047Y963602D01*
G01X1441235Y963623D02*
X1442772Y963640D01*
G01X1439047Y991948D02*
X1440094Y991960D01*
G01X1438785Y991948D02*
X1436420Y991922D01*
G01X1437751Y991934D02*
X1439047Y991948D01*
G01Y988798D02*
X1440094Y988810D01*
G01X1438785Y988798D02*
X1436420Y988772D01*
G01X1437751Y988784D02*
X1439047Y988798D01*
G01Y985649D02*
X1440094Y985660D01*
G01X1438785Y985649D02*
X1436420Y985623D01*
G01X1437751Y985635D02*
X1439047Y985649D01*
G01Y982499D02*
X1440094Y982511D01*
G01X1438785Y982499D02*
X1436420Y982473D01*
G01X1437751Y982485D02*
X1439047Y982499D01*
G01Y979350D02*
X1440094Y979361D01*
G01X1438785Y979350D02*
X1436420Y979324D01*
G01X1437751Y979335D02*
X1439047Y979350D01*
G01Y976200D02*
X1440094Y976212D01*
G01X1438785Y976200D02*
X1436420Y976174D01*
G01X1437751Y976186D02*
X1439047Y976200D01*
G01Y973050D02*
X1440094Y973062D01*
G01X1438785Y973050D02*
X1436420Y973024D01*
G01X1437751Y973036D02*
X1439047Y973050D01*
G01Y969901D02*
X1440094Y969912D01*
G01X1438785Y969901D02*
X1436420Y969875D01*
G01X1437751Y969887D02*
X1439047Y969901D01*
G01Y966751D02*
X1440094Y966763D01*
G01X1438785Y966751D02*
X1436420Y966725D01*
G01X1437751Y966737D02*
X1439047Y966751D01*
G01Y963602D02*
X1440094Y963613D01*
G01X1438785Y963602D02*
X1436420Y963576D01*
G01X1437751Y963587D02*
X1439047Y963602D01*
G01Y972142D02*
X1440094Y972131D01*
G01X1437751Y972157D02*
X1440094Y972131D01*
G01X1439047Y968993D02*
X1442543Y968955D01*
G01X1437751Y969007D02*
X1441007Y968971D01*
G01X1439047Y965843D02*
X1442543Y965805D01*
G01X1437751Y965857D02*
X1441007Y965821D01*
G01X1439047Y962693D02*
X1442543Y962655D01*
G01X1437751Y962708D02*
X1441007Y962672D01*
G01X1439047Y959544D02*
X1442543Y959506D01*
G01X1437751Y959558D02*
X1441007Y959522D01*
G01X1439047Y956394D02*
X1442543Y956356D01*
G01X1437751Y956409D02*
X1441007Y956373D01*
G01X1439047Y953245D02*
X1442543Y953207D01*
G01X1437751Y953259D02*
X1441007Y953223D01*
G01X1439047Y950095D02*
X1442543Y950057D01*
G01X1437751Y950109D02*
X1441007Y950073D01*
G01X1439047Y946945D02*
X1442543Y946907D01*
G01X1437751Y946960D02*
X1441007Y946924D01*
G01X1439047Y943796D02*
X1442543Y943758D01*
G01X1437751Y943810D02*
X1441007Y943774D01*
G01X1439047Y940646D02*
X1442543Y940608D01*
G01X1437751Y940660D02*
X1441007Y940625D01*
G01X1439047Y937497D02*
X1442543Y937459D01*
G01X1437751Y937511D02*
X1441007Y937475D01*
G01X1439047Y934347D02*
X1442543Y934309D01*
G01X1437751Y934361D02*
X1441007Y934325D01*
G01X1439047Y931197D02*
X1442543Y931159D01*
G01X1437751Y931212D02*
X1441007Y931176D01*
G01X1439047Y928048D02*
X1442543Y928010D01*
G01X1437751Y928062D02*
X1441007Y928026D01*
G01X1439047Y924898D02*
X1442543Y924860D01*
G01X1437751Y924912D02*
X1441007Y924877D01*
G01X1438785Y972142D02*
X1436420Y972168D01*
G01X1438785Y968993D02*
X1436420Y969019D01*
G01X1438785Y965843D02*
X1436420Y965869D01*
G01X1438785Y962693D02*
X1436420Y962720D01*
G01X1438785Y959544D02*
X1436420Y959570D01*
G01X1438785Y956394D02*
X1436420Y956420D01*
G01X1438785Y953245D02*
X1436420Y953271D01*
G01X1438785Y950095D02*
X1436420Y950121D01*
G01X1438785Y946945D02*
X1436420Y946971D01*
G01X1438785Y943796D02*
X1436420Y943822D01*
G01X1438785Y940646D02*
X1436420Y940672D01*
G01X1438785Y937497D02*
X1436420Y937523D01*
G01X1438785Y934347D02*
X1436420Y934373D01*
G01X1438785Y931197D02*
X1436420Y931223D01*
G01X1438785Y928048D02*
X1436420Y928074D01*
G01X1438785Y924898D02*
X1436420Y924924D01*
G01X1441235Y968971D02*
X1442772Y968955D01*
G01X1441235Y965821D02*
X1442772Y965805D01*
G01X1441235Y962672D02*
X1442772Y962655D01*
G01X1441235Y959522D02*
X1442772Y959506D01*
G01X1441235Y956373D02*
X1442772Y956356D01*
G01X1441235Y953223D02*
X1442772Y953207D01*
G01X1441235Y950073D02*
X1442772Y950057D01*
G01X1441235Y946924D02*
X1442772Y946907D01*
G01X1441235Y943774D02*
X1442772Y943758D01*
G01X1441235Y940625D02*
X1442772Y940608D01*
G01X1441235Y937475D02*
X1442772Y937459D01*
G01X1441235Y934325D02*
X1442772Y934309D01*
G01X1441235Y931176D02*
X1442772Y931159D01*
G01X1441235Y928026D02*
X1442772Y928010D01*
G01X1441235Y924877D02*
X1442772Y924860D01*
G01X1441235Y968971D02*
X1438785Y968993D01*
G01X1437751Y969007D02*
X1436420Y969019D01*
G01X1441235Y965821D02*
X1438785Y965843D01*
G01X1437751Y965857D02*
X1436420Y965869D01*
G01X1441235Y962672D02*
X1438785Y962693D01*
G01X1437751Y962708D02*
X1436420Y962720D01*
G01X1441235Y959522D02*
X1438785Y959544D01*
G01X1437751Y959558D02*
X1436420Y959570D01*
G01X1441235Y956373D02*
X1438785Y956394D01*
G01X1437751Y956409D02*
X1436420Y956420D01*
G01X1441235Y953223D02*
X1438785Y953245D01*
G01X1437751Y953259D02*
X1436420Y953271D01*
G01X1441235Y950073D02*
X1438785Y950095D01*
G01X1437751Y950109D02*
X1436420Y950121D01*
G01X1441235Y946924D02*
X1438785Y946945D01*
G01X1437751Y946960D02*
X1436420Y946971D01*
G01X1441235Y943774D02*
X1438785Y943796D01*
G01X1437751Y943810D02*
X1436420Y943822D01*
G01X1441235Y940625D02*
X1438785Y940646D01*
G01X1437751Y940660D02*
X1436420Y940672D01*
G01X1441235Y937475D02*
X1438785Y937497D01*
G01X1437751Y937511D02*
X1436420Y937523D01*
G01X1441235Y934325D02*
X1438785Y934347D01*
G01X1437751Y934361D02*
X1436420Y934373D01*
G01X1441235Y931176D02*
X1438785Y931197D01*
G01X1437751Y931212D02*
X1436420Y931223D01*
G01X1441235Y928026D02*
X1438785Y928048D01*
G01X1437751Y928062D02*
X1436420Y928074D01*
G01X1441235Y924877D02*
X1438785Y924898D01*
G01X1437751Y924912D02*
X1436420Y924924D01*
G01X1439047Y965843D02*
X1438785D01*
G01X1441235Y965821D02*
X1441007D01*
G01X1441235Y963623D02*
X1441007D01*
G01X1439047Y963602D02*
X1438785D01*
G01X1439047Y962693D02*
X1438785D01*
G01X1441235Y962672D02*
X1441007D01*
G01X1441235Y960474D02*
X1441007D01*
G01X1439047Y960452D02*
X1438785D01*
G01X1439047Y959544D02*
X1438785D01*
G01X1441235Y959522D02*
X1441007D01*
G01X1441235Y957324D02*
X1441007D01*
G01X1439047Y957302D02*
X1438785D01*
G01X1439047Y956394D02*
X1438785D01*
G01X1441235Y956373D02*
X1441007D01*
G01X1441235Y954174D02*
X1441007D01*
G01X1439047Y954153D02*
X1438785D01*
G01X1439047Y953245D02*
X1438785D01*
G01X1441235Y953223D02*
X1441007D01*
G01X1441235Y951025D02*
X1441007D01*
G01X1439047Y951003D02*
X1438785D01*
G01X1439047Y950095D02*
X1438785D01*
G01X1441235Y950073D02*
X1441007D01*
G01X1441235Y947875D02*
X1441007D01*
G01X1439047Y947854D02*
X1438785D01*
G01X1439047Y946945D02*
X1438785D01*
G01X1441235Y946924D02*
X1441007D01*
G01X1441235Y944726D02*
X1441007D01*
G01X1439047Y944704D02*
X1438785D01*
G01X1439047Y943796D02*
X1438785D01*
G01X1441235Y943774D02*
X1441007D01*
G01X1441235Y941576D02*
X1441007D01*
G01X1438785Y941554D02*
X1439047D01*
G01Y940646D02*
X1438785D01*
G01X1441235Y940625D02*
X1441007D01*
G01X1441235Y938426D02*
X1441007D01*
G01X1439047Y938405D02*
X1438785D01*
G01X1439047Y937497D02*
X1438785D01*
G01X1441235Y937475D02*
X1441007D01*
G01X1441235Y935277D02*
X1441007D01*
G01X1439047Y935255D02*
X1438785D01*
G01X1439047Y934347D02*
X1438785D01*
G01X1441235Y934325D02*
X1441007D01*
G01X1441235Y932127D02*
X1441007D01*
G01X1439047Y932106D02*
X1438785D01*
G01X1439047Y931197D02*
X1438785D01*
G01X1441235Y931176D02*
X1441007D01*
G01X1441235Y928978D02*
X1441007D01*
G01X1439047Y928956D02*
X1438785D01*
G01X1439047Y928048D02*
X1438785D01*
G01X1441235Y928026D02*
X1441007D01*
G01X1441235Y925828D02*
X1441007D01*
G01X1439047Y925806D02*
X1438785D01*
G01X1439047Y924898D02*
X1438785D01*
G01X1441235Y924877D02*
X1441007D01*
G01X1441235Y922678D02*
X1441007D01*
G01X1439047Y922657D02*
X1438785D01*
G01X1440094Y960464D02*
X1438785Y960452D01*
G01X1441235Y960474D02*
X1440094Y960464D01*
G01Y957314D02*
X1438785Y957302D01*
G01X1441235Y957324D02*
X1440094Y957314D01*
G01Y954164D02*
X1438785Y954153D01*
G01X1441235Y954174D02*
X1440094Y954164D01*
G01Y951015D02*
X1438785Y951003D01*
G01X1441235Y951025D02*
X1440094Y951015D01*
G01Y947865D02*
X1438785Y947854D01*
G01X1441235Y947875D02*
X1440094Y947865D01*
G01X1438785Y944704D02*
X1440094Y944716D01*
G01X1441235Y944726D02*
X1440094Y944716D01*
G01Y941566D02*
X1438785Y941554D01*
G01X1441235Y941576D02*
X1440094Y941566D01*
G01Y938416D02*
X1438785Y938405D01*
G01X1441235Y938426D02*
X1440094Y938416D01*
G01Y935267D02*
X1438785Y935255D01*
G01X1441235Y935277D02*
X1440094Y935267D01*
G01Y932117D02*
X1438785Y932106D01*
G01X1441235Y932127D02*
X1440094Y932117D01*
G01Y928968D02*
X1438785Y928956D01*
G01X1441235Y928978D02*
X1440094Y928968D01*
G01Y925818D02*
X1438785Y925806D01*
G01X1441235Y925828D02*
X1440094Y925818D01*
G01Y922668D02*
X1438785Y922657D01*
G01X1441235Y922678D02*
X1440094Y922668D01*
G01X1437751Y960438D02*
X1436420Y960426D01*
G01X1437751Y957288D02*
X1436420Y957276D01*
G01X1437751Y954139D02*
X1436420Y954127D01*
G01X1437751Y950989D02*
X1436420Y950977D01*
G01X1437751Y947839D02*
X1436420Y947828D01*
G01X1437751Y944690D02*
X1436420Y944678D01*
G01X1437751Y941540D02*
X1436420Y941528D01*
G01X1437751Y938391D02*
X1436420Y938379D01*
G01X1437751Y935241D02*
X1436420Y935229D01*
G01X1437751Y932091D02*
X1436420Y932079D01*
G01X1437751Y928942D02*
X1436420Y928930D01*
G01X1437751Y925792D02*
X1436420Y925780D01*
G01X1437751Y922642D02*
X1436420Y922631D01*
G01X1442543Y960490D02*
X1441007Y960474D01*
G01X1442543Y960490D02*
X1439047Y960452D01*
G01X1441235Y960474D02*
X1442772Y960490D01*
G01X1442543Y957340D02*
X1441007Y957324D01*
G01X1442543Y957340D02*
X1439047Y957302D01*
G01X1441235Y957324D02*
X1442772Y957340D01*
G01X1442543Y954191D02*
X1441007Y954174D01*
G01X1442543Y954191D02*
X1439047Y954153D01*
G01X1441235Y954174D02*
X1442772Y954191D01*
G01X1442543Y951041D02*
X1441007Y951025D01*
G01X1442543Y951041D02*
X1439047Y951003D01*
G01X1441235Y951025D02*
X1442772Y951041D01*
G01X1442543Y947892D02*
X1441007Y947875D01*
G01X1442543Y947892D02*
X1439047Y947854D01*
G01X1441235Y947875D02*
X1442772Y947892D01*
G01X1442543Y944742D02*
X1441007Y944726D01*
G01X1442543Y944742D02*
X1439047Y944704D01*
G01X1441235Y944726D02*
X1442772Y944742D01*
G01X1442543Y941592D02*
X1441007Y941576D01*
G01X1442543Y941592D02*
X1439047Y941554D01*
G01X1441235Y941576D02*
X1442772Y941592D01*
G01X1442543Y938443D02*
X1441007Y938426D01*
G01X1442543Y938443D02*
X1439047Y938405D01*
G01X1441235Y938426D02*
X1442772Y938443D01*
G01X1442543Y935293D02*
X1441007Y935277D01*
G01X1442543Y935293D02*
X1439047Y935255D01*
G01X1441235Y935277D02*
X1442772Y935293D01*
G01X1442543Y932144D02*
X1441007Y932127D01*
G01X1442543Y932144D02*
X1439047Y932106D01*
G01X1441235Y932127D02*
X1442772Y932144D01*
G01X1442543Y928994D02*
X1441007Y928978D01*
G01X1442543Y928994D02*
X1439047Y928956D01*
G01X1441235Y928978D02*
X1442772Y928994D01*
G01X1442543Y925844D02*
X1441007Y925828D01*
G01X1442543Y925844D02*
X1439047Y925806D01*
G01X1441235Y925828D02*
X1442772Y925844D01*
G01X1442543Y922695D02*
X1441007Y922678D01*
G01X1442543Y922695D02*
X1439047Y922657D01*
G01X1441235Y922678D02*
X1442772Y922695D01*
G01X1439047Y960452D02*
X1440094Y960464D01*
G01X1438785Y960452D02*
X1436420Y960426D01*
G01X1437751Y960438D02*
X1439047Y960452D01*
G01Y957302D02*
X1440094Y957314D01*
G01X1438785Y957302D02*
X1436420Y957276D01*
G01X1437751Y957288D02*
X1439047Y957302D01*
G01Y954153D02*
X1440094Y954164D01*
G01X1438785Y954153D02*
X1436420Y954127D01*
G01X1437751Y954139D02*
X1439047Y954153D01*
G01Y951003D02*
X1440094Y951015D01*
G01X1438785Y951003D02*
X1436420Y950977D01*
G01X1437751Y950989D02*
X1439047Y951003D01*
G01Y947854D02*
X1440094Y947865D01*
G01X1438785Y947854D02*
X1436420Y947828D01*
G01X1437751Y947839D02*
X1439047Y947854D01*
G01Y944704D02*
X1440094Y944716D01*
G01X1438785Y944704D02*
X1436420Y944678D01*
G01X1437751Y944690D02*
X1439047Y944704D01*
G01Y941554D02*
X1440094Y941566D01*
G01X1438785Y941554D02*
X1436420Y941528D01*
G01X1437751Y941540D02*
X1439047Y941554D01*
G01Y938405D02*
X1440094Y938416D01*
G01X1438785Y938405D02*
X1436420Y938379D01*
G01X1437751Y938391D02*
X1439047Y938405D01*
G01Y935255D02*
X1440094Y935267D01*
G01X1438785Y935255D02*
X1436420Y935229D01*
G01X1437751Y935241D02*
X1439047Y935255D01*
G01Y932106D02*
X1440094Y932117D01*
G01X1438785Y932106D02*
X1436420Y932079D01*
G01X1437751Y932091D02*
X1439047Y932106D01*
G01Y928956D02*
X1440094Y928968D01*
G01X1438785Y928956D02*
X1436420Y928930D01*
G01X1437751Y928942D02*
X1439047Y928956D01*
G01Y925806D02*
X1440094Y925818D01*
G01X1438785Y925806D02*
X1436420Y925780D01*
G01X1437751Y925792D02*
X1439047Y925806D01*
G01Y922657D02*
X1440094Y922668D01*
G01X1438785Y922657D02*
X1436420Y922631D01*
G01X1437751Y922642D02*
X1439047Y922657D01*
G01X1441235Y928977D02*
Y928026D01*
G01Y925828D02*
Y924877D01*
G01Y932127D02*
Y931176D01*
G01Y938426D02*
Y937475D01*
G01Y935277D02*
Y934325D01*
G01Y941576D02*
Y940625D01*
G01Y947875D02*
Y946924D01*
G01Y944726D02*
Y943774D01*
G01Y951025D02*
Y950073D01*
G01Y957324D02*
Y956373D01*
G01Y954174D02*
Y953223D01*
G01Y960474D02*
Y959522D01*
G01Y966773D02*
Y965821D01*
G01Y963623D02*
Y962672D01*
G01Y969922D02*
Y968971D01*
G01Y976222D02*
Y975270D01*
G01Y973072D02*
Y972121D01*
G01Y979371D02*
Y978420D01*
G01Y985670D02*
Y984719D01*
G01Y982521D02*
Y981570D01*
G01Y988820D02*
Y987869D01*
G01Y991970D02*
Y991018D01*
G01X1441007Y928978D02*
Y928026D01*
G01Y925828D02*
Y924877D01*
G01Y932127D02*
Y931176D01*
G01Y938426D02*
Y937475D01*
G01Y935277D02*
Y934325D01*
G01Y941576D02*
Y940625D01*
G01Y947875D02*
Y946924D01*
G01Y944726D02*
Y943774D01*
G01Y951025D02*
Y950073D01*
G01Y957324D02*
Y956373D01*
G01Y954174D02*
Y953223D01*
G01Y960474D02*
Y959522D01*
G01Y966773D02*
Y965821D01*
G01Y963623D02*
Y962672D01*
G01Y969922D02*
Y968971D01*
G01Y976222D02*
Y975270D01*
G01Y973072D02*
Y972121D01*
G01Y979371D02*
Y978420D01*
G01Y985670D02*
Y984719D01*
G01Y982521D02*
Y981570D01*
G01Y988820D02*
Y987869D01*
G01Y991970D02*
Y991018D01*
G01X1439047Y928956D02*
Y928048D01*
G01Y925806D02*
Y924898D01*
G01Y932106D02*
Y931197D01*
G01Y938405D02*
Y937497D01*
G01Y935255D02*
Y934347D01*
G01Y941554D02*
Y940646D01*
G01Y947854D02*
Y946945D01*
G01Y944704D02*
Y943796D01*
G01Y951003D02*
Y950095D01*
G01Y957302D02*
Y956394D01*
G01Y954153D02*
Y953245D01*
G01Y960452D02*
Y959544D01*
G01Y966751D02*
Y965843D01*
G01Y963602D02*
Y962693D01*
G01Y969901D02*
Y968993D01*
G01Y976200D02*
Y975292D01*
G01Y973051D02*
Y972142D01*
G01Y979350D02*
Y978441D01*
G01Y985649D02*
Y984741D01*
G01Y982499D02*
Y981591D01*
G01Y988799D02*
Y987890D01*
G01Y991948D02*
Y991040D01*
G01X1438785Y928956D02*
Y928048D01*
G01Y925806D02*
Y924898D01*
G01Y932106D02*
Y931197D01*
G01Y938405D02*
Y937497D01*
G01Y935255D02*
Y934347D01*
G01Y941554D02*
Y940646D01*
G01Y947854D02*
Y946945D01*
G01Y944704D02*
Y943796D01*
G01Y951003D02*
Y950095D01*
G01Y957302D02*
Y956394D01*
G01Y954153D02*
Y953245D01*
G01Y960452D02*
Y959544D01*
G01Y966751D02*
Y965843D01*
G01Y963602D02*
Y962693D01*
G01Y969901D02*
Y968993D01*
G01Y976200D02*
Y975292D01*
G01Y973051D02*
Y972142D01*
G01Y979350D02*
Y978441D01*
G01Y985649D02*
Y984741D01*
G01Y982499D02*
Y981591D01*
G01Y988799D02*
Y987890D01*
G01Y991948D02*
Y991040D01*
G01X1437751Y928936D02*
Y928068D01*
G01Y925786D02*
Y924918D01*
G01Y932085D02*
Y931218D01*
G01Y938385D02*
Y937517D01*
G01Y935235D02*
Y934367D01*
G01Y941534D02*
Y940666D01*
G01Y947833D02*
Y946966D01*
G01Y944684D02*
Y943816D01*
G01Y950983D02*
Y950115D01*
G01Y957282D02*
Y956414D01*
G01Y954133D02*
Y953265D01*
G01Y960432D02*
Y959564D01*
G01Y966731D02*
Y965863D01*
G01Y963581D02*
Y962714D01*
G01Y969881D02*
Y969013D01*
G01Y976180D02*
Y975312D01*
G01Y973030D02*
Y972162D01*
G01Y979329D02*
Y978462D01*
G01Y985629D02*
Y984761D01*
G01Y982479D02*
Y981611D01*
G01Y988778D02*
Y987910D01*
G01Y991928D02*
Y991060D01*
G01X1436420Y928930D02*
Y928074D01*
G01Y925780D02*
Y924924D01*
G01Y932079D02*
Y931223D01*
G01Y938379D02*
Y937523D01*
G01Y935229D02*
Y934373D01*
G01Y941528D02*
Y940672D01*
G01Y947828D02*
Y946971D01*
G01Y944678D02*
Y943822D01*
G01Y950977D02*
Y950121D01*
G01Y957276D02*
Y956420D01*
G01Y954127D02*
Y953271D01*
G01Y960426D02*
Y959570D01*
G01Y966725D02*
Y965869D01*
G01Y963576D02*
Y962720D01*
G01Y969875D02*
Y969019D01*
G01Y976174D02*
Y975318D01*
G01Y973024D02*
Y972168D01*
G01Y979324D02*
Y978468D01*
G01Y985623D02*
Y984767D01*
G01Y982473D02*
Y981617D01*
G01Y988772D02*
Y987916D01*
G01Y991922D02*
Y991066D01*
G01X1469507Y921868D02*
X1469278Y921612D01*
G01X1469855Y921868D02*
X1469636Y921598D01*
G01X1470921Y921868D02*
X1469507D01*
G01X1442772Y921711D02*
X1442543D01*
G01X1469631Y921612D02*
X1457535D01*
G01X1444212Y921415D02*
X1443073D01*
G01X1457732Y921022D02*
X1457220D01*
G01X1470921Y922537D02*
Y921868D01*
G01X1470574Y922537D02*
Y921868D01*
G01X1469631Y922793D02*
Y921612D01*
G01X1469278Y922793D02*
Y921612D01*
G01X1467296Y922793D02*
Y921612D01*
G01X1467186Y922793D02*
Y921612D01*
G01X1458405Y922793D02*
Y921612D01*
G01X1458295Y922793D02*
Y921612D01*
G01X1457929Y922793D02*
Y921612D01*
G01X1457732D02*
Y921022D01*
G01X1457535Y921612D02*
Y921022D01*
G01X1444212Y922990D02*
Y921415D01*
G01X1442684Y922783D02*
Y921623D01*
G01X1442772Y921711D02*
X1443243Y921415D01*
G01X1442543Y921711D02*
X1442684Y921623D01*
G01D02*
X1443073Y921415D01*
G01Y922990D02*
X1442684Y922783D01*
G01X1443073Y926140D02*
X1442684Y925932D01*
G01X1443073Y929289D02*
X1442684Y929082D01*
G01X1443073Y932439D02*
X1442684Y932231D01*
G01X1443073Y935588D02*
X1442684Y935381D01*
G01X1443073Y938738D02*
X1442684Y938531D01*
G01X1443073Y941888D02*
X1442684Y941680D01*
G01X1443073Y945037D02*
X1442684Y944830D01*
G01X1443073Y948187D02*
X1442684Y947979D01*
G01X1443073Y951337D02*
X1442684Y951129D01*
G01X1443073Y954486D02*
X1442684Y954279D01*
G01X1443073Y957636D02*
X1442684Y957428D01*
G01X1443073Y960785D02*
X1442684Y960578D01*
G01X1443073Y963935D02*
X1442684Y963727D01*
G01X1443073Y967085D02*
X1442684Y966877D01*
G01X1443073Y970234D02*
X1442684Y970027D01*
G01X1443243Y922990D02*
X1442772Y922695D01*
G01X1442684Y922783D02*
X1442543Y922695D01*
G01X1443073Y973384D02*
X1442684Y973176D01*
G01X1443073Y976533D02*
X1442684Y976326D01*
G01X1443073Y979683D02*
X1442684Y979476D01*
G01X1443073Y982833D02*
X1442684Y982625D01*
G01X1443073Y985982D02*
X1442684Y985775D01*
G01X1443073Y989132D02*
X1442684Y988924D01*
G01X1443073Y992281D02*
X1442684Y992074D01*
G01X1443243Y926140D02*
X1442772Y925844D01*
G01X1442684Y925932D02*
X1442543Y925844D01*
G01X1443243Y929289D02*
X1442772Y928994D01*
G01X1442684Y929082D02*
X1442543Y928994D01*
G01X1443243Y932439D02*
X1442772Y932144D01*
G01X1442684Y932231D02*
X1442543Y932144D01*
G01X1443243Y935588D02*
X1442772Y935293D01*
G01X1442684Y935381D02*
X1442543Y935293D01*
G01X1443243Y938738D02*
X1442772Y938443D01*
G01X1442684Y938531D02*
X1442543Y938443D01*
G01X1443243Y941888D02*
X1442772Y941592D01*
G01X1442684Y941680D02*
X1442543Y941592D01*
G01X1443243Y945037D02*
X1442772Y944742D01*
G01X1442684Y944830D02*
X1442543Y944742D01*
G01X1443243Y948187D02*
X1442772Y947892D01*
G01X1442684Y947979D02*
X1442543Y947892D01*
G01X1443243Y951337D02*
X1442772Y951041D01*
G01X1442684Y951129D02*
X1442543Y951041D01*
G01X1443243Y954486D02*
X1442772Y954191D01*
G01X1442684Y954279D02*
X1442543Y954191D01*
G01X1443243Y957636D02*
X1442772Y957340D01*
G01X1442684Y957428D02*
X1442543Y957340D01*
G01X1443243Y960785D02*
X1442772Y960490D01*
G01X1442684Y960578D02*
X1442543Y960490D01*
G01X1443243Y963935D02*
X1442772Y963640D01*
G01X1442684Y963727D02*
X1442543Y963640D01*
G01X1443243Y967085D02*
X1442772Y966789D01*
G01X1442684Y966877D02*
X1442543Y966789D01*
G01X1443243Y970234D02*
X1442772Y969939D01*
G01X1442684Y970027D02*
X1442543Y969939D01*
G01X1443243Y973384D02*
X1442772Y973088D01*
G01X1442684Y973176D02*
X1442543Y973088D01*
G01X1443243Y976533D02*
X1442772Y976238D01*
G01X1442684Y976326D02*
X1442543Y976238D01*
G01X1443243Y979683D02*
X1442772Y979388D01*
G01X1442684Y979476D02*
X1442543Y979388D01*
G01X1443243Y982833D02*
X1442772Y982537D01*
G01X1442684Y982625D02*
X1442543Y982537D01*
G01X1443243Y985982D02*
X1442772Y985687D01*
G01X1442684Y985775D02*
X1442543Y985687D01*
G01X1443243Y989132D02*
X1442772Y988837D01*
G01X1442684Y988924D02*
X1442543Y988837D01*
G01X1443243Y992281D02*
X1442772Y991986D01*
G01X1442684Y992074D02*
X1442543Y991986D01*
G01X1469507Y925018D02*
X1469278Y924762D01*
G01X1469507Y928167D02*
X1469278Y927911D01*
G01X1469507Y931317D02*
X1469278Y931061D01*
G01X1469507Y934466D02*
X1469278Y934211D01*
G01X1469507Y937616D02*
X1469278Y937360D01*
G01X1469507Y940766D02*
X1469278Y940510D01*
G01X1469507Y943915D02*
X1469278Y943659D01*
G01X1469507Y947065D02*
X1469278Y946809D01*
G01X1469507Y950214D02*
X1469278Y949959D01*
G01X1469507Y953364D02*
X1469278Y953108D01*
G01X1469507Y956514D02*
X1469278Y956258D01*
G01X1469507Y959663D02*
X1469278Y959407D01*
G01X1469507Y962813D02*
X1469278Y962557D01*
G01X1469507Y965963D02*
X1469278Y965707D01*
G01X1469507Y969112D02*
X1469278Y968856D01*
G01X1469507Y972262D02*
X1469278Y972006D01*
G01X1469507Y975411D02*
X1469278Y975155D01*
G01X1469507Y978561D02*
X1469278Y978305D01*
G01X1469507Y981711D02*
X1469278Y981455D01*
G01X1469507Y984860D02*
X1469278Y984604D01*
G01X1469507Y988010D02*
X1469278Y987754D01*
G01X1469507Y991159D02*
X1469278Y990903D01*
G01X1469855Y925018D02*
X1469636Y924748D01*
G01X1469855Y928167D02*
X1469636Y927897D01*
G01X1469855Y931317D02*
X1469636Y931047D01*
G01X1469855Y934466D02*
X1469636Y934196D01*
G01X1469855Y937616D02*
X1469636Y937346D01*
G01X1469855Y940766D02*
X1469636Y940496D01*
G01X1469855Y943915D02*
X1469636Y943645D01*
G01X1469855Y947065D02*
X1469636Y946795D01*
G01X1469855Y950214D02*
X1469636Y949944D01*
G01X1469855Y953364D02*
X1469636Y953094D01*
G01X1469855Y956514D02*
X1469636Y956244D01*
G01X1469855Y959663D02*
X1469636Y959393D01*
G01X1469855Y962813D02*
X1469636Y962543D01*
G01X1469855Y965963D02*
X1469636Y965692D01*
G01X1469855Y969112D02*
X1469636Y968842D01*
G01X1469855Y972262D02*
X1469636Y971992D01*
G01X1469855Y975411D02*
X1469636Y975141D01*
G01X1469855Y978561D02*
X1469636Y978291D01*
G01X1469855Y981711D02*
X1469636Y981441D01*
G01X1469855Y984860D02*
X1469636Y984590D01*
G01X1469855Y988010D02*
X1469636Y987740D01*
G01X1469855Y991159D02*
X1469636Y990889D01*
G01X1457732Y992675D02*
X1457220D01*
G01X1444212Y992281D02*
X1443073D01*
G01X1469631Y992085D02*
X1457535D01*
G01X1442772Y991986D02*
X1442543D01*
G01X1470921Y991829D02*
X1469507D01*
G01X1470921Y991159D02*
X1469507D01*
G01X1442772Y991002D02*
X1442543D01*
G01X1469631Y990903D02*
X1457535D01*
G01X1444212Y990707D02*
X1443073D01*
G01X1457732Y990313D02*
X1457220D01*
G01X1457732Y989525D02*
X1457220D01*
G01X1444212Y989132D02*
X1443073D01*
G01X1469631Y988935D02*
X1457535D01*
G01X1442772Y988837D02*
X1442543D01*
G01X1470921Y988679D02*
X1469507D01*
G01X1470921Y988010D02*
X1469507D01*
G01X1442772Y987852D02*
X1442543D01*
G01X1469631Y987754D02*
X1457535D01*
G01X1444212Y987557D02*
X1443073D01*
G01X1457732Y987163D02*
X1457220D01*
G01X1457732Y986376D02*
X1457220D01*
G01X1444212Y985982D02*
X1443073D01*
G01X1469631Y985785D02*
X1457535D01*
G01X1442772Y985687D02*
X1442543D01*
G01X1470921Y985529D02*
X1469507D01*
G01X1470921Y984860D02*
X1469507D01*
G01X1442772Y984703D02*
X1442543D01*
G01X1469631Y984604D02*
X1457535D01*
G01X1444212Y984407D02*
X1443073D01*
G01X1457732Y984014D02*
X1457220D01*
G01X1457732Y983226D02*
X1457220D01*
G01X1444212Y982833D02*
X1443073D01*
G01X1469631Y982636D02*
X1457535D01*
G01X1442772Y982537D02*
X1442543D01*
G01X1470921Y982380D02*
X1469507D01*
G01X1470921Y981711D02*
X1469507D01*
G01X1442772Y981553D02*
X1442543D01*
G01X1469631Y981455D02*
X1457535D01*
G01X1444212Y981258D02*
X1443073D01*
G01X1457732Y980864D02*
X1457220D01*
G01X1457732Y980077D02*
X1457220D01*
G01X1444212Y979683D02*
X1443073D01*
G01X1469631Y979486D02*
X1457535D01*
G01X1442772Y979388D02*
X1442543D01*
G01X1470921Y979230D02*
X1469507D01*
G01X1470921Y978561D02*
X1469507D01*
G01X1442772Y978403D02*
X1442543D01*
G01X1469631Y978305D02*
X1457535D01*
G01X1444212Y978108D02*
X1443073D01*
G01X1457732Y977714D02*
X1457220D01*
G01X1457732Y976927D02*
X1457220D01*
G01X1444212Y976533D02*
X1443073D01*
G01X1469631Y976337D02*
X1457535D01*
G01X1442772Y976238D02*
X1442543D01*
G01X1470921Y976081D02*
X1469507D01*
G01X1470921Y975411D02*
X1469507D01*
G01X1442772Y975254D02*
X1442543D01*
G01X1469631Y975155D02*
X1457535D01*
G01X1444212Y974959D02*
X1443073D01*
G01X1457732Y974565D02*
X1457220D01*
G01X1457732Y973777D02*
X1457220D01*
G01X1444212Y973384D02*
X1443073D01*
G01X1469631Y973187D02*
X1457535D01*
G01X1442772Y973088D02*
X1442543D01*
G01X1470921Y972931D02*
X1469507D01*
G01X1470921Y972262D02*
X1469507D01*
G01X1442772Y972104D02*
X1442543D01*
G01X1469631Y972006D02*
X1457535D01*
G01X1444212Y971809D02*
X1443073D01*
G01X1457732Y971415D02*
X1457220D01*
G01X1457732Y970628D02*
X1457220D01*
G01X1444212Y970234D02*
X1443073D01*
G01X1469631Y970037D02*
X1457535D01*
G01X1442772Y969939D02*
X1442543D01*
G01X1470921Y969781D02*
X1469507D01*
G01X1470921Y969112D02*
X1469507D01*
G01X1442772Y968955D02*
X1442543D01*
G01X1469631Y968856D02*
X1457535D01*
G01X1444212Y968659D02*
X1443073D01*
G01X1457732Y968266D02*
X1457220D01*
G01X1457732Y967478D02*
X1457220D01*
G01X1444212Y967085D02*
X1443073D01*
G01X1469631Y966888D02*
X1457535D01*
G01X1442772Y966789D02*
X1442543D01*
G01X1470921Y966632D02*
X1469507D01*
G01X1470921Y965963D02*
X1469507D01*
G01X1442772Y965805D02*
X1442543D01*
G01X1469631Y965707D02*
X1457535D01*
G01X1444212Y965510D02*
X1443073D01*
G01X1457732Y965116D02*
X1457220D01*
G01X1457732Y964329D02*
X1457220D01*
G01X1444212Y963935D02*
X1443073D01*
G01X1469631Y963738D02*
X1457535D01*
G01X1442772Y963640D02*
X1442543D01*
G01X1470921Y963482D02*
X1469507D01*
G01X1470921Y962813D02*
X1469507D01*
G01X1442772Y962655D02*
X1442543D01*
G01X1469631Y962557D02*
X1457535D01*
G01X1444212Y962360D02*
X1443073D01*
G01X1457732Y961966D02*
X1457220D01*
G01X1457732Y961179D02*
X1457220D01*
G01X1444212Y960785D02*
X1443073D01*
G01X1469631Y960588D02*
X1457535D01*
G01X1442772Y960490D02*
X1442543D01*
G01X1470921Y960333D02*
X1469507D01*
G01X1470921Y959663D02*
X1469507D01*
G01X1442772Y959506D02*
X1442543D01*
G01X1469631Y959407D02*
X1457535D01*
G01X1444212Y959211D02*
X1443073D01*
G01X1457732Y958817D02*
X1457220D01*
G01X1457732Y958029D02*
X1457220D01*
G01X1444212Y957636D02*
X1443073D01*
G01X1469631Y957439D02*
X1457535D01*
G01X1442772Y957340D02*
X1442543D01*
G01X1470921Y957183D02*
X1469507D01*
G01X1470921Y956514D02*
X1469507D01*
G01X1442772Y956356D02*
X1442543D01*
G01X1469631Y956258D02*
X1457535D01*
G01X1444212Y956061D02*
X1443073D01*
G01X1457732Y955667D02*
X1457220D01*
G01X1457732Y954880D02*
X1457220D01*
G01X1444212Y954486D02*
X1443073D01*
G01X1469631Y954289D02*
X1457535D01*
G01X1442772Y954191D02*
X1442543D01*
G01X1470921Y954033D02*
X1469507D01*
G01X1470921Y953364D02*
X1469507D01*
G01X1442772Y953207D02*
X1442543D01*
G01X1469631Y953108D02*
X1457535D01*
G01X1444212Y952911D02*
X1443073D01*
G01X1457732Y952518D02*
X1457220D01*
G01X1457732Y951730D02*
X1457220D01*
G01X1444212Y951337D02*
X1443073D01*
G01X1469631Y951140D02*
X1457535D01*
G01X1442772Y951041D02*
X1442543D01*
G01X1470921Y950884D02*
X1469507D01*
G01X1470921Y950214D02*
X1469507D01*
G01X1442772Y950057D02*
X1442543D01*
G01X1469631Y949959D02*
X1457535D01*
G01X1444212Y949762D02*
X1443073D01*
G01X1457732Y949368D02*
X1457220D01*
G01X1457732Y948581D02*
X1457220D01*
G01X1444212Y948187D02*
X1443073D01*
G01X1469631Y947990D02*
X1457535D01*
G01X1442772Y947892D02*
X1442543D01*
G01X1470921Y947734D02*
X1469507D01*
G01X1470921Y947065D02*
X1469507D01*
G01X1442772Y946907D02*
X1442543D01*
G01X1469631Y946809D02*
X1457535D01*
G01X1444212Y946612D02*
X1443073D01*
G01X1457732Y946218D02*
X1457220D01*
G01X1457732Y945431D02*
X1457220D01*
G01X1444212Y945037D02*
X1443073D01*
G01X1469631Y944840D02*
X1457535D01*
G01X1442772Y944742D02*
X1442543D01*
G01X1470921Y944585D02*
X1469507D01*
G01X1470921Y943915D02*
X1469507D01*
G01X1442772Y943758D02*
X1442543D01*
G01X1469631Y943659D02*
X1457535D01*
G01X1444212Y943463D02*
X1443073D01*
G01X1457732Y943069D02*
X1457220D01*
G01X1457732Y942281D02*
X1457220D01*
G01X1444212Y941888D02*
X1443073D01*
G01X1469631Y941691D02*
X1457535D01*
G01X1442772Y941592D02*
X1442543D01*
G01X1470921Y941435D02*
X1469507D01*
G01X1470921Y940766D02*
X1469507D01*
G01X1442772Y940608D02*
X1442543D01*
G01X1469631Y940510D02*
X1457535D01*
G01X1444212Y940313D02*
X1443073D01*
G01X1457732Y939919D02*
X1457220D01*
G01X1457732Y939132D02*
X1457220D01*
G01X1444212Y938738D02*
X1443073D01*
G01X1469631Y938541D02*
X1457535D01*
G01X1442772Y938443D02*
X1442543D01*
G01X1470921Y938285D02*
X1469507D01*
G01X1470921Y937616D02*
X1469507D01*
G01X1442772Y937459D02*
X1442543D01*
G01X1469631Y937360D02*
X1457535D01*
G01X1444212Y937163D02*
X1443073D01*
G01X1457732Y936770D02*
X1457220D01*
G01X1457732Y935982D02*
X1457220D01*
G01X1444212Y935588D02*
X1443073D01*
G01X1469631Y935392D02*
X1457535D01*
G01X1442772Y935293D02*
X1442543D01*
G01X1470921Y935136D02*
X1469507D01*
G01X1470921Y934466D02*
X1469507D01*
G01X1442772Y934309D02*
X1442543D01*
G01X1469631Y934211D02*
X1457535D01*
G01X1444212Y934014D02*
X1443073D01*
G01X1457732Y933620D02*
X1457220D01*
G01X1457732Y932833D02*
X1457220D01*
G01X1444212Y932439D02*
X1443073D01*
G01X1469631Y932242D02*
X1457535D01*
G01X1442772Y932144D02*
X1442543D01*
G01X1470921Y931986D02*
X1469507D01*
G01X1470921Y931317D02*
X1469507D01*
G01X1442772Y931159D02*
X1442543D01*
G01X1469631Y931061D02*
X1457535D01*
G01X1444212Y930864D02*
X1443073D01*
G01X1457732Y930470D02*
X1457220D01*
G01X1457732Y929683D02*
X1457220D01*
G01X1444212Y929289D02*
X1443073D01*
G01X1469631Y929092D02*
X1457535D01*
G01X1442772Y928994D02*
X1442543D01*
G01X1470921Y928837D02*
X1469507D01*
G01X1470921Y928167D02*
X1469507D01*
G01X1442772Y928010D02*
X1442543D01*
G01X1469631Y927911D02*
X1457535D01*
G01X1444212Y927714D02*
X1443073D01*
G01X1457732Y927321D02*
X1457220D01*
G01X1457732Y926533D02*
X1457220D01*
G01X1444212Y926140D02*
X1443073D01*
G01X1469631Y925943D02*
X1457535D01*
G01X1442772Y925844D02*
X1442543D01*
G01X1470921Y925687D02*
X1469507D01*
G01X1470921Y925018D02*
X1469507D01*
G01X1442772Y924860D02*
X1442543D01*
G01X1469631Y924762D02*
X1457535D01*
G01X1444212Y924565D02*
X1443073D01*
G01X1457732Y924171D02*
X1457220D01*
G01X1457732Y923384D02*
X1457220D01*
G01X1444212Y922990D02*
X1443073D01*
G01X1469631Y922793D02*
X1457535D01*
G01X1442772Y922695D02*
X1442543D01*
G01X1470921Y922537D02*
X1469507D01*
G01X1442772Y991002D02*
X1443243Y990707D01*
G01X1442543Y991002D02*
X1442684Y990914D01*
G01X1442772Y987852D02*
X1443243Y987557D01*
G01X1442543Y987852D02*
X1442684Y987764D01*
G01X1442772Y984703D02*
X1443243Y984407D01*
G01X1442543Y984703D02*
X1442684Y984615D01*
G01X1442772Y981553D02*
X1443243Y981258D01*
G01X1442543Y981553D02*
X1442684Y981465D01*
G01X1442772Y978403D02*
X1443243Y978108D01*
G01X1442543Y978403D02*
X1442684Y978316D01*
G01X1442772Y975254D02*
X1443243Y974959D01*
G01X1442543Y975254D02*
X1442684Y975166D01*
G01X1442772Y972104D02*
X1443243Y971809D01*
G01X1442543Y972104D02*
X1442684Y972016D01*
G01Y990914D02*
X1443073Y990707D01*
G01X1442684Y987764D02*
X1443073Y987557D01*
G01X1442684Y984615D02*
X1443073Y984407D01*
G01X1442684Y981465D02*
X1443073Y981258D01*
G01X1442684Y978316D02*
X1443073Y978108D01*
G01X1442684Y975166D02*
X1443073Y974959D01*
G01X1442684Y972016D02*
X1443073Y971809D01*
G01X1442684Y968867D02*
X1443073Y968659D01*
G01X1442684Y965717D02*
X1443073Y965510D01*
G01X1442684Y962568D02*
X1443073Y962360D01*
G01X1442684Y959418D02*
X1443073Y959211D01*
G01X1442684Y956268D02*
X1443073Y956061D01*
G01X1442684Y953119D02*
X1443073Y952911D01*
G01X1442684Y949969D02*
X1443073Y949762D01*
G01X1442684Y946820D02*
X1443073Y946612D01*
G01X1470921Y928837D02*
Y928167D01*
G01Y925687D02*
Y925018D01*
G01Y931986D02*
Y931317D01*
G01Y938285D02*
Y937616D01*
G01Y935136D02*
Y934466D01*
G01Y941435D02*
Y940766D01*
G01Y947734D02*
Y947065D01*
G01Y944585D02*
Y943915D01*
G01Y950884D02*
Y950214D01*
G01Y957183D02*
Y956514D01*
G01Y954033D02*
Y953364D01*
G01Y960333D02*
Y959663D01*
G01Y966632D02*
Y965963D01*
G01Y963482D02*
Y962813D01*
G01Y969781D02*
Y969112D01*
G01Y976081D02*
Y975411D01*
G01Y972931D02*
Y972262D01*
G01Y979230D02*
Y978561D01*
G01Y985529D02*
Y984860D01*
G01Y982380D02*
Y981711D01*
G01Y988679D02*
Y988010D01*
G01Y991829D02*
Y991159D01*
G01X1470574Y928837D02*
Y928167D01*
G01Y925687D02*
Y925018D01*
G01Y931986D02*
Y931317D01*
G01Y938285D02*
Y937616D01*
G01Y935136D02*
Y934466D01*
G01Y941435D02*
Y940766D01*
G01Y947734D02*
Y947065D01*
G01Y944585D02*
Y943915D01*
G01Y950884D02*
Y950214D01*
G01Y957183D02*
Y956514D01*
G01Y954033D02*
Y953364D01*
G01Y960333D02*
Y959663D01*
G01Y966632D02*
Y965963D01*
G01Y963482D02*
Y962813D01*
G01Y969781D02*
Y969112D01*
G01Y976081D02*
Y975411D01*
G01Y972931D02*
Y972262D01*
G01Y979230D02*
Y978561D01*
G01Y985529D02*
Y984860D01*
G01Y982380D02*
Y981711D01*
G01Y988679D02*
Y988010D01*
G01Y991829D02*
Y991159D01*
G01X1469631Y929092D02*
Y927911D01*
G01Y925943D02*
Y924762D01*
G01Y932242D02*
Y931061D01*
G01Y938541D02*
Y937360D01*
G01Y935392D02*
Y934211D01*
G01Y941691D02*
Y940510D01*
G01Y947990D02*
Y946809D01*
G01Y944840D02*
Y943659D01*
G01Y951140D02*
Y949959D01*
G01Y957439D02*
Y956258D01*
G01Y954289D02*
Y953108D01*
G01Y960588D02*
Y959407D01*
G01Y966888D02*
Y965707D01*
G01Y963738D02*
Y962557D01*
G01Y970037D02*
Y968856D01*
G01Y976337D02*
Y975155D01*
G01Y973187D02*
Y972006D01*
G01Y979486D02*
Y978305D01*
G01Y985785D02*
Y984604D01*
G01Y982636D02*
Y981455D01*
G01Y988935D02*
Y987754D01*
G01Y992085D02*
Y990903D01*
G01X1469278Y929092D02*
Y927911D01*
G01Y925943D02*
Y924762D01*
G01Y932242D02*
Y931061D01*
G01Y938541D02*
Y937360D01*
G01Y935392D02*
Y934211D01*
G01Y941691D02*
Y940510D01*
G01Y947990D02*
Y946809D01*
G01Y944840D02*
Y943659D01*
G01Y951140D02*
Y949959D01*
G01Y957439D02*
Y956258D01*
G01Y954289D02*
Y953108D01*
G01Y960588D02*
Y959407D01*
G01Y966888D02*
Y965707D01*
G01Y963738D02*
Y962557D01*
G01Y970037D02*
Y968856D01*
G01Y976337D02*
Y975155D01*
G01Y973187D02*
Y972006D01*
G01Y979486D02*
Y978305D01*
G01Y985785D02*
Y984604D01*
G01Y982636D02*
Y981455D01*
G01Y988935D02*
Y987754D01*
G01Y992085D02*
Y990903D01*
G01X1467296Y929092D02*
Y927911D01*
G01Y925943D02*
Y924762D01*
G01Y932242D02*
Y931061D01*
G01Y938541D02*
Y937360D01*
G01Y935392D02*
Y934211D01*
G01Y941691D02*
Y940510D01*
G01Y947990D02*
Y946809D01*
G01Y944840D02*
Y943659D01*
G01Y951140D02*
Y949959D01*
G01Y957439D02*
Y956258D01*
G01Y954289D02*
Y953108D01*
G01Y960588D02*
Y959407D01*
G01Y966888D02*
Y965707D01*
G01Y963738D02*
Y962557D01*
G01Y970037D02*
Y968856D01*
G01Y976337D02*
Y975155D01*
G01Y973187D02*
Y972006D01*
G01Y979486D02*
Y978305D01*
G01Y985785D02*
Y984604D01*
G01Y982636D02*
Y981455D01*
G01Y988935D02*
Y987754D01*
G01Y992085D02*
Y990903D01*
G01X1467186Y929092D02*
Y927911D01*
G01Y925943D02*
Y924762D01*
G01Y932242D02*
Y931061D01*
G01Y938541D02*
Y937360D01*
G01Y935392D02*
Y934211D01*
G01Y941691D02*
Y940510D01*
G01Y947990D02*
Y946809D01*
G01Y944840D02*
Y943659D01*
G01Y951140D02*
Y949959D01*
G01Y957439D02*
Y956258D01*
G01Y954289D02*
Y953108D01*
G01Y960588D02*
Y959407D01*
G01Y966888D02*
Y965707D01*
G01Y963738D02*
Y962557D01*
G01Y970037D02*
Y968856D01*
G01Y976337D02*
Y975155D01*
G01Y973187D02*
Y972006D01*
G01Y979486D02*
Y978305D01*
G01Y985785D02*
Y984604D01*
G01Y982636D02*
Y981455D01*
G01Y988935D02*
Y987754D01*
G01Y992085D02*
Y990903D01*
G01X1458405Y929092D02*
Y927911D01*
G01Y925943D02*
Y924762D01*
G01Y932242D02*
Y931061D01*
G01Y938541D02*
Y937360D01*
G01Y935392D02*
Y934211D01*
G01Y941691D02*
Y940510D01*
G01Y947990D02*
Y946809D01*
G01Y944840D02*
Y943659D01*
G01Y951140D02*
Y949959D01*
G01Y957439D02*
Y956258D01*
G01Y954289D02*
Y953108D01*
G01Y960588D02*
Y959407D01*
G01Y966888D02*
Y965707D01*
G01Y963738D02*
Y962557D01*
G01Y970037D02*
Y968856D01*
G01Y976337D02*
Y975155D01*
G01Y973187D02*
Y972006D01*
G01Y979486D02*
Y978305D01*
G01Y985785D02*
Y984604D01*
G01Y982636D02*
Y981455D01*
G01Y988935D02*
Y987754D01*
G01Y992085D02*
Y990903D01*
G01X1458295Y929092D02*
Y927911D01*
G01Y925943D02*
Y924762D01*
G01Y932242D02*
Y931061D01*
G01Y938541D02*
Y937360D01*
G01Y935392D02*
Y934211D01*
G01Y941691D02*
Y940510D01*
G01Y947990D02*
Y946809D01*
G01Y944840D02*
Y943659D01*
G01Y951140D02*
Y949959D01*
G01Y957439D02*
Y956258D01*
G01Y954289D02*
Y953108D01*
G01Y960588D02*
Y959407D01*
G01Y966888D02*
Y965707D01*
G01Y963738D02*
Y962557D01*
G01Y970037D02*
Y968856D01*
G01Y976337D02*
Y975155D01*
G01Y973187D02*
Y972006D01*
G01Y979486D02*
Y978305D01*
G01Y985785D02*
Y984604D01*
G01Y982636D02*
Y981455D01*
G01Y988935D02*
Y987754D01*
G01Y992085D02*
Y990903D01*
G01X1457929Y929092D02*
Y927911D01*
G01Y925943D02*
Y924762D01*
G01Y932242D02*
Y931061D01*
G01Y938541D02*
Y937360D01*
G01Y935392D02*
Y934211D01*
G01Y941691D02*
Y940510D01*
G01Y947990D02*
Y946809D01*
G01Y944840D02*
Y943659D01*
G01Y951140D02*
Y949959D01*
G01Y957439D02*
Y956258D01*
G01Y954289D02*
Y953108D01*
G01Y960588D02*
Y959407D01*
G01Y966888D02*
Y965707D01*
G01Y963738D02*
Y962557D01*
G01Y970037D02*
Y968856D01*
G01Y976337D02*
Y975155D01*
G01Y973187D02*
Y972006D01*
G01Y979486D02*
Y978305D01*
G01Y985785D02*
Y984604D01*
G01Y982636D02*
Y981455D01*
G01Y988935D02*
Y987754D01*
G01Y992085D02*
Y990903D01*
G01X1457732Y924762D02*
Y924171D01*
G01Y923384D02*
Y922793D01*
G01Y927911D02*
Y927321D01*
G01Y929683D02*
Y929092D01*
G01Y926533D02*
Y925943D01*
G01Y934211D02*
Y933620D01*
G01Y931061D02*
Y930470D01*
G01Y932833D02*
Y932242D01*
G01Y937360D02*
Y936770D01*
G01Y939132D02*
Y938541D01*
G01Y935982D02*
Y935392D01*
G01Y943659D02*
Y943069D01*
G01Y940510D02*
Y939919D01*
G01Y942281D02*
Y941691D01*
G01Y946809D02*
Y946218D01*
G01Y948581D02*
Y947990D01*
G01Y945431D02*
Y944840D01*
G01Y953108D02*
Y952518D01*
G01Y949959D02*
Y949368D01*
G01Y951730D02*
Y951140D01*
G01Y956258D02*
Y955667D01*
G01Y958029D02*
Y957439D01*
G01Y954880D02*
Y954289D01*
G01Y962557D02*
Y961966D01*
G01Y959407D02*
Y958817D01*
G01Y961179D02*
Y960588D01*
G01Y965707D02*
Y965116D01*
G01Y967478D02*
Y966888D01*
G01Y964329D02*
Y963738D01*
G01Y972006D02*
Y971415D01*
G01Y968856D02*
Y968266D01*
G01Y970628D02*
Y970037D01*
G01Y975155D02*
Y974565D01*
G01Y976927D02*
Y976337D01*
G01Y973777D02*
Y973187D01*
G01Y981455D02*
Y980864D01*
G01Y978305D02*
Y977714D01*
G01Y980077D02*
Y979486D01*
G01Y984604D02*
Y984014D01*
G01Y986376D02*
Y985785D01*
G01Y983226D02*
Y982636D01*
G01Y990903D02*
Y990313D01*
G01Y987754D02*
Y987163D01*
G01Y989525D02*
Y988935D01*
G01Y992675D02*
Y992085D01*
G01X1457535Y924762D02*
Y924171D01*
G01Y923384D02*
Y922793D01*
G01Y927911D02*
Y927321D01*
G01Y929683D02*
Y929092D01*
G01Y926533D02*
Y925943D01*
G01Y934211D02*
Y933620D01*
G01Y931061D02*
Y930470D01*
G01Y932833D02*
Y932242D01*
G01Y937360D02*
Y936770D01*
G01Y939132D02*
Y938541D01*
G01Y935982D02*
Y935392D01*
G01Y943659D02*
Y943069D01*
G01Y940510D02*
Y939919D01*
G01Y942281D02*
Y941691D01*
G01Y946809D02*
Y946218D01*
G01Y948581D02*
Y947990D01*
G01Y945431D02*
Y944840D01*
G01Y953108D02*
Y952518D01*
G01Y949959D02*
Y949368D01*
G01Y951730D02*
Y951140D01*
G01Y956258D02*
Y955667D01*
G01Y958029D02*
Y957439D01*
G01Y954880D02*
Y954289D01*
G01Y962557D02*
Y961966D01*
G01Y959407D02*
Y958817D01*
G01Y961179D02*
Y960588D01*
G01Y965707D02*
Y965116D01*
G01Y967478D02*
Y966888D01*
G01Y964329D02*
Y963738D01*
G01Y972006D02*
Y971415D01*
G01Y968856D02*
Y968266D01*
G01Y970628D02*
Y970037D01*
G01Y975155D02*
Y974565D01*
G01Y976927D02*
Y976337D01*
G01Y973777D02*
Y973187D01*
G01Y981455D02*
Y980864D01*
G01Y978305D02*
Y977714D01*
G01Y980077D02*
Y979486D01*
G01Y984604D02*
Y984014D01*
G01Y986376D02*
Y985785D01*
G01Y983226D02*
Y982636D01*
G01Y990903D02*
Y990313D01*
G01Y987754D02*
Y987163D01*
G01Y989525D02*
Y988935D01*
G01Y992675D02*
Y992085D01*
G01X1444212Y929289D02*
Y927714D01*
G01Y926140D02*
Y924565D01*
G01Y932439D02*
Y930864D01*
G01Y938738D02*
Y937163D01*
G01Y935588D02*
Y934014D01*
G01Y941888D02*
Y940313D01*
G01Y948187D02*
Y946612D01*
G01Y945037D02*
Y943463D01*
G01Y951337D02*
Y949762D01*
G01Y957636D02*
Y956061D01*
G01Y954486D02*
Y952911D01*
G01Y960785D02*
Y959211D01*
G01Y967085D02*
Y965510D01*
G01Y963935D02*
Y962360D01*
G01Y970234D02*
Y968659D01*
G01Y976533D02*
Y974959D01*
G01Y973384D02*
Y971809D01*
G01Y979683D02*
Y978108D01*
G01Y985982D02*
Y984407D01*
G01Y982833D02*
Y981258D01*
G01Y989132D02*
Y987557D01*
G01Y992281D02*
Y990707D01*
G01X1442684Y929082D02*
Y927922D01*
G01Y925932D02*
Y924772D01*
G01Y932231D02*
Y931072D01*
G01Y938531D02*
Y937371D01*
G01Y935381D02*
Y934221D01*
G01Y941680D02*
Y940520D01*
G01Y947979D02*
Y946820D01*
G01Y944830D02*
Y943670D01*
G01Y951129D02*
Y949969D01*
G01Y957428D02*
Y956268D01*
G01Y954279D02*
Y953119D01*
G01Y960578D02*
Y959418D01*
G01Y966877D02*
Y965717D01*
G01Y963727D02*
Y962568D01*
G01Y970027D02*
Y968867D01*
G01Y976326D02*
Y975166D01*
G01Y973176D02*
Y972016D01*
G01Y979476D02*
Y978316D01*
G01Y985775D02*
Y984615D01*
G01Y982625D02*
Y981465D01*
G01Y988924D02*
Y987764D01*
G01Y992074D02*
Y990914D01*
G01X1469636Y992099D02*
X1469855Y991829D01*
G01X1469636Y988949D02*
X1469855Y988679D01*
G01X1469636Y985799D02*
X1469855Y985529D01*
G01X1469636Y982650D02*
X1469855Y982380D01*
G01X1469636Y979500D02*
X1469855Y979230D01*
G01X1469636Y976351D02*
X1469855Y976081D01*
G01X1469636Y973201D02*
X1469855Y972931D01*
G01X1469636Y970051D02*
X1469855Y969781D01*
G01X1469636Y966902D02*
X1469855Y966632D01*
G01X1469636Y963752D02*
X1469855Y963482D01*
G01X1469636Y960603D02*
X1469855Y960333D01*
G01X1469636Y957453D02*
X1469855Y957183D01*
G01X1469636Y954303D02*
X1469855Y954033D01*
G01X1469636Y951154D02*
X1469855Y950884D01*
G01X1469636Y948004D02*
X1469855Y947734D01*
G01X1469636Y944855D02*
X1469855Y944585D01*
G01X1469636Y941705D02*
X1469855Y941435D01*
G01X1469636Y938555D02*
X1469855Y938285D01*
G01X1469636Y935406D02*
X1469855Y935136D01*
G01X1469636Y932256D02*
X1469855Y931986D01*
G01X1469636Y929107D02*
X1469855Y928837D01*
G01X1469636Y925957D02*
X1469855Y925687D01*
G01X1469636Y922807D02*
X1469855Y922537D01*
G01X1469278Y992085D02*
X1469507Y991829D01*
G01X1469278Y988935D02*
X1469507Y988679D01*
G01X1469278Y985785D02*
X1469507Y985529D01*
G01X1469278Y982636D02*
X1469507Y982380D01*
G01X1469278Y979486D02*
X1469507Y979230D01*
G01X1469278Y976337D02*
X1469507Y976081D01*
G01X1469278Y973187D02*
X1469507Y972931D01*
G01X1469278Y970037D02*
X1469507Y969781D01*
G01X1469278Y966888D02*
X1469507Y966632D01*
G01X1469278Y963738D02*
X1469507Y963482D01*
G01X1469278Y960588D02*
X1469507Y960333D01*
G01X1469278Y957439D02*
X1469507Y957183D01*
G01X1469278Y954289D02*
X1469507Y954033D01*
G01X1469278Y951140D02*
X1469507Y950884D01*
G01X1469278Y947990D02*
X1469507Y947734D01*
G01X1469278Y944840D02*
X1469507Y944585D01*
G01X1469278Y941691D02*
X1469507Y941435D01*
G01X1469278Y938541D02*
X1469507Y938285D01*
G01X1469278Y935392D02*
X1469507Y935136D01*
G01X1469278Y932242D02*
X1469507Y931986D01*
G01X1469278Y929092D02*
X1469507Y928837D01*
G01X1469278Y925943D02*
X1469507Y925687D01*
G01X1469278Y922793D02*
X1469507Y922537D01*
G01X1442772Y968955D02*
X1443243Y968659D01*
G01X1442543Y968955D02*
X1442684Y968867D01*
G01X1442772Y965805D02*
X1443243Y965510D01*
G01X1442543Y965805D02*
X1442684Y965717D01*
G01X1442772Y962655D02*
X1443243Y962360D01*
G01X1442543Y962655D02*
X1442684Y962568D01*
G01X1442772Y959506D02*
X1443243Y959211D01*
G01X1442543Y959506D02*
X1442684Y959418D01*
G01X1442772Y956356D02*
X1443243Y956061D01*
G01X1442543Y956356D02*
X1442684Y956268D01*
G01X1442772Y953207D02*
X1443243Y952911D01*
G01X1442543Y953207D02*
X1442684Y953119D01*
G01X1442772Y950057D02*
X1443243Y949762D01*
G01X1442543Y950057D02*
X1442684Y949969D01*
G01X1442772Y946907D02*
X1443243Y946612D01*
G01X1442543Y946907D02*
X1442684Y946820D01*
G01X1442772Y943758D02*
X1443243Y943463D01*
G01X1442543Y943758D02*
X1442684Y943670D01*
G01X1442772Y940608D02*
X1443243Y940313D01*
G01X1442543Y940608D02*
X1442684Y940520D01*
G01X1442772Y937459D02*
X1443243Y937163D01*
G01X1442543Y937459D02*
X1442684Y937371D01*
G01X1442772Y934309D02*
X1443243Y934014D01*
G01X1442543Y934309D02*
X1442684Y934221D01*
G01X1442772Y931159D02*
X1443243Y930864D01*
G01X1442543Y931159D02*
X1442684Y931072D01*
G01X1442772Y928010D02*
X1443243Y927714D01*
G01X1442543Y928010D02*
X1442684Y927922D01*
G01X1442772Y924860D02*
X1443243Y924565D01*
G01X1442543Y924860D02*
X1442684Y924772D01*
G01Y943670D02*
X1443073Y943463D01*
G01X1442684Y940520D02*
X1443073Y940313D01*
G01X1442684Y937371D02*
X1443073Y937163D01*
G01X1442684Y934221D02*
X1443073Y934014D01*
G01X1442684Y931072D02*
X1443073Y930864D01*
G01X1442684Y927922D02*
X1443073Y927714D01*
G01X1442684Y924772D02*
X1443073Y924565D01*
G01X1439047Y1063481D02*
X1442543Y1063443D01*
G01X1437751Y1063495D02*
X1441007Y1063459D01*
G01X1439047Y1060331D02*
X1442543Y1060293D01*
G01X1437751Y1060346D02*
X1441007Y1060310D01*
G01X1439047Y1057182D02*
X1442543Y1057144D01*
G01X1437751Y1057196D02*
X1441007Y1057160D01*
G01X1438785Y1063481D02*
X1436420Y1063507D01*
G01X1438785Y1060331D02*
X1436420Y1060357D01*
G01X1438785Y1057182D02*
X1436420Y1057208D01*
G01X1441235Y1063459D02*
X1442772Y1063443D01*
G01X1441235Y1060310D02*
X1442772Y1060293D01*
G01X1441235Y1057160D02*
X1442772Y1057144D01*
G01X1441235Y1063459D02*
X1438785Y1063481D01*
G01X1437751Y1063495D02*
X1436420Y1063507D01*
G01X1441235Y1060310D02*
X1438785Y1060331D01*
G01X1437751Y1060346D02*
X1436420Y1060357D01*
G01X1441235Y1057160D02*
X1438785Y1057182D01*
G01X1437751Y1057196D02*
X1436420Y1057208D01*
G01X1441235Y1064411D02*
X1441007D01*
G01X1439047Y1064389D02*
X1438785D01*
G01X1439047Y1063481D02*
X1438785D01*
G01X1441235Y1063459D02*
X1441007D01*
G01X1441235Y1061261D02*
X1441007D01*
G01X1439047Y1061239D02*
X1438785D01*
G01X1439047Y1060331D02*
X1438785D01*
G01X1441235Y1060310D02*
X1441007D01*
G01X1441235Y1058111D02*
X1441007D01*
G01X1439047Y1058090D02*
X1438785D01*
G01X1439047Y1057182D02*
X1438785D01*
G01X1441235Y1057160D02*
X1441007D01*
G01X1441235Y1054962D02*
X1441007D01*
G01X1439047Y1054940D02*
X1438785D01*
G01X1440094Y1064401D02*
X1438785Y1064389D01*
G01X1441235Y1064411D02*
X1440094Y1064401D01*
G01Y1061251D02*
X1438785Y1061239D01*
G01X1441235Y1061261D02*
X1440094Y1061251D01*
G01Y1058101D02*
X1438785Y1058090D01*
G01X1441235Y1058111D02*
X1440094Y1058101D01*
G01Y1054952D02*
X1438785Y1054940D01*
G01X1441235Y1054962D02*
X1440094Y1054952D01*
G01X1437751Y1064375D02*
X1436420Y1064363D01*
G01X1437751Y1061225D02*
X1436420Y1061213D01*
G01X1437751Y1058076D02*
X1436420Y1058064D01*
G01X1437751Y1054926D02*
X1436420Y1054914D01*
G01X1442543Y1064427D02*
X1441007Y1064411D01*
G01X1442543Y1064427D02*
X1439047Y1064389D01*
G01X1441235Y1064411D02*
X1442772Y1064427D01*
G01X1442543Y1061277D02*
X1441007Y1061261D01*
G01X1442543Y1061277D02*
X1439047Y1061239D01*
G01X1441235Y1061261D02*
X1442772Y1061277D01*
G01X1442543Y1058128D02*
X1441007Y1058111D01*
G01X1442543Y1058128D02*
X1439047Y1058090D01*
G01X1441235Y1058111D02*
X1442772Y1058128D01*
G01X1442543Y1054978D02*
X1441007Y1054962D01*
G01X1442543Y1054978D02*
X1439047Y1054940D01*
G01X1441235Y1054962D02*
X1442772Y1054978D01*
G01X1439047Y1064389D02*
X1440094Y1064401D01*
G01X1438785Y1064389D02*
X1436420Y1064363D01*
G01X1437751Y1064375D02*
X1439047Y1064389D01*
G01Y1061239D02*
X1440094Y1061251D01*
G01X1438785Y1061239D02*
X1436420Y1061213D01*
G01X1437751Y1061225D02*
X1439047Y1061239D01*
G01Y1058090D02*
X1440094Y1058101D01*
G01X1438785Y1058090D02*
X1436420Y1058064D01*
G01X1437751Y1058076D02*
X1439047Y1058090D01*
G01Y1054940D02*
X1440094Y1054952D01*
G01X1438785Y1054940D02*
X1436420Y1054914D01*
G01X1437751Y1054926D02*
X1439047Y1054940D01*
G01X1441235Y1054962D02*
Y1054010D01*
G01Y1061261D02*
Y1060310D01*
G01Y1058111D02*
Y1057160D01*
G01Y1064411D02*
Y1063459D01*
G01X1441007Y1054962D02*
Y1054010D01*
G01Y1061261D02*
Y1060310D01*
G01Y1058111D02*
Y1057160D01*
G01Y1064411D02*
Y1063459D01*
G01X1439047Y1054940D02*
Y1054032D01*
G01Y1061239D02*
Y1060331D01*
G01Y1058090D02*
Y1057182D01*
G01Y1064389D02*
Y1063481D01*
G01X1438785Y1054940D02*
Y1054032D01*
G01Y1061239D02*
Y1060331D01*
G01Y1058090D02*
Y1057182D01*
G01Y1064389D02*
Y1063481D01*
G01X1437751Y1054920D02*
Y1054052D01*
G01Y1061219D02*
Y1060351D01*
G01Y1058070D02*
Y1057202D01*
G01Y1064369D02*
Y1063501D01*
G01X1436420Y1054914D02*
Y1054058D01*
G01Y1061213D02*
Y1060357D01*
G01Y1058064D02*
Y1057208D01*
G01Y1064363D02*
Y1063507D01*
G01X1430449Y1198187D02*
Y1019053D01*
G01X1443073Y1055274D02*
X1442684Y1055066D01*
G01X1443073Y1058423D02*
X1442684Y1058216D01*
G01X1443073Y1061573D02*
X1442684Y1061365D01*
G01X1443073Y1064722D02*
X1442684Y1064515D01*
G01X1443243Y1055274D02*
X1442772Y1054978D01*
G01X1442684Y1055066D02*
X1442543Y1054978D01*
G01X1443243Y1058423D02*
X1442772Y1058128D01*
G01X1442684Y1058216D02*
X1442543Y1058128D01*
G01X1443243Y1061573D02*
X1442772Y1061277D01*
G01X1442684Y1061365D02*
X1442543Y1061277D01*
G01X1443243Y1064722D02*
X1442772Y1064427D01*
G01X1442684Y1064515D02*
X1442543Y1064427D01*
G01X1457732Y1065903D02*
X1457220D01*
G01X1457732Y1065116D02*
X1457220D01*
G01X1444212Y1064722D02*
X1443073D01*
G01X1469631Y1064525D02*
X1457535D01*
G01X1442772Y1064427D02*
X1442543D01*
G01X1470921Y1064270D02*
X1469507D01*
G01X1470921Y1063600D02*
X1469507D01*
G01X1442772Y1063443D02*
X1442543D01*
G01X1469631Y1063344D02*
X1457535D01*
G01X1444212Y1063148D02*
X1443073D01*
G01X1457732Y1062754D02*
X1457220D01*
G01X1457732Y1061966D02*
X1457220D01*
G01X1444212Y1061573D02*
X1443073D01*
G01X1469631Y1061376D02*
X1457535D01*
G01X1442772Y1061277D02*
X1442543D01*
G01X1470921Y1061120D02*
X1469507D01*
G01X1470921Y1060451D02*
X1469507D01*
G01X1442772Y1060293D02*
X1442543D01*
G01X1469631Y1060195D02*
X1457535D01*
G01X1444212Y1059998D02*
X1443073D01*
G01X1457732Y1059604D02*
X1457220D01*
G01X1457732Y1058817D02*
X1457220D01*
G01X1444212Y1058423D02*
X1443073D01*
G01X1469631Y1058226D02*
X1457535D01*
G01X1442772Y1058128D02*
X1442543D01*
G01X1470921Y1057970D02*
X1469507D01*
G01X1470921Y1057301D02*
X1469507D01*
G01X1442772Y1057144D02*
X1442543D01*
G01X1469631Y1057045D02*
X1457535D01*
G01X1444212Y1056848D02*
X1443073D01*
G01X1457732Y1056455D02*
X1457220D01*
G01X1457732Y1055667D02*
X1457220D01*
G01X1444212Y1055274D02*
X1443073D01*
G01X1469631Y1055077D02*
X1457535D01*
G01X1442772Y1054978D02*
X1442543D01*
G01X1470921Y1054821D02*
X1469507D01*
G01Y1057301D02*
X1469278Y1057045D01*
G01X1469507Y1060451D02*
X1469278Y1060195D01*
G01X1469507Y1063600D02*
X1469278Y1063344D01*
G01X1469855Y1057301D02*
X1469636Y1057031D01*
G01X1469855Y1060451D02*
X1469636Y1060181D01*
G01X1469855Y1063600D02*
X1469636Y1063330D01*
G01X1442772Y1063443D02*
X1443243Y1063148D01*
G01X1442543Y1063443D02*
X1442684Y1063355D01*
G01X1442772Y1060293D02*
X1443243Y1059998D01*
G01X1442543Y1060293D02*
X1442684Y1060205D01*
G01Y1063355D02*
X1443073Y1063148D01*
G01X1442684Y1060205D02*
X1443073Y1059998D01*
G01X1442684Y1057056D02*
X1443073Y1056848D01*
G01X1469636Y1064540D02*
X1469855Y1064270D01*
G01X1469636Y1061390D02*
X1469855Y1061120D01*
G01X1469636Y1058240D02*
X1469855Y1057970D01*
G01X1469636Y1055091D02*
X1469855Y1054821D01*
G01X1469278Y1064525D02*
X1469507Y1064270D01*
G01X1469278Y1061376D02*
X1469507Y1061120D01*
G01X1469278Y1058226D02*
X1469507Y1057970D01*
G01X1469278Y1055077D02*
X1469507Y1054821D01*
G01X1442772Y1057144D02*
X1443243Y1056848D01*
G01X1442543Y1057144D02*
X1442684Y1057056D01*
G01X1470921Y1054821D02*
Y1054151D01*
G01Y1061120D02*
Y1060451D01*
G01Y1057970D02*
Y1057301D01*
G01Y1064270D02*
Y1063600D01*
G01X1470574Y1054821D02*
Y1054151D01*
G01Y1061120D02*
Y1060451D01*
G01Y1057970D02*
Y1057301D01*
G01Y1064270D02*
Y1063600D01*
G01X1469631Y1055077D02*
Y1053896D01*
G01Y1061376D02*
Y1060195D01*
G01Y1058226D02*
Y1057045D01*
G01Y1064525D02*
Y1063344D01*
G01X1469278Y1055077D02*
Y1053896D01*
G01Y1061376D02*
Y1060195D01*
G01Y1058226D02*
Y1057045D01*
G01Y1064525D02*
Y1063344D01*
G01X1467296Y1055077D02*
Y1053896D01*
G01Y1061376D02*
Y1060195D01*
G01Y1058226D02*
Y1057045D01*
G01Y1064525D02*
Y1063344D01*
G01X1467186Y1055077D02*
Y1053896D01*
G01Y1061376D02*
Y1060195D01*
G01Y1058226D02*
Y1057045D01*
G01Y1064525D02*
Y1063344D01*
G01X1458405Y1055077D02*
Y1053896D01*
G01Y1061376D02*
Y1060195D01*
G01Y1058226D02*
Y1057045D01*
G01Y1064525D02*
Y1063344D01*
G01X1458295Y1055077D02*
Y1053896D01*
G01Y1061376D02*
Y1060195D01*
G01Y1058226D02*
Y1057045D01*
G01Y1064525D02*
Y1063344D01*
G01X1457929Y1055077D02*
Y1053896D01*
G01Y1061376D02*
Y1060195D01*
G01Y1058226D02*
Y1057045D01*
G01Y1064525D02*
Y1063344D01*
G01X1457732Y1055667D02*
Y1055077D01*
G01Y1060195D02*
Y1059604D01*
G01Y1057045D02*
Y1056455D01*
G01Y1058817D02*
Y1058226D01*
G01Y1063344D02*
Y1062754D01*
G01Y1065116D02*
Y1064525D01*
G01Y1061966D02*
Y1061376D01*
G01Y1066494D02*
Y1065903D01*
G01X1457535Y1055667D02*
Y1055077D01*
G01Y1060195D02*
Y1059604D01*
G01Y1057045D02*
Y1056455D01*
G01Y1058817D02*
Y1058226D01*
G01Y1063344D02*
Y1062754D01*
G01Y1065116D02*
Y1064525D01*
G01Y1061966D02*
Y1061376D01*
G01Y1066494D02*
Y1065903D01*
G01X1457220Y1504880D02*
Y1021415D01*
G01X1449937Y1200155D02*
Y1019053D01*
G01X1444212Y1055274D02*
Y1053699D01*
G01Y1058423D02*
Y1056848D01*
G01Y1064722D02*
Y1063148D01*
G01Y1061573D02*
Y1059998D01*
G01X1442684Y1055066D02*
Y1053906D01*
G01Y1061365D02*
Y1060205D01*
G01Y1058216D02*
Y1057056D01*
G01Y1064515D02*
Y1063355D01*
G01X1439047Y994189D02*
X1442543Y994151D01*
G01X1437751Y994204D02*
X1441007Y994168D01*
G01X1438785Y994190D02*
X1436420Y994216D01*
G01X1441235Y994168D02*
X1442772Y994151D01*
G01X1441235Y994168D02*
X1438785Y994190D01*
G01X1437751Y994204D02*
X1436420Y994216D01*
G01X1441235Y995119D02*
X1441007D01*
G01X1439047Y995098D02*
X1438785D01*
G01X1439047Y994190D02*
X1438785D01*
G01X1441235Y994168D02*
X1441007D01*
G01X1440094Y995109D02*
X1438785Y995098D01*
G01X1441235Y995119D02*
X1440094Y995109D01*
G01X1437751Y995083D02*
X1436420Y995072D01*
G01X1442543Y995136D02*
X1441007Y995119D01*
G01X1442543Y995136D02*
X1439047Y995098D01*
G01X1441235Y995119D02*
X1442772Y995136D01*
G01X1439047Y995098D02*
X1440094Y995109D01*
G01X1438785Y995098D02*
X1436420Y995072D01*
G01X1437751Y995083D02*
X1439047Y995098D01*
G01X1441235Y995119D02*
Y994168D01*
G01X1441007Y995119D02*
Y994168D01*
G01X1439047Y995098D02*
Y994189D01*
G01X1438785Y995098D02*
Y994190D01*
G01X1437751Y995078D02*
Y994210D01*
G01X1436420Y995072D02*
Y994216D01*
G01X1430449Y1019053D02*
X1426512Y1017085D01*
G01X1439047Y1054032D02*
X1442543Y1053994D01*
G01X1437751Y1054046D02*
X1441007Y1054010D01*
G01X1439047Y1050882D02*
X1442543Y1050844D01*
G01X1437751Y1050897D02*
X1441007Y1050861D01*
G01X1438785Y1054032D02*
X1436420Y1054058D01*
G01X1438785Y1050882D02*
X1436420Y1050909D01*
G01X1441235Y1054010D02*
X1442772Y1053994D01*
G01X1441235Y1050861D02*
X1442772Y1050844D01*
G01X1441235Y1054010D02*
X1438785Y1054032D01*
G01X1437751Y1054046D02*
X1436420Y1054058D01*
G01X1441235Y1050861D02*
X1438785Y1050882D01*
G01X1437751Y1050897D02*
X1436420Y1050909D01*
G01X1439047Y1054032D02*
X1438785D01*
G01X1441235Y1054010D02*
X1441007D01*
G01X1441235Y1051812D02*
X1441007D01*
G01X1439047Y1051791D02*
X1438785D01*
G01X1439047Y1050882D02*
X1438785D01*
G01X1441235Y1050861D02*
X1441007D01*
G01X1441235Y1048663D02*
X1441007D01*
G01X1439047Y1048641D02*
X1438785D01*
G01X1439047Y1047733D02*
X1438785D01*
G01X1441235Y1047711D02*
X1441007D01*
G01X1441235Y1045513D02*
X1441007D01*
G01X1439047Y1045491D02*
X1438785D01*
G01X1439047Y1044583D02*
X1438785D01*
G01X1441235Y1044562D02*
X1441007D01*
G01X1440094Y1051802D02*
X1438785Y1051791D01*
G01X1441235Y1051812D02*
X1440094Y1051802D01*
G01Y1048653D02*
X1438785Y1048641D01*
G01X1441235Y1048663D02*
X1440094Y1048653D01*
G01Y1045503D02*
X1438785Y1045491D01*
G01X1441235Y1045513D02*
X1440094Y1045503D01*
G01Y1042353D02*
X1438785Y1042342D01*
G01X1441235Y1042363D02*
X1440094Y1042353D01*
G01Y1039204D02*
X1438785Y1039192D01*
G01X1441235Y1039214D02*
X1440094Y1039204D01*
G01X1437751Y1051776D02*
X1436420Y1051765D01*
G01X1437751Y1048627D02*
X1436420Y1048615D01*
G01X1437751Y1045477D02*
X1436420Y1045465D01*
G01X1437751Y1042328D02*
X1436420Y1042316D01*
G01X1437751Y1039178D02*
X1436420Y1039166D01*
G01X1442543Y1051829D02*
X1441007Y1051812D01*
G01X1442543Y1051829D02*
X1439047Y1051791D01*
G01X1441235Y1051812D02*
X1442772Y1051829D01*
G01X1442543Y1048679D02*
X1441007Y1048663D01*
G01X1442543Y1048679D02*
X1439047Y1048641D01*
G01X1441235Y1048663D02*
X1442772Y1048679D01*
G01X1442543Y1045529D02*
X1441007Y1045513D01*
G01X1442543Y1045529D02*
X1439047Y1045491D01*
G01X1441235Y1045513D02*
X1442772Y1045529D01*
G01X1442543Y1042380D02*
X1441007Y1042363D01*
G01X1442543Y1042380D02*
X1439047Y1042342D01*
G01X1441235Y1042363D02*
X1442772Y1042380D01*
G01X1442543Y1039230D02*
X1441007Y1039214D01*
G01X1442543Y1039230D02*
X1439047Y1039192D01*
G01X1441235Y1039214D02*
X1442772Y1039230D01*
G01X1439047Y1051791D02*
X1440094Y1051802D01*
G01X1438785Y1051791D02*
X1436420Y1051765D01*
G01X1437751Y1051776D02*
X1439047Y1051791D01*
G01Y1048641D02*
X1440094Y1048653D01*
G01X1438785Y1048641D02*
X1436420Y1048615D01*
G01X1437751Y1048627D02*
X1439047Y1048641D01*
G01Y1045491D02*
X1440094Y1045503D01*
G01X1438785Y1045491D02*
X1436420Y1045465D01*
G01X1437751Y1045477D02*
X1439047Y1045491D01*
G01Y1042342D02*
X1440094Y1042353D01*
G01X1438785Y1042342D02*
X1436420Y1042316D01*
G01X1437751Y1042328D02*
X1439047Y1042342D01*
G01Y1039192D02*
X1440094Y1039204D01*
G01X1438785Y1039192D02*
X1436420Y1039166D01*
G01X1437751Y1039178D02*
X1439047Y1039192D01*
G01Y1047733D02*
X1442543Y1047695D01*
G01X1437751Y1047747D02*
X1441007Y1047711D01*
G01X1439047Y1044583D02*
X1442543Y1044545D01*
G01X1437751Y1044597D02*
X1441007Y1044562D01*
G01X1439047Y1041434D02*
X1442543Y1041396D01*
G01X1437751Y1041448D02*
X1441007Y1041412D01*
G01X1439047Y1038284D02*
X1442543Y1038246D01*
G01X1437751Y1038298D02*
X1441007Y1038262D01*
G01X1439047Y1035134D02*
X1442543Y1035096D01*
G01X1437751Y1035149D02*
X1441007Y1035113D01*
G01X1439047Y1031985D02*
X1442543Y1031947D01*
G01X1437751Y1031999D02*
X1441007Y1031963D01*
G01X1439047Y1028835D02*
X1442543Y1028797D01*
G01X1437751Y1028849D02*
X1441007Y1028814D01*
G01X1439047Y1025686D02*
X1442543Y1025648D01*
G01X1437751Y1025700D02*
X1441007Y1025664D01*
G01X1439047Y1022536D02*
X1442543Y1022498D01*
G01X1437751Y1022550D02*
X1441007Y1022514D01*
G01X1439047Y1006788D02*
X1442543Y1006750D01*
G01X1437751Y1006802D02*
X1441007Y1006766D01*
G01X1439047Y1003638D02*
X1442543Y1003600D01*
G01X1437751Y1003653D02*
X1441007Y1003617D01*
G01X1439047Y1000489D02*
X1442543Y1000451D01*
G01X1437751Y1000503D02*
X1441007Y1000467D01*
G01X1439047Y997339D02*
X1442543Y997301D01*
G01X1437751Y997353D02*
X1441007Y997318D01*
G01X1438785Y1047733D02*
X1436420Y1047759D01*
G01X1438785Y1044583D02*
X1436420Y1044609D01*
G01X1438785Y1041434D02*
X1436420Y1041460D01*
G01X1438785Y1038284D02*
X1436420Y1038310D01*
G01X1438785Y1035134D02*
X1436420Y1035160D01*
G01X1438785Y1031985D02*
X1436420Y1032011D01*
G01X1438785Y1028835D02*
X1436420Y1028861D01*
G01X1438785Y1025686D02*
X1436420Y1025712D01*
G01X1438785Y1022536D02*
X1436420Y1022562D01*
G01X1438785Y1006788D02*
X1436420Y1006814D01*
G01X1438785Y1003638D02*
X1436420Y1003664D01*
G01X1438785Y1000489D02*
X1436420Y1000515D01*
G01X1438785Y997339D02*
X1436420Y997365D01*
G01X1441235Y1047711D02*
X1442772Y1047695D01*
G01X1441235Y1044562D02*
X1442772Y1044545D01*
G01X1441235Y1041412D02*
X1442772Y1041396D01*
G01X1441235Y1038262D02*
X1442772Y1038246D01*
G01X1441235Y1035113D02*
X1442772Y1035096D01*
G01X1441235Y1031963D02*
X1442772Y1031947D01*
G01X1441235Y1028814D02*
X1442772Y1028797D01*
G01X1441235Y1025664D02*
X1442772Y1025648D01*
G01X1441235Y1022514D02*
X1442772Y1022498D01*
G01X1441235Y1006766D02*
X1442772Y1006750D01*
G01X1441235Y1003617D02*
X1442772Y1003600D01*
G01X1441235Y1000467D02*
X1442772Y1000451D01*
G01X1441235Y997318D02*
X1442772Y997301D01*
G01X1441235Y1047711D02*
X1438785Y1047733D01*
G01X1437751Y1047747D02*
X1436420Y1047759D01*
G01X1441235Y1044562D02*
X1438785Y1044583D01*
G01X1437751Y1044597D02*
X1436420Y1044609D01*
G01X1441235Y1041412D02*
X1438785Y1041434D01*
G01X1437751Y1041448D02*
X1436420Y1041460D01*
G01X1441235Y1038262D02*
X1438785Y1038284D01*
G01X1437751Y1038298D02*
X1436420Y1038310D01*
G01X1441235Y1035113D02*
X1438785Y1035134D01*
G01X1437751Y1035149D02*
X1436420Y1035160D01*
G01X1441235Y1031963D02*
X1438785Y1031985D01*
G01X1437751Y1031999D02*
X1436420Y1032011D01*
G01X1441235Y1028814D02*
X1438785Y1028835D01*
G01X1437751Y1028849D02*
X1436420Y1028861D01*
G01X1441235Y1025664D02*
X1438785Y1025686D01*
G01X1437751Y1025700D02*
X1436420Y1025712D01*
G01X1441235Y1022514D02*
X1438785Y1022536D01*
G01X1437751Y1022550D02*
X1436420Y1022562D01*
G01X1441235Y1006766D02*
X1438785Y1006788D01*
G01X1437751Y1006802D02*
X1436420Y1006814D01*
G01X1441235Y1003617D02*
X1438785Y1003638D01*
G01X1437751Y1003653D02*
X1436420Y1003664D01*
G01X1441235Y1000467D02*
X1438785Y1000489D01*
G01X1437751Y1000503D02*
X1436420Y1000515D01*
G01X1441235Y997318D02*
X1438785Y997339D01*
G01X1437751Y997353D02*
X1436420Y997365D01*
G01X1441235Y1042363D02*
X1441007D01*
G01X1439047Y1042342D02*
X1438785D01*
G01X1439047Y1041434D02*
X1438785D01*
G01X1441235Y1041412D02*
X1441007D01*
G01X1441235Y1039214D02*
X1441007D01*
G01X1439047Y1039192D02*
X1438785D01*
G01X1439047Y1038284D02*
X1438785D01*
G01X1441235Y1038262D02*
X1441007D01*
G01X1441235Y1036064D02*
X1441007D01*
G01X1439047Y1036043D02*
X1438785D01*
G01X1439047Y1035134D02*
X1438785D01*
G01X1441235Y1035113D02*
X1441007D01*
G01X1441235Y1032915D02*
X1441007D01*
G01X1439047Y1032893D02*
X1438785D01*
G01X1439047Y1031985D02*
X1438785D01*
G01X1441235Y1031963D02*
X1441007D01*
G01X1441235Y1029765D02*
X1441007D01*
G01X1439047Y1029743D02*
X1438785D01*
G01X1439047Y1028835D02*
X1438785D01*
G01X1441235Y1028814D02*
X1441007D01*
G01X1441235Y1026615D02*
X1441007D01*
G01X1439047Y1026594D02*
X1438785D01*
G01X1439047Y1025686D02*
X1438785D01*
G01X1441235Y1025664D02*
X1441007D01*
G01Y1023466D02*
X1441235D01*
G01X1439047Y1023444D02*
X1438785D01*
G01X1439047Y1022536D02*
X1438785D01*
G01X1441235Y1022514D02*
X1441007D01*
G01X1449937Y1019053D02*
X1430449D01*
G01Y1011179D02*
X1449937D01*
G01X1441235Y1007718D02*
X1441007D01*
G01X1439047Y1007696D02*
X1438785D01*
G01X1439047Y1006788D02*
X1438785D01*
G01X1441235Y1006766D02*
X1441007D01*
G01X1441235Y1004568D02*
X1441007D01*
G01X1439047Y1004547D02*
X1438785D01*
G01X1439047Y1003638D02*
X1438785D01*
G01X1441235Y1003617D02*
X1441007D01*
G01X1441235Y1001418D02*
X1441007D01*
G01X1439047Y1001397D02*
X1438785D01*
G01X1439047Y1000489D02*
X1438785D01*
G01X1441235Y1000467D02*
X1441007D01*
G01X1441235Y998269D02*
X1441007D01*
G01X1439047Y998247D02*
X1438785D01*
G01X1439047Y997339D02*
X1438785D01*
G01X1441235Y997318D02*
X1441007D01*
G01X1440094Y1036054D02*
X1438785Y1036043D01*
G01X1441235Y1036064D02*
X1440094Y1036054D01*
G01Y1032905D02*
X1438785Y1032893D01*
G01X1441235Y1032915D02*
X1440094Y1032905D01*
G01Y1029755D02*
X1438785Y1029743D01*
G01X1441235Y1029765D02*
X1440094Y1029755D01*
G01Y1026605D02*
X1438785Y1026594D01*
G01X1441235Y1026615D02*
X1440094Y1026605D01*
G01Y1023456D02*
X1438785Y1023444D01*
G01X1441235Y1023466D02*
X1440094Y1023456D01*
G01Y1007708D02*
X1438785Y1007696D01*
G01X1441235Y1007718D02*
X1440094Y1007708D01*
G01Y1004558D02*
X1438785Y1004547D01*
G01X1441235Y1004568D02*
X1440094Y1004558D01*
G01Y1001408D02*
X1438785Y1001397D01*
G01X1441235Y1001418D02*
X1440094Y1001408D01*
G01Y998259D02*
X1438785Y998247D01*
G01X1441235Y998269D02*
X1440094Y998259D01*
G01X1437751Y1036028D02*
X1436420Y1036017D01*
G01X1437751Y1032879D02*
X1436420Y1032867D01*
G01X1437751Y1029729D02*
X1436420Y1029717D01*
G01X1437751Y1026579D02*
X1436420Y1026568D01*
G01X1437751Y1023430D02*
X1436420Y1023418D01*
G01X1437751Y1007682D02*
X1436420Y1007670D01*
G01X1437751Y1004532D02*
X1436420Y1004520D01*
G01X1437751Y1001383D02*
X1436420Y1001371D01*
G01X1437751Y998233D02*
X1436420Y998221D01*
G01X1442543Y1036081D02*
X1441007Y1036064D01*
G01X1442543Y1036081D02*
X1439047Y1036043D01*
G01X1441235Y1036064D02*
X1442772Y1036081D01*
G01X1442543Y1032931D02*
X1441007Y1032915D01*
G01X1442543Y1032931D02*
X1439047Y1032893D01*
G01X1441235Y1032915D02*
X1442772Y1032931D01*
G01X1442543Y1029781D02*
X1441007Y1029765D01*
G01X1442543Y1029781D02*
X1439047Y1029743D01*
G01X1441235Y1029765D02*
X1442772Y1029781D01*
G01X1442543Y1026632D02*
X1441007Y1026615D01*
G01X1442543Y1026632D02*
X1439047Y1026594D01*
G01X1441235Y1026615D02*
X1442772Y1026632D01*
G01X1442543Y1023482D02*
X1441007Y1023466D01*
G01X1442543Y1023482D02*
X1439047Y1023444D01*
G01X1441235Y1023466D02*
X1442772Y1023482D01*
G01X1442543Y1007734D02*
X1441007Y1007718D01*
G01X1442543Y1007734D02*
X1439047Y1007696D01*
G01X1441235Y1007718D02*
X1442772Y1007734D01*
G01X1442543Y1004585D02*
X1441007Y1004568D01*
G01X1442543Y1004585D02*
X1439047Y1004547D01*
G01X1441235Y1004568D02*
X1442772Y1004585D01*
G01X1442543Y1001435D02*
X1441007Y1001418D01*
G01X1442543Y1001435D02*
X1439047Y1001397D01*
G01X1441235Y1001418D02*
X1442772Y1001435D01*
G01X1442543Y998285D02*
X1441007Y998269D01*
G01X1442543Y998285D02*
X1439047Y998247D01*
G01X1441235Y998269D02*
X1442772Y998285D01*
G01X1439047Y1036043D02*
X1440094Y1036054D01*
G01X1438785Y1036043D02*
X1436420Y1036017D01*
G01X1437751Y1036028D02*
X1439047Y1036043D01*
G01Y1032893D02*
X1440094Y1032905D01*
G01X1438785Y1032893D02*
X1436420Y1032867D01*
G01X1437751Y1032879D02*
X1439047Y1032893D01*
G01Y1029743D02*
X1440094Y1029755D01*
G01X1438785Y1029743D02*
X1436420Y1029717D01*
G01X1437751Y1029729D02*
X1439047Y1029743D01*
G01Y1026594D02*
X1440094Y1026605D01*
G01X1438785Y1026594D02*
X1436420Y1026568D01*
G01X1437751Y1026579D02*
X1439047Y1026594D01*
G01Y1023444D02*
X1440094Y1023456D01*
G01X1438785Y1023444D02*
X1436420Y1023418D01*
G01X1437751Y1023430D02*
X1439047Y1023444D01*
G01Y1007696D02*
X1440094Y1007708D01*
G01X1438785Y1007696D02*
X1436420Y1007670D01*
G01X1437751Y1007682D02*
X1439047Y1007696D01*
G01Y1004547D02*
X1440094Y1004558D01*
G01X1438785Y1004547D02*
X1436420Y1004520D01*
G01X1437751Y1004532D02*
X1439047Y1004547D01*
G01Y1001397D02*
X1440094Y1001408D01*
G01X1438785Y1001397D02*
X1436420Y1001371D01*
G01X1437751Y1001383D02*
X1439047Y1001397D01*
G01Y998247D02*
X1440094Y998259D01*
G01X1438785Y998247D02*
X1436420Y998221D01*
G01X1437751Y998233D02*
X1439047Y998247D01*
G01X1426512Y1013148D02*
X1430449Y1011179D01*
G01X1441235Y998269D02*
Y997318D01*
G01Y1004568D02*
Y1003617D01*
G01Y1001418D02*
Y1000467D01*
G01Y1007718D02*
Y1006766D01*
G01Y1023466D02*
Y1022514D01*
G01Y1026615D02*
Y1025664D01*
G01Y1032914D02*
Y1031963D01*
G01Y1029765D02*
Y1028814D01*
G01Y1036064D02*
Y1035113D01*
G01Y1042363D02*
Y1041412D01*
G01Y1039214D02*
Y1038262D01*
G01Y1045513D02*
Y1044562D01*
G01Y1051812D02*
Y1050861D01*
G01Y1048663D02*
Y1047711D01*
G01X1441007Y998269D02*
Y997318D01*
G01Y1004568D02*
Y1003617D01*
G01Y1001418D02*
Y1000467D01*
G01Y1007718D02*
Y1006766D01*
G01Y1023466D02*
Y1022514D01*
G01Y1026615D02*
Y1025664D01*
G01Y1032915D02*
Y1031963D01*
G01Y1029765D02*
Y1028814D01*
G01Y1036064D02*
Y1035113D01*
G01Y1042363D02*
Y1041412D01*
G01Y1039214D02*
Y1038262D01*
G01Y1045513D02*
Y1044562D01*
G01Y1051812D02*
Y1050861D01*
G01Y1048663D02*
Y1047711D01*
G01X1439047Y998247D02*
Y997339D01*
G01Y1004547D02*
Y1003638D01*
G01Y1001397D02*
Y1000489D01*
G01Y1007696D02*
Y1006788D01*
G01Y1023444D02*
Y1022536D01*
G01Y1026594D02*
Y1025686D01*
G01Y1032893D02*
Y1031985D01*
G01Y1029743D02*
Y1028835D01*
G01Y1036043D02*
Y1035134D01*
G01Y1042342D02*
Y1041434D01*
G01Y1039192D02*
Y1038284D01*
G01Y1045491D02*
Y1044583D01*
G01Y1051791D02*
Y1050882D01*
G01Y1048641D02*
Y1047733D01*
G01X1438785Y998247D02*
Y997339D01*
G01Y1004547D02*
Y1003638D01*
G01Y1001397D02*
Y1000489D01*
G01Y1007696D02*
Y1006788D01*
G01Y1023444D02*
Y1022536D01*
G01Y1026594D02*
Y1025686D01*
G01Y1032893D02*
Y1031985D01*
G01Y1029743D02*
Y1028835D01*
G01Y1036043D02*
Y1035134D01*
G01Y1042342D02*
Y1041434D01*
G01Y1039192D02*
Y1038284D01*
G01Y1045491D02*
Y1044583D01*
G01Y1051791D02*
Y1050882D01*
G01Y1048641D02*
Y1047733D01*
G01X1437751Y998227D02*
Y997359D01*
G01Y1004526D02*
Y1003659D01*
G01Y1001377D02*
Y1000509D01*
G01Y1007676D02*
Y1006808D01*
G01Y1023424D02*
Y1022556D01*
G01Y1026574D02*
Y1025706D01*
G01Y1032873D02*
Y1032005D01*
G01Y1029723D02*
Y1028855D01*
G01Y1036022D02*
Y1035155D01*
G01Y1042322D02*
Y1041454D01*
G01Y1039172D02*
Y1038304D01*
G01Y1045471D02*
Y1044603D01*
G01Y1051770D02*
Y1050903D01*
G01Y1048621D02*
Y1047753D01*
G01X1436420Y998221D02*
Y997365D01*
G01Y1004520D02*
Y1003664D01*
G01Y1001371D02*
Y1000515D01*
G01Y1007670D02*
Y1006814D01*
G01Y1023418D02*
Y1022562D01*
G01Y1026568D02*
Y1025712D01*
G01Y1032867D02*
Y1032011D01*
G01Y1029717D02*
Y1028861D01*
G01Y1036017D02*
Y1035160D01*
G01Y1042316D02*
Y1041460D01*
G01Y1039166D02*
Y1038310D01*
G01Y1045465D02*
Y1044609D01*
G01Y1051765D02*
Y1050909D01*
G01Y1048615D02*
Y1047759D01*
G01X1443073Y995431D02*
X1442684Y995224D01*
G01X1443243Y995431D02*
X1442772Y995136D01*
G01X1442684Y995224D02*
X1442543Y995136D01*
G01X1469507Y994309D02*
X1469278Y994053D01*
G01X1469855Y994309D02*
X1469636Y994039D01*
G01X1469631Y995234D02*
X1457535D01*
G01X1442772Y995136D02*
X1442543D01*
G01X1470921Y994978D02*
X1469507D01*
G01X1470921Y994309D02*
X1469507D01*
G01X1442772Y994151D02*
X1442543D01*
G01X1469631Y994053D02*
X1457535D01*
G01X1444212Y993856D02*
X1443073D01*
G01X1457732Y993463D02*
X1457220D01*
G01X1442772Y994151D02*
X1443243Y993856D01*
G01X1442543Y994151D02*
X1442684Y994064D01*
G01D02*
X1443073Y993856D01*
G01X1470921Y994978D02*
Y994309D01*
G01X1470574Y994978D02*
Y994309D01*
G01X1469631Y995234D02*
Y994053D01*
G01X1469278Y995234D02*
Y994053D01*
G01X1467296Y995234D02*
Y994053D01*
G01X1467186Y995234D02*
Y994053D01*
G01X1458405Y995234D02*
Y994053D01*
G01X1458295Y995234D02*
Y994053D01*
G01X1457929Y995234D02*
Y994053D01*
G01X1457732D02*
Y993463D01*
G01Y995825D02*
Y995234D01*
G01X1457535Y994053D02*
Y993463D01*
G01Y995825D02*
Y995234D01*
G01X1444212Y995431D02*
Y993856D01*
G01X1442684Y995224D02*
Y994064D01*
G01X1469636Y995248D02*
X1469855Y994978D01*
G01X1469278Y995234D02*
X1469507Y994978D01*
G01X1474543Y1010785D02*
G03Y1019447I0J4331D01*
G01X1443073Y998581D02*
X1442684Y998373D01*
G01X1443073Y1001730D02*
X1442684Y1001523D01*
G01X1443073Y1004880D02*
X1442684Y1004672D01*
G01X1443073Y1008029D02*
X1442684Y1007822D01*
G01X1443073Y1023777D02*
X1442684Y1023570D01*
G01X1443073Y1026927D02*
X1442684Y1026720D01*
G01X1443073Y1030077D02*
X1442684Y1029869D01*
G01X1443073Y1033226D02*
X1442684Y1033019D01*
G01X1443073Y1036376D02*
X1442684Y1036168D01*
G01X1443073Y1039525D02*
X1442684Y1039318D01*
G01X1443073Y1042675D02*
X1442684Y1042468D01*
G01X1443073Y1045825D02*
X1442684Y1045617D01*
G01X1443073Y1048974D02*
X1442684Y1048767D01*
G01X1443073Y1052124D02*
X1442684Y1051916D01*
G01X1443243Y998581D02*
X1442772Y998285D01*
G01X1442684Y998373D02*
X1442543Y998285D01*
G01X1443243Y1001730D02*
X1442772Y1001435D01*
G01X1442684Y1001523D02*
X1442543Y1001435D01*
G01X1443243Y1004880D02*
X1442772Y1004585D01*
G01X1442684Y1004672D02*
X1442543Y1004585D01*
G01X1443243Y1008029D02*
X1442772Y1007734D01*
G01X1442684Y1007822D02*
X1442543Y1007734D01*
G01X1443243Y1023777D02*
X1442772Y1023482D01*
G01X1442684Y1023570D02*
X1442543Y1023482D01*
G01X1443243Y1026927D02*
X1442772Y1026632D01*
G01X1442684Y1026720D02*
X1442543Y1026632D01*
G01X1443243Y1030077D02*
X1442772Y1029781D01*
G01X1442684Y1029869D02*
X1442543Y1029781D01*
G01X1443243Y1033226D02*
X1442772Y1032931D01*
G01X1442684Y1033019D02*
X1442543Y1032931D01*
G01X1443243Y1036376D02*
X1442772Y1036081D01*
G01X1442684Y1036168D02*
X1442543Y1036081D01*
G01X1443243Y1039525D02*
X1442772Y1039230D01*
G01X1442684Y1039318D02*
X1442543Y1039230D01*
G01X1443243Y1042675D02*
X1442772Y1042380D01*
G01X1442684Y1042468D02*
X1442543Y1042380D01*
G01X1443243Y1045825D02*
X1442772Y1045529D01*
G01X1442684Y1045617D02*
X1442543Y1045529D01*
G01X1443243Y1048974D02*
X1442772Y1048679D01*
G01X1442684Y1048767D02*
X1442543Y1048679D01*
G01X1443243Y1052124D02*
X1442772Y1051829D01*
G01X1442684Y1051916D02*
X1442543Y1051829D01*
G01X1470921Y1054151D02*
X1469507D01*
G01X1442772Y1053994D02*
X1442543D01*
G01X1469631Y1053896D02*
X1457535D01*
G01X1444212Y1053699D02*
X1443073D01*
G01X1457732Y1053305D02*
X1457220D01*
G01X1457732Y1052518D02*
X1457220D01*
G01X1444212Y1052124D02*
X1443073D01*
G01X1469631Y1051927D02*
X1457535D01*
G01X1442772Y1051829D02*
X1442543D01*
G01X1470921Y1051671D02*
X1469507D01*
G01X1470921Y1051002D02*
X1469507D01*
G01X1442772Y1050844D02*
X1442543D01*
G01X1469631Y1050746D02*
X1457535D01*
G01X1444212Y1050549D02*
X1443073D01*
G01X1457732Y1050155D02*
X1457220D01*
G01X1457732Y1049368D02*
X1457220D01*
G01X1444212Y1048974D02*
X1443073D01*
G01X1469631Y1048777D02*
X1457535D01*
G01X1442772Y1048679D02*
X1442543D01*
G01X1470921Y1048522D02*
X1469507D01*
G01X1470921Y1047852D02*
X1469507D01*
G01X1442772Y1047695D02*
X1442543D01*
G01X1469631Y1047596D02*
X1457535D01*
G01X1444212Y1047400D02*
X1443073D01*
G01X1457732Y1047006D02*
X1457220D01*
G01X1457732Y1046218D02*
X1457220D01*
G01X1444212Y1045825D02*
X1443073D01*
G01X1469631Y1045628D02*
X1457535D01*
G01X1442772Y1045529D02*
X1442543D01*
G01X1470921Y1045372D02*
X1469507D01*
G01X1470921Y1044703D02*
X1469507D01*
G01X1442772Y1044545D02*
X1442543D01*
G01X1469631Y1044447D02*
X1457535D01*
G01X1444212Y1044250D02*
X1443073D01*
G01X1457732Y1043856D02*
X1457220D01*
G01X1476905Y1013148D02*
X1474937Y1011179D01*
G01X1457220Y1008817D02*
X1459189Y1010785D01*
G01X1469507Y997459D02*
X1469278Y997203D01*
G01X1469507Y1000608D02*
X1469278Y1000352D01*
G01X1469507Y1003758D02*
X1469278Y1003502D01*
G01X1469507Y1006907D02*
X1469278Y1006651D01*
G01X1469507Y1022655D02*
X1469278Y1022400D01*
G01X1469507Y1025805D02*
X1469278Y1025549D01*
G01X1469507Y1028955D02*
X1469278Y1028699D01*
G01X1469507Y1032104D02*
X1469278Y1031848D01*
G01X1469507Y1035254D02*
X1469278Y1034998D01*
G01X1469507Y1038403D02*
X1469278Y1038148D01*
G01X1469855Y997459D02*
X1469636Y997189D01*
G01X1457732Y1043069D02*
X1457220D01*
G01X1444212Y1042675D02*
X1443073D01*
G01X1469631Y1042478D02*
X1457535D01*
G01X1442772Y1042380D02*
X1442543D01*
G01X1470921Y1042222D02*
X1469507D01*
G01X1470921Y1041553D02*
X1469507D01*
G01X1442772Y1041396D02*
X1442543D01*
G01X1469631Y1041297D02*
X1457535D01*
G01X1444212Y1041100D02*
X1443073D01*
G01X1457732Y1040707D02*
X1457220D01*
G01X1457732Y1039919D02*
X1457220D01*
G01X1444212Y1039525D02*
X1443073D01*
G01X1469631Y1039329D02*
X1457535D01*
G01X1442772Y1039230D02*
X1442543D01*
G01X1470921Y1039073D02*
X1469507D01*
G01X1470921Y1038403D02*
X1469507D01*
G01X1442772Y1038246D02*
X1442543D01*
G01X1469631Y1038148D02*
X1457535D01*
G01X1444212Y1037951D02*
X1443073D01*
G01X1457732Y1037557D02*
X1457220D01*
G01X1457732Y1036770D02*
X1457220D01*
G01X1444212Y1036376D02*
X1443073D01*
G01X1469631Y1036179D02*
X1457535D01*
G01X1442772Y1036081D02*
X1442543D01*
G01X1470921Y1035923D02*
X1469507D01*
G01X1470921Y1035254D02*
X1469507D01*
G01X1442772Y1035096D02*
X1442543D01*
G01X1469631Y1034998D02*
X1457535D01*
G01X1444212Y1034801D02*
X1443073D01*
G01X1457732Y1034407D02*
X1457220D01*
G01X1457732Y1033620D02*
X1457220D01*
G01X1444212Y1033226D02*
X1443073D01*
G01X1469631Y1033029D02*
X1457535D01*
G01X1442772Y1032931D02*
X1442543D01*
G01X1470921Y1032774D02*
X1469507D01*
G01X1470921Y1032104D02*
X1469507D01*
G01X1442772Y1031947D02*
X1442543D01*
G01X1469631Y1031848D02*
X1457535D01*
G01X1444212Y1031651D02*
X1443073D01*
G01X1457732Y1031258D02*
X1457220D01*
G01X1457732Y1030470D02*
X1457220D01*
G01X1444212Y1030077D02*
X1443073D01*
G01X1469631Y1029880D02*
X1457535D01*
G01X1442772Y1029781D02*
X1442543D01*
G01X1470921Y1029624D02*
X1469507D01*
G01X1470921Y1028955D02*
X1469507D01*
G01X1442772Y1028797D02*
X1442543D01*
G01X1469631Y1028699D02*
X1457535D01*
G01X1444212Y1028502D02*
X1443073D01*
G01X1457732Y1028108D02*
X1457220D01*
G01X1457732Y1027321D02*
X1457220D01*
G01X1444212Y1026927D02*
X1443073D01*
G01X1469631Y1026730D02*
X1457535D01*
G01X1442772Y1026632D02*
X1442543D01*
G01X1470921Y1026474D02*
X1469507D01*
G01X1470921Y1025805D02*
X1469507D01*
G01X1442772Y1025648D02*
X1442543D01*
G01X1469631Y1025549D02*
X1457535D01*
G01X1444212Y1025352D02*
X1443073D01*
G01X1457732Y1024959D02*
X1457220D01*
G01X1457732Y1024171D02*
X1457220D01*
G01X1444212Y1023777D02*
X1443073D01*
G01X1469631Y1023581D02*
X1457535D01*
G01X1442772Y1023482D02*
X1442543D01*
G01X1470921Y1023325D02*
X1469507D01*
G01X1470921Y1022655D02*
X1469507D01*
G01X1442772Y1022498D02*
X1442543D01*
G01X1469631Y1022400D02*
X1457535D01*
G01X1444212Y1022203D02*
X1443073D01*
G01X1457732Y1021809D02*
X1457220D01*
G01X1474543Y1019447D02*
X1459189D01*
G01X1474937Y1019053D02*
X1457220D01*
G01X1474937Y1011179D02*
X1457220D01*
G01X1459189Y1010785D02*
X1474543D01*
G01X1457732Y1008423D02*
X1457220D01*
G01X1444212Y1008029D02*
X1443073D01*
G01X1469631Y1007833D02*
X1457535D01*
G01X1442772Y1007734D02*
X1442543D01*
G01X1470921Y1007577D02*
X1469507D01*
G01X1470921Y1006907D02*
X1469507D01*
G01X1442772Y1006750D02*
X1442543D01*
G01X1469631Y1006651D02*
X1457535D01*
G01X1444212Y1006455D02*
X1443073D01*
G01X1457732Y1006061D02*
X1457220D01*
G01X1457732Y1005274D02*
X1457220D01*
G01X1444212Y1004880D02*
X1443073D01*
G01X1469631Y1004683D02*
X1457535D01*
G01X1442772Y1004585D02*
X1442543D01*
G01X1470921Y1004427D02*
X1469507D01*
G01X1470921Y1003758D02*
X1469507D01*
G01X1442772Y1003600D02*
X1442543D01*
G01X1469631Y1003502D02*
X1457535D01*
G01X1444212Y1003305D02*
X1443073D01*
G01X1457732Y1002911D02*
X1457220D01*
G01X1457732Y1002124D02*
X1457220D01*
G01X1444212Y1001730D02*
X1443073D01*
G01X1469631Y1001533D02*
X1457535D01*
G01X1442772Y1001435D02*
X1442543D01*
G01X1470921Y1001277D02*
X1469507D01*
G01X1470921Y1000608D02*
X1469507D01*
G01X1442772Y1000451D02*
X1442543D01*
G01X1469631Y1000352D02*
X1457535D01*
G01X1444212Y1000155D02*
X1443073D01*
G01X1457732Y999762D02*
X1457220D01*
G01X1457732Y998974D02*
X1457220D01*
G01X1444212Y998581D02*
X1443073D01*
G01X1469631Y998384D02*
X1457535D01*
G01X1442772Y998285D02*
X1442543D01*
G01X1470921Y998128D02*
X1469507D01*
G01X1470921Y997459D02*
X1469507D01*
G01X1442772Y997301D02*
X1442543D01*
G01X1469631Y997203D02*
X1457535D01*
G01X1444212Y997006D02*
X1443073D01*
G01X1457732Y996612D02*
X1457220D01*
G01X1457732Y995825D02*
X1457220D01*
G01X1444212Y995431D02*
X1443073D01*
G01X1469507Y1041553D02*
X1469278Y1041297D01*
G01X1469507Y1044703D02*
X1469278Y1044447D01*
G01X1469507Y1047852D02*
X1469278Y1047596D01*
G01X1469507Y1051002D02*
X1469278Y1050746D01*
G01X1469507Y1054151D02*
X1469278Y1053896D01*
G01X1469855Y1000608D02*
X1469636Y1000338D01*
G01X1469855Y1003758D02*
X1469636Y1003488D01*
G01X1469855Y1006907D02*
X1469636Y1006637D01*
G01X1469855Y1022655D02*
X1469636Y1022385D01*
G01X1469855Y1025805D02*
X1469636Y1025535D01*
G01X1469855Y1028955D02*
X1469636Y1028685D01*
G01X1469855Y1032104D02*
X1469636Y1031834D01*
G01X1469855Y1035254D02*
X1469636Y1034984D01*
G01X1469855Y1038403D02*
X1469636Y1038133D01*
G01X1469855Y1041553D02*
X1469636Y1041283D01*
G01X1469855Y1044703D02*
X1469636Y1044433D01*
G01X1469855Y1047852D02*
X1469636Y1047582D01*
G01X1469855Y1051002D02*
X1469636Y1050732D01*
G01X1469855Y1054151D02*
X1469636Y1053881D01*
G01X1442684Y1053906D02*
X1443073Y1053699D01*
G01X1442684Y1050757D02*
X1443073Y1050549D01*
G01X1442684Y1047607D02*
X1443073Y1047400D01*
G01X1442684Y1044457D02*
X1443073Y1044250D01*
G01X1442684Y1041308D02*
X1443073Y1041100D01*
G01X1442684Y1038158D02*
X1443073Y1037951D01*
G01X1442684Y1035009D02*
X1443073Y1034801D01*
G01X1469636Y1051941D02*
X1469855Y1051671D01*
G01X1469636Y1048792D02*
X1469855Y1048522D01*
G01X1469636Y1045642D02*
X1469855Y1045372D01*
G01X1469636Y1042492D02*
X1469855Y1042222D01*
G01X1469278Y1051927D02*
X1469507Y1051671D01*
G01X1469278Y1048777D02*
X1469507Y1048522D01*
G01X1469278Y1045628D02*
X1469507Y1045372D01*
G01X1469278Y1042478D02*
X1469507Y1042222D01*
G01X1469278Y1039329D02*
X1469507Y1039073D01*
G01X1469278Y1036179D02*
X1469507Y1035923D01*
G01X1469278Y1033029D02*
X1469507Y1032774D01*
G01X1469278Y1029880D02*
X1469507Y1029624D01*
G01X1474937Y1019053D02*
X1476905Y1017085D01*
G01X1442772Y1053994D02*
X1443243Y1053699D01*
G01X1442543Y1053994D02*
X1442684Y1053906D01*
G01X1442772Y1050844D02*
X1443243Y1050549D01*
G01X1442543Y1050844D02*
X1442684Y1050757D01*
G01X1442772Y1047695D02*
X1443243Y1047400D01*
G01X1442543Y1047695D02*
X1442684Y1047607D01*
G01X1442772Y1044545D02*
X1443243Y1044250D01*
G01X1442543Y1044545D02*
X1442684Y1044457D01*
G01X1442772Y1041396D02*
X1443243Y1041100D01*
G01X1442543Y1041396D02*
X1442684Y1041308D01*
G01X1442772Y1038246D02*
X1443243Y1037951D01*
G01X1442543Y1038246D02*
X1442684Y1038158D01*
G01X1442772Y1035096D02*
X1443243Y1034801D01*
G01X1442543Y1035096D02*
X1442684Y1035009D01*
G01X1442772Y1031947D02*
X1443243Y1031651D01*
G01X1442543Y1031947D02*
X1442684Y1031859D01*
G01X1442772Y1028797D02*
X1443243Y1028502D01*
G01X1442543Y1028797D02*
X1442684Y1028709D01*
G01X1442772Y1025648D02*
X1443243Y1025352D01*
G01X1442543Y1025648D02*
X1442684Y1025560D01*
G01X1442772Y1022498D02*
X1443243Y1022203D01*
G01X1442543Y1022498D02*
X1442684Y1022410D01*
G01X1442772Y1006750D02*
X1443243Y1006455D01*
G01X1442543Y1006750D02*
X1442684Y1006662D01*
G01X1442772Y1003600D02*
X1443243Y1003305D01*
G01X1442543Y1003600D02*
X1442684Y1003512D01*
G01X1442772Y1000451D02*
X1443243Y1000155D01*
G01X1442543Y1000451D02*
X1442684Y1000363D01*
G01X1442772Y997301D02*
X1443243Y997006D01*
G01X1442543Y997301D02*
X1442684Y997213D01*
G01Y1031859D02*
X1443073Y1031651D01*
G01X1442684Y1028709D02*
X1443073Y1028502D01*
G01X1442684Y1025560D02*
X1443073Y1025352D01*
G01X1442684Y1022410D02*
X1443073Y1022203D01*
G01X1442684Y1006662D02*
X1443073Y1006455D01*
G01X1442684Y1003512D02*
X1443073Y1003305D01*
G01X1442684Y1000363D02*
X1443073Y1000155D01*
G01X1442684Y997213D02*
X1443073Y997006D01*
G01X1476905Y1017085D02*
Y1013148D01*
G01X1470921Y998128D02*
Y997459D01*
G01Y1004427D02*
Y1003758D01*
G01Y1001277D02*
Y1000608D01*
G01Y1007577D02*
Y1006907D01*
G01Y1023325D02*
Y1022655D01*
G01Y1026474D02*
Y1025805D01*
G01Y1032774D02*
Y1032104D01*
G01Y1029624D02*
Y1028955D01*
G01Y1035923D02*
Y1035254D01*
G01Y1042222D02*
Y1041553D01*
G01Y1039073D02*
Y1038403D01*
G01Y1045372D02*
Y1044703D01*
G01Y1051671D02*
Y1051002D01*
G01Y1048522D02*
Y1047852D01*
G01X1470574Y998128D02*
Y997459D01*
G01Y1004427D02*
Y1003758D01*
G01Y1001277D02*
Y1000608D01*
G01Y1007577D02*
Y1006907D01*
G01Y1023325D02*
Y1022655D01*
G01Y1026474D02*
Y1025805D01*
G01Y1032774D02*
Y1032104D01*
G01Y1029624D02*
Y1028955D01*
G01Y1035923D02*
Y1035254D01*
G01Y1042222D02*
Y1041553D01*
G01Y1039073D02*
Y1038403D01*
G01Y1045372D02*
Y1044703D01*
G01Y1051671D02*
Y1051002D01*
G01Y1048522D02*
Y1047852D01*
G01X1469631Y998384D02*
Y997203D01*
G01Y1004683D02*
Y1003502D01*
G01Y1001533D02*
Y1000352D01*
G01Y1007833D02*
Y1006651D01*
G01Y1023581D02*
Y1022400D01*
G01Y1026730D02*
Y1025549D01*
G01Y1033029D02*
Y1031848D01*
G01Y1029880D02*
Y1028699D01*
G01Y1036179D02*
Y1034998D01*
G01Y1042478D02*
Y1041297D01*
G01Y1039329D02*
Y1038148D01*
G01Y1045628D02*
Y1044447D01*
G01Y1051927D02*
Y1050746D01*
G01Y1048777D02*
Y1047596D01*
G01X1469278Y998384D02*
Y997203D01*
G01Y1004683D02*
Y1003502D01*
G01Y1001533D02*
Y1000352D01*
G01Y1007833D02*
Y1006651D01*
G01Y1023581D02*
Y1022400D01*
G01Y1026730D02*
Y1025549D01*
G01Y1033029D02*
Y1031848D01*
G01Y1029880D02*
Y1028699D01*
G01Y1036179D02*
Y1034998D01*
G01Y1042478D02*
Y1041297D01*
G01Y1039329D02*
Y1038148D01*
G01Y1045628D02*
Y1044447D01*
G01Y1051927D02*
Y1050746D01*
G01Y1048777D02*
Y1047596D01*
G01X1467296Y998384D02*
Y997203D01*
G01Y1004683D02*
Y1003502D01*
G01Y1001533D02*
Y1000352D01*
G01Y1007833D02*
Y1006651D01*
G01Y1023581D02*
Y1022400D01*
G01Y1026730D02*
Y1025549D01*
G01Y1033029D02*
Y1031848D01*
G01Y1029880D02*
Y1028699D01*
G01Y1036179D02*
Y1034998D01*
G01Y1042478D02*
Y1041297D01*
G01Y1039329D02*
Y1038148D01*
G01Y1045628D02*
Y1044447D01*
G01Y1051927D02*
Y1050746D01*
G01Y1048777D02*
Y1047596D01*
G01X1467186Y998384D02*
Y997203D01*
G01Y1004683D02*
Y1003502D01*
G01Y1001533D02*
Y1000352D01*
G01Y1007833D02*
Y1006651D01*
G01Y1023581D02*
Y1022400D01*
G01Y1026730D02*
Y1025549D01*
G01Y1033029D02*
Y1031848D01*
G01Y1029880D02*
Y1028699D01*
G01Y1036179D02*
Y1034998D01*
G01Y1042478D02*
Y1041297D01*
G01Y1039329D02*
Y1038148D01*
G01Y1045628D02*
Y1044447D01*
G01Y1051927D02*
Y1050746D01*
G01Y1048777D02*
Y1047596D01*
G01X1458405Y998384D02*
Y997203D01*
G01Y1004683D02*
Y1003502D01*
G01Y1001533D02*
Y1000352D01*
G01Y1007833D02*
Y1006651D01*
G01Y1023581D02*
Y1022400D01*
G01Y1026730D02*
Y1025549D01*
G01Y1033029D02*
Y1031848D01*
G01Y1029880D02*
Y1028699D01*
G01Y1036179D02*
Y1034998D01*
G01Y1042478D02*
Y1041297D01*
G01Y1039329D02*
Y1038148D01*
G01Y1045628D02*
Y1044447D01*
G01Y1051927D02*
Y1050746D01*
G01Y1048777D02*
Y1047596D01*
G01X1458295Y998384D02*
Y997203D01*
G01Y1004683D02*
Y1003502D01*
G01Y1001533D02*
Y1000352D01*
G01Y1007833D02*
Y1006651D01*
G01Y1023581D02*
Y1022400D01*
G01Y1026730D02*
Y1025549D01*
G01Y1033029D02*
Y1031848D01*
G01Y1029880D02*
Y1028699D01*
G01Y1036179D02*
Y1034998D01*
G01Y1042478D02*
Y1041297D01*
G01Y1039329D02*
Y1038148D01*
G01Y1045628D02*
Y1044447D01*
G01Y1051927D02*
Y1050746D01*
G01Y1048777D02*
Y1047596D01*
G01X1457929Y998384D02*
Y997203D01*
G01Y1004683D02*
Y1003502D01*
G01Y1001533D02*
Y1000352D01*
G01Y1007833D02*
Y1006651D01*
G01Y1023581D02*
Y1022400D01*
G01Y1026730D02*
Y1025549D01*
G01Y1033029D02*
Y1031848D01*
G01Y1029880D02*
Y1028699D01*
G01Y1036179D02*
Y1034998D01*
G01Y1042478D02*
Y1041297D01*
G01Y1039329D02*
Y1038148D01*
G01Y1045628D02*
Y1044447D01*
G01Y1051927D02*
Y1050746D01*
G01Y1048777D02*
Y1047596D01*
G01X1457732Y1000352D02*
Y999762D01*
G01Y997203D02*
Y996612D01*
G01Y998974D02*
Y998384D01*
G01Y1003502D02*
Y1002911D01*
G01Y1002124D02*
Y1001533D01*
G01Y1006651D02*
Y1006061D01*
G01Y1008423D02*
Y1007833D01*
G01Y1005274D02*
Y1004683D01*
G01Y1022400D02*
Y1021809D01*
G01Y1025549D02*
Y1024959D01*
G01Y1027321D02*
Y1026730D01*
G01Y1024171D02*
Y1023581D01*
G01Y1031848D02*
Y1031258D01*
G01Y1028699D02*
Y1028108D01*
G01Y1030470D02*
Y1029880D01*
G01Y1034998D02*
Y1034407D01*
G01Y1036770D02*
Y1036179D01*
G01Y1033620D02*
Y1033029D01*
G01Y1041297D02*
Y1040707D01*
G01Y1038148D02*
Y1037557D01*
G01Y1039919D02*
Y1039329D01*
G01Y1044447D02*
Y1043856D01*
G01Y1046218D02*
Y1045628D01*
G01Y1043069D02*
Y1042478D01*
G01Y1050746D02*
Y1050155D01*
G01Y1047596D02*
Y1047006D01*
G01Y1049368D02*
Y1048777D01*
G01Y1053896D02*
Y1053305D01*
G01Y1052518D02*
Y1051927D01*
G01X1457535Y1000352D02*
Y999762D01*
G01Y997203D02*
Y996612D01*
G01Y998974D02*
Y998384D01*
G01Y1003502D02*
Y1002911D01*
G01Y1002124D02*
Y1001533D01*
G01Y1006651D02*
Y1006061D01*
G01Y1008423D02*
Y1007833D01*
G01Y1005274D02*
Y1004683D01*
G01Y1022400D02*
Y1021809D01*
G01Y1025549D02*
Y1024959D01*
G01Y1027321D02*
Y1026730D01*
G01Y1024171D02*
Y1023581D01*
G01Y1031848D02*
Y1031258D01*
G01Y1028699D02*
Y1028108D01*
G01Y1030470D02*
Y1029880D01*
G01Y1034998D02*
Y1034407D01*
G01Y1036770D02*
Y1036179D01*
G01Y1033620D02*
Y1033029D01*
G01Y1041297D02*
Y1040707D01*
G01Y1038148D02*
Y1037557D01*
G01Y1039919D02*
Y1039329D01*
G01Y1044447D02*
Y1043856D01*
G01Y1046218D02*
Y1045628D01*
G01Y1043069D02*
Y1042478D01*
G01Y1050746D02*
Y1050155D01*
G01Y1047596D02*
Y1047006D01*
G01Y1049368D02*
Y1048777D01*
G01Y1053896D02*
Y1053305D01*
G01Y1052518D02*
Y1051927D01*
G01X1444212Y998581D02*
Y997006D01*
G01Y1004880D02*
Y1003305D01*
G01Y1001730D02*
Y1000155D01*
G01Y1008029D02*
Y1006455D01*
G01Y1023777D02*
Y1022203D01*
G01Y1026927D02*
Y1025352D01*
G01Y1033226D02*
Y1031651D01*
G01Y1030077D02*
Y1028502D01*
G01Y1036376D02*
Y1034801D01*
G01Y1042675D02*
Y1041100D01*
G01Y1039525D02*
Y1037951D01*
G01Y1045825D02*
Y1044250D01*
G01Y1048974D02*
Y1047400D01*
G01Y1052124D02*
Y1050549D01*
G01X1442684Y998373D02*
Y997213D01*
G01Y1004672D02*
Y1003512D01*
G01Y1001523D02*
Y1000363D01*
G01Y1007822D02*
Y1006662D01*
G01Y1023570D02*
Y1022410D01*
G01Y1026720D02*
Y1025560D01*
G01Y1033019D02*
Y1031859D01*
G01Y1029869D02*
Y1028709D01*
G01Y1036168D02*
Y1035009D01*
G01Y1042468D02*
Y1041308D01*
G01Y1039318D02*
Y1038158D01*
G01Y1045617D02*
Y1044457D01*
G01Y1051916D02*
Y1050757D01*
G01Y1048767D02*
Y1047607D01*
G01X1469636Y1039343D02*
X1469855Y1039073D01*
G01X1469636Y1036193D02*
X1469855Y1035923D01*
G01X1469636Y1033044D02*
X1469855Y1032774D01*
G01X1469636Y1029894D02*
X1469855Y1029624D01*
G01X1469636Y1026744D02*
X1469855Y1026474D01*
G01X1469636Y1023595D02*
X1469855Y1023325D01*
G01X1469636Y1007847D02*
X1469855Y1007577D01*
G01X1469636Y1004697D02*
X1469855Y1004427D01*
G01X1469636Y1001547D02*
X1469855Y1001277D01*
G01X1469636Y998398D02*
X1469855Y998128D01*
G01X1469278Y1026730D02*
X1469507Y1026474D01*
G01X1469278Y1023581D02*
X1469507Y1023325D01*
G01X1469278Y1007833D02*
X1469507Y1007577D01*
G01X1469278Y1004683D02*
X1469507Y1004427D01*
G01X1469278Y1001533D02*
X1469507Y1001277D01*
G01X1469278Y998384D02*
X1469507Y998128D01*
G01X1459189Y1019447D02*
X1457220Y1021415D01*
G01X1439047Y1066630D02*
X1442543Y1066592D01*
G01X1437751Y1066645D02*
X1441007Y1066609D01*
G01X1438785Y1066630D02*
X1436420Y1066657D01*
G01X1441235Y1066609D02*
X1442772Y1066592D01*
G01X1441235Y1066609D02*
X1438785Y1066630D01*
G01X1437751Y1066645D02*
X1436420Y1066657D01*
G01X1441235Y1067560D02*
X1441007D01*
G01X1439047Y1067539D02*
X1438785D01*
G01X1439047Y1066630D02*
X1438785D01*
G01X1441235Y1066609D02*
X1441007D01*
G01X1440094Y1067550D02*
X1438785Y1067539D01*
G01X1441235Y1067560D02*
X1440094Y1067550D01*
G01X1437751Y1067524D02*
X1436420Y1067513D01*
G01X1442543Y1067577D02*
X1441007Y1067560D01*
G01X1442543Y1067577D02*
X1439047Y1067539D01*
G01X1441235Y1067560D02*
X1442772Y1067577D01*
G01X1439047Y1067539D02*
X1440094Y1067550D01*
G01X1438785Y1067539D02*
X1436420Y1067513D01*
G01X1437751Y1067524D02*
X1439047Y1067539D01*
G01X1441235Y1067560D02*
Y1066609D01*
G01X1441007Y1067560D02*
Y1066609D01*
G01X1439047Y1067539D02*
Y1066630D01*
G01X1438785Y1067539D02*
Y1066630D01*
G01X1437751Y1067518D02*
Y1066651D01*
G01X1436420Y1067513D02*
Y1066657D01*
G01X1439047Y1135922D02*
X1442543Y1135884D01*
G01X1437751Y1135936D02*
X1441007Y1135900D01*
G01X1439047Y1132772D02*
X1442543Y1132734D01*
G01X1437751Y1132786D02*
X1441007Y1132751D01*
G01X1439047Y1129623D02*
X1442543Y1129585D01*
G01X1437751Y1129637D02*
X1441007Y1129601D01*
G01X1439047Y1126473D02*
X1442543Y1126435D01*
G01X1437751Y1126487D02*
X1441007Y1126451D01*
G01X1438785Y1135922D02*
X1436420Y1135948D01*
G01X1438785Y1132772D02*
X1436420Y1132798D01*
G01X1438785Y1129623D02*
X1436420Y1129649D01*
G01X1438785Y1126473D02*
X1436420Y1126499D01*
G01X1441235Y1135900D02*
X1442772Y1135884D01*
G01X1441235Y1132751D02*
X1442772Y1132734D01*
G01X1441235Y1129601D02*
X1442772Y1129585D01*
G01X1441235Y1126451D02*
X1442772Y1126435D01*
G01X1441235Y1135900D02*
X1438785Y1135922D01*
G01X1437751Y1135936D02*
X1436420Y1135948D01*
G01X1441235Y1132751D02*
X1438785Y1132772D01*
G01X1437751Y1132786D02*
X1436420Y1132798D01*
G01X1441235Y1129601D02*
X1438785Y1129623D01*
G01X1437751Y1129637D02*
X1436420Y1129649D01*
G01X1441235Y1126451D02*
X1438785Y1126473D01*
G01X1437751Y1126487D02*
X1436420Y1126499D01*
G01X1441235Y1136852D02*
X1441007D01*
G01X1439047Y1136830D02*
X1438785D01*
G01X1439047Y1135922D02*
X1438785D01*
G01X1441235Y1135900D02*
X1441007D01*
G01Y1133702D02*
X1441235D01*
G01X1439047Y1133680D02*
X1438785D01*
G01X1439047Y1132772D02*
X1438785D01*
G01X1441235Y1132751D02*
X1441007D01*
G01X1441235Y1130552D02*
X1441007D01*
G01X1439047Y1130531D02*
X1438785D01*
G01X1439047Y1129623D02*
X1438785D01*
G01X1441235Y1129601D02*
X1441007D01*
G01X1441235Y1127403D02*
X1441007D01*
G01X1439047Y1127381D02*
X1438785D01*
G01X1439047Y1126473D02*
X1438785D01*
G01X1441235Y1126451D02*
X1441007D01*
G01X1441235Y1124253D02*
X1441007D01*
G01X1438785Y1124232D02*
X1439047D01*
G01Y1123323D02*
X1438785D01*
G01X1441235Y1123302D02*
X1441007D01*
G01X1441235Y1121104D02*
X1441007D01*
G01X1439047Y1121082D02*
X1438785D01*
G01Y1136830D02*
X1440094Y1136842D01*
G01X1441235Y1136852D02*
X1440094Y1136842D01*
G01Y1133692D02*
X1438785Y1133680D01*
G01X1441235Y1133702D02*
X1440094Y1133692D01*
G01Y1130542D02*
X1438785Y1130531D01*
G01X1441235Y1130552D02*
X1440094Y1130542D01*
G01Y1127393D02*
X1438785Y1127381D01*
G01X1441235Y1127403D02*
X1440094Y1127393D01*
G01Y1124243D02*
X1438785Y1124232D01*
G01X1441235Y1124253D02*
X1440094Y1124243D01*
G01Y1121094D02*
X1438785Y1121082D01*
G01X1441235Y1121104D02*
X1440094Y1121094D01*
G01X1438785Y1117932D02*
X1440094Y1117944D01*
G01X1441235Y1117954D02*
X1440094Y1117944D01*
G01X1437751Y1136816D02*
X1436420Y1136804D01*
G01X1437751Y1133666D02*
X1436420Y1133654D01*
G01X1437751Y1130516D02*
X1436420Y1130505D01*
G01X1437751Y1127367D02*
X1436420Y1127355D01*
G01X1437751Y1124217D02*
X1436420Y1124205D01*
G01X1437751Y1121068D02*
X1436420Y1121056D01*
G01X1437751Y1117918D02*
X1436420Y1117906D01*
G01X1442543Y1136868D02*
X1441007Y1136852D01*
G01X1442543Y1136868D02*
X1439047Y1136830D01*
G01X1441235Y1136852D02*
X1442772Y1136868D01*
G01X1442543Y1133718D02*
X1441007Y1133702D01*
G01X1442543Y1133718D02*
X1439047Y1133680D01*
G01X1441235Y1133702D02*
X1442772Y1133718D01*
G01X1442543Y1130569D02*
X1441007Y1130552D01*
G01X1442543Y1130569D02*
X1439047Y1130531D01*
G01X1441235Y1130552D02*
X1442772Y1130569D01*
G01X1442543Y1127419D02*
X1441007Y1127403D01*
G01X1442543Y1127419D02*
X1439047Y1127381D01*
G01X1441235Y1127403D02*
X1442772Y1127419D01*
G01X1442543Y1124270D02*
X1441007Y1124253D01*
G01X1442543Y1124270D02*
X1439047Y1124232D01*
G01X1441235Y1124253D02*
X1442772Y1124270D01*
G01X1442543Y1121120D02*
X1441007Y1121104D01*
G01X1442543Y1121120D02*
X1439047Y1121082D01*
G01X1441235Y1121104D02*
X1442772Y1121120D01*
G01X1442543Y1117970D02*
X1441007Y1117954D01*
G01X1442543Y1117970D02*
X1439047Y1117932D01*
G01X1441235Y1117954D02*
X1442772Y1117970D01*
G01X1442543Y1114821D02*
X1441007Y1114804D01*
G01X1442543Y1114821D02*
X1439047Y1114783D01*
G01X1441235Y1114804D02*
X1442772Y1114821D01*
G01X1439047Y1136830D02*
X1440094Y1136842D01*
G01X1438785Y1136830D02*
X1436420Y1136804D01*
G01X1437751Y1136816D02*
X1439047Y1136830D01*
G01Y1133680D02*
X1440094Y1133692D01*
G01X1438785Y1133680D02*
X1436420Y1133654D01*
G01X1437751Y1133666D02*
X1439047Y1133680D01*
G01Y1130531D02*
X1440094Y1130542D01*
G01X1438785Y1130531D02*
X1436420Y1130505D01*
G01X1437751Y1130516D02*
X1439047Y1130531D01*
G01Y1127381D02*
X1440094Y1127393D01*
G01X1438785Y1127381D02*
X1436420Y1127355D01*
G01X1437751Y1127367D02*
X1439047Y1127381D01*
G01Y1124232D02*
X1440094Y1124243D01*
G01X1438785Y1124232D02*
X1436420Y1124205D01*
G01X1437751Y1124217D02*
X1439047Y1124232D01*
G01Y1121082D02*
X1440094Y1121094D01*
G01X1438785Y1121082D02*
X1436420Y1121056D01*
G01X1437751Y1121068D02*
X1439047Y1121082D01*
G01Y1117932D02*
X1440094Y1117944D01*
G01X1438785Y1117932D02*
X1436420Y1117906D01*
G01X1437751Y1117918D02*
X1439047Y1117932D01*
G01Y1114783D02*
X1440094Y1114794D01*
G01X1438785Y1114783D02*
X1436420Y1114757D01*
G01X1437751Y1114768D02*
X1439047Y1114783D01*
G01Y1123323D02*
X1442543Y1123285D01*
G01X1437751Y1123338D02*
X1441007Y1123302D01*
G01X1439047Y1120174D02*
X1442543Y1120136D01*
G01X1437751Y1120188D02*
X1441007Y1120152D01*
G01X1439047Y1117024D02*
X1442543Y1116986D01*
G01X1437751Y1117038D02*
X1441007Y1117003D01*
G01X1439047Y1113874D02*
X1442543Y1113837D01*
G01X1437751Y1113889D02*
X1441007Y1113853D01*
G01X1439047Y1110725D02*
X1442543Y1110687D01*
G01X1437751Y1110739D02*
X1441007Y1110703D01*
G01X1439047Y1107575D02*
X1442543Y1107537D01*
G01X1437751Y1107590D02*
X1441007Y1107554D01*
G01X1439047Y1104426D02*
X1442543Y1104388D01*
G01X1437751Y1104440D02*
X1441007Y1104404D01*
G01X1439047Y1101276D02*
X1442543Y1101238D01*
G01X1437751Y1101290D02*
X1441007Y1101255D01*
G01X1439047Y1098126D02*
X1442543Y1098088D01*
G01X1437751Y1098141D02*
X1441007Y1098105D01*
G01X1439047Y1094977D02*
X1442543Y1094939D01*
G01X1437751Y1094991D02*
X1441007Y1094955D01*
G01X1439047Y1091827D02*
X1442543Y1091789D01*
G01X1437751Y1091842D02*
X1441007Y1091806D01*
G01X1439047Y1088678D02*
X1442543Y1088640D01*
G01X1437751Y1088692D02*
X1441007Y1088656D01*
G01X1439047Y1085528D02*
X1442543Y1085490D01*
G01X1437751Y1085542D02*
X1441007Y1085507D01*
G01X1439047Y1082378D02*
X1442543Y1082340D01*
G01X1437751Y1082393D02*
X1441007Y1082357D01*
G01X1439047Y1079229D02*
X1442543Y1079191D01*
G01X1437751Y1079243D02*
X1441007Y1079207D01*
G01X1439047Y1076079D02*
X1442543Y1076041D01*
G01X1437751Y1076094D02*
X1441007Y1076058D01*
G01X1439047Y1072930D02*
X1442543Y1072892D01*
G01X1437751Y1072944D02*
X1441007Y1072908D01*
G01X1439047Y1069780D02*
X1442543Y1069742D01*
G01X1437751Y1069794D02*
X1441007Y1069758D01*
G01X1438785Y1123323D02*
X1436420Y1123349D01*
G01X1438785Y1120174D02*
X1436420Y1120200D01*
G01X1438785Y1117024D02*
X1436420Y1117050D01*
G01X1438785Y1113875D02*
X1436420Y1113901D01*
G01X1438785Y1110725D02*
X1436420Y1110751D01*
G01X1438785Y1107575D02*
X1436420Y1107601D01*
G01X1438785Y1104426D02*
X1436420Y1104452D01*
G01X1438785Y1101276D02*
X1436420Y1101302D01*
G01X1438785Y1098127D02*
X1436420Y1098153D01*
G01X1438785Y1094977D02*
X1436420Y1095003D01*
G01X1438785Y1091827D02*
X1436420Y1091853D01*
G01X1438785Y1088678D02*
X1436420Y1088704D01*
G01X1438785Y1085528D02*
X1436420Y1085554D01*
G01X1438785Y1082378D02*
X1436420Y1082405D01*
G01X1438785Y1079229D02*
X1436420Y1079255D01*
G01X1438785Y1076079D02*
X1436420Y1076105D01*
G01X1438785Y1072930D02*
X1436420Y1072956D01*
G01X1438785Y1069780D02*
X1436420Y1069806D01*
G01X1441235Y1123302D02*
X1442772Y1123285D01*
G01X1441235Y1120152D02*
X1442772Y1120136D01*
G01X1441235Y1117003D02*
X1442772Y1116986D01*
G01X1441235Y1113853D02*
X1442772Y1113837D01*
G01X1441235Y1110703D02*
X1442772Y1110687D01*
G01X1441235Y1107554D02*
X1442772Y1107537D01*
G01X1441235Y1104404D02*
X1442772Y1104388D01*
G01X1441235Y1101255D02*
X1442772Y1101238D01*
G01X1441235Y1098105D02*
X1442772Y1098088D01*
G01X1441235Y1094955D02*
X1442772Y1094939D01*
G01X1441235Y1091806D02*
X1442772Y1091789D01*
G01X1441235Y1088656D02*
X1442772Y1088640D01*
G01X1441235Y1085507D02*
X1442772Y1085490D01*
G01X1441235Y1082357D02*
X1442772Y1082340D01*
G01X1441235Y1079207D02*
X1442772Y1079191D01*
G01X1441235Y1076058D02*
X1442772Y1076041D01*
G01X1441235Y1072908D02*
X1442772Y1072892D01*
G01X1441235Y1069758D02*
X1442772Y1069742D01*
G01X1441235Y1123302D02*
X1438785Y1123323D01*
G01X1437751Y1123338D02*
X1436420Y1123349D01*
G01X1441235Y1120152D02*
X1438785Y1120174D01*
G01X1437751Y1120188D02*
X1436420Y1120200D01*
G01X1441235Y1117003D02*
X1438785Y1117024D01*
G01X1437751Y1117038D02*
X1436420Y1117050D01*
G01X1441235Y1113853D02*
X1438785Y1113875D01*
G01X1437751Y1113889D02*
X1436420Y1113901D01*
G01X1441235Y1110703D02*
X1438785Y1110725D01*
G01X1437751Y1110739D02*
X1436420Y1110751D01*
G01X1441235Y1107554D02*
X1438785Y1107575D01*
G01X1437751Y1107590D02*
X1436420Y1107601D01*
G01X1441235Y1104404D02*
X1438785Y1104426D01*
G01X1437751Y1104440D02*
X1436420Y1104452D01*
G01X1441235Y1101255D02*
X1438785Y1101276D01*
G01X1437751Y1101290D02*
X1436420Y1101302D01*
G01X1441235Y1098105D02*
X1438785Y1098127D01*
G01X1437751Y1098141D02*
X1436420Y1098153D01*
G01X1441235Y1094955D02*
X1438785Y1094977D01*
G01X1437751Y1094991D02*
X1436420Y1095003D01*
G01X1441235Y1091806D02*
X1438785Y1091827D01*
G01X1437751Y1091842D02*
X1436420Y1091853D01*
G01X1441235Y1088656D02*
X1438785Y1088678D01*
G01X1437751Y1088692D02*
X1436420Y1088704D01*
G01X1441235Y1085507D02*
X1438785Y1085528D01*
G01X1437751Y1085542D02*
X1436420Y1085554D01*
G01X1441235Y1082357D02*
X1438785Y1082378D01*
G01X1437751Y1082393D02*
X1436420Y1082405D01*
G01X1441235Y1079207D02*
X1438785Y1079229D01*
G01X1437751Y1079243D02*
X1436420Y1079255D01*
G01X1441235Y1076058D02*
X1438785Y1076079D01*
G01X1437751Y1076094D02*
X1436420Y1076105D01*
G01X1441235Y1072908D02*
X1438785Y1072930D01*
G01X1437751Y1072944D02*
X1436420Y1072956D01*
G01X1441235Y1069758D02*
X1438785Y1069780D01*
G01X1437751Y1069794D02*
X1436420Y1069806D01*
G01X1439047Y1120174D02*
X1438785D01*
G01X1441235Y1120152D02*
X1441007D01*
G01X1441235Y1117954D02*
X1441007D01*
G01X1439047Y1117932D02*
X1438785D01*
G01X1439047Y1117024D02*
X1438785D01*
G01X1441235Y1117003D02*
X1441007D01*
G01X1441235Y1114804D02*
X1441007D01*
G01X1439047Y1114783D02*
X1438785D01*
G01X1439047Y1113875D02*
X1438785D01*
G01X1441235Y1113853D02*
X1441007D01*
G01X1441235Y1111655D02*
X1441007D01*
G01X1439047Y1111633D02*
X1438785D01*
G01X1439047Y1110725D02*
X1438785D01*
G01X1441235Y1110703D02*
X1441007D01*
G01X1441235Y1108505D02*
X1441007D01*
G01X1439047Y1108484D02*
X1438785D01*
G01X1439047Y1107575D02*
X1438785D01*
G01X1441235Y1107554D02*
X1441007D01*
G01X1441235Y1105355D02*
X1441007D01*
G01X1439047Y1105334D02*
X1438785D01*
G01X1439047Y1104426D02*
X1438785D01*
G01X1441235Y1104404D02*
X1441007D01*
G01X1441235Y1102206D02*
X1441007D01*
G01X1439047Y1102184D02*
X1438785D01*
G01X1439047Y1101276D02*
X1438785D01*
G01X1441235Y1101255D02*
X1441007D01*
G01X1441235Y1099056D02*
X1441007D01*
G01X1439047Y1099035D02*
X1438785D01*
G01X1439047Y1098127D02*
X1438785D01*
G01X1441235Y1098105D02*
X1441007D01*
G01Y1095907D02*
X1441235D01*
G01X1439047Y1095885D02*
X1438785D01*
G01X1439047Y1094977D02*
X1438785D01*
G01X1441235Y1094955D02*
X1441007D01*
G01X1441235Y1092757D02*
X1441007D01*
G01X1439047Y1092735D02*
X1438785D01*
G01X1439047Y1091827D02*
X1438785D01*
G01X1441235Y1091806D02*
X1441007D01*
G01X1441235Y1089607D02*
X1441007D01*
G01X1438785Y1089586D02*
X1439047D01*
G01Y1088678D02*
X1438785D01*
G01X1441235Y1088656D02*
X1441007D01*
G01X1441235Y1086458D02*
X1441007D01*
G01X1439047Y1086436D02*
X1438785D01*
G01X1439047Y1085528D02*
X1438785D01*
G01X1441235Y1085507D02*
X1441007D01*
G01X1441235Y1083308D02*
X1441007D01*
G01X1439047Y1083287D02*
X1438785D01*
G01X1439047Y1082378D02*
X1438785D01*
G01X1441235Y1082357D02*
X1441007D01*
G01X1441235Y1080159D02*
X1441007D01*
G01X1439047Y1080137D02*
X1438785D01*
G01X1439047Y1079229D02*
X1438785D01*
G01X1441235Y1079207D02*
X1441007D01*
G01X1441235Y1077009D02*
X1441007D01*
G01X1439047Y1076987D02*
X1438785D01*
G01X1439047Y1076079D02*
X1438785D01*
G01X1441235Y1076058D02*
X1441007D01*
G01X1441235Y1073859D02*
X1441007D01*
G01X1439047Y1073838D02*
X1438785D01*
G01X1439047Y1072930D02*
X1438785D01*
G01X1441235Y1072908D02*
X1441007D01*
G01X1441235Y1070710D02*
X1441007D01*
G01X1439047Y1070688D02*
X1438785D01*
G01X1439047Y1069780D02*
X1438785D01*
G01X1441235Y1069758D02*
X1441007D01*
G01X1440094Y1114794D02*
X1438785Y1114783D01*
G01X1441235Y1114804D02*
X1440094Y1114794D01*
G01Y1111645D02*
X1438785Y1111633D01*
G01X1441235Y1111655D02*
X1440094Y1111645D01*
G01Y1108495D02*
X1438785Y1108484D01*
G01X1441235Y1108505D02*
X1440094Y1108495D01*
G01Y1105345D02*
X1438785Y1105334D01*
G01X1441235Y1105355D02*
X1440094Y1105345D01*
G01Y1102196D02*
X1438785Y1102184D01*
G01X1441235Y1102206D02*
X1440094Y1102196D01*
G01Y1099046D02*
X1438785Y1099035D01*
G01X1441235Y1099056D02*
X1440094Y1099046D01*
G01Y1095897D02*
X1438785Y1095885D01*
G01X1441235Y1095907D02*
X1440094Y1095897D01*
G01Y1092747D02*
X1438785Y1092735D01*
G01X1441235Y1092757D02*
X1440094Y1092747D01*
G01Y1089597D02*
X1438785Y1089586D01*
G01X1441235Y1089607D02*
X1440094Y1089597D01*
G01Y1086448D02*
X1438785Y1086436D01*
G01X1441235Y1086458D02*
X1440094Y1086448D01*
G01Y1083298D02*
X1438785Y1083287D01*
G01X1441235Y1083308D02*
X1440094Y1083298D01*
G01Y1080149D02*
X1438785Y1080137D01*
G01X1441235Y1080159D02*
X1440094Y1080149D01*
G01Y1076999D02*
X1438785Y1076987D01*
G01X1441235Y1077009D02*
X1440094Y1076999D01*
G01Y1073849D02*
X1438785Y1073838D01*
G01X1441235Y1073859D02*
X1440094Y1073849D01*
G01Y1070700D02*
X1438785Y1070688D01*
G01X1441235Y1070710D02*
X1440094Y1070700D01*
G01X1437751Y1114768D02*
X1436420Y1114757D01*
G01X1437751Y1111619D02*
X1436420Y1111607D01*
G01X1437751Y1108469D02*
X1436420Y1108457D01*
G01X1437751Y1105320D02*
X1436420Y1105308D01*
G01X1437751Y1102170D02*
X1436420Y1102158D01*
G01X1437751Y1099020D02*
X1436420Y1099009D01*
G01X1437751Y1095871D02*
X1436420Y1095859D01*
G01X1437751Y1092721D02*
X1436420Y1092709D01*
G01X1437751Y1089572D02*
X1436420Y1089560D01*
G01X1437751Y1086422D02*
X1436420Y1086410D01*
G01X1437751Y1083272D02*
X1436420Y1083261D01*
G01X1437751Y1080123D02*
X1436420Y1080111D01*
G01X1437751Y1076973D02*
X1436420Y1076961D01*
G01X1437751Y1073824D02*
X1436420Y1073812D01*
G01X1437751Y1070674D02*
X1436420Y1070662D01*
G01X1442543Y1111671D02*
X1441007Y1111655D01*
G01X1442543Y1111671D02*
X1439047Y1111633D01*
G01X1441235Y1111655D02*
X1442772Y1111671D01*
G01X1442543Y1108522D02*
X1441007Y1108505D01*
G01X1442543Y1108522D02*
X1439047Y1108484D01*
G01X1441235Y1108505D02*
X1442772Y1108522D01*
G01X1442543Y1105372D02*
X1441007Y1105355D01*
G01X1442543Y1105372D02*
X1439047Y1105334D01*
G01X1441235Y1105355D02*
X1442772Y1105372D01*
G01X1442543Y1102222D02*
X1441007Y1102206D01*
G01X1442543Y1102222D02*
X1439047Y1102184D01*
G01X1441235Y1102206D02*
X1442772Y1102222D01*
G01X1442543Y1099073D02*
X1441007Y1099056D01*
G01X1442543Y1099073D02*
X1439047Y1099035D01*
G01X1441235Y1099056D02*
X1442772Y1099073D01*
G01X1442543Y1095923D02*
X1441007Y1095907D01*
G01X1442543Y1095923D02*
X1439047Y1095885D01*
G01X1441235Y1095907D02*
X1442772Y1095923D01*
G01X1442543Y1092774D02*
X1441007Y1092757D01*
G01X1442543Y1092774D02*
X1439047Y1092736D01*
G01X1441235Y1092757D02*
X1442772Y1092774D01*
G01X1442543Y1089624D02*
X1441007Y1089607D01*
G01X1442543Y1089624D02*
X1439047Y1089586D01*
G01X1441235Y1089607D02*
X1442772Y1089624D01*
G01X1442543Y1086474D02*
X1441007Y1086458D01*
G01X1442543Y1086474D02*
X1439047Y1086436D01*
G01X1441235Y1086458D02*
X1442772Y1086474D01*
G01X1442543Y1083325D02*
X1441007Y1083308D01*
G01X1442543Y1083325D02*
X1439047Y1083287D01*
G01X1441235Y1083308D02*
X1442772Y1083325D01*
G01X1442543Y1080175D02*
X1441007Y1080159D01*
G01X1442543Y1080175D02*
X1439047Y1080137D01*
G01X1441235Y1080159D02*
X1442772Y1080175D01*
G01X1442543Y1077025D02*
X1441007Y1077009D01*
G01X1442543Y1077025D02*
X1439047Y1076988D01*
G01X1441235Y1077009D02*
X1442772Y1077025D01*
G01X1442543Y1073876D02*
X1441007Y1073859D01*
G01X1442543Y1073876D02*
X1439047Y1073838D01*
G01X1441235Y1073859D02*
X1442772Y1073876D01*
G01X1442543Y1070726D02*
X1441007Y1070710D01*
G01X1442543Y1070726D02*
X1439047Y1070688D01*
G01X1441235Y1070710D02*
X1442772Y1070726D01*
G01X1439047Y1111633D02*
X1440094Y1111645D01*
G01X1438785Y1111633D02*
X1436420Y1111607D01*
G01X1437751Y1111619D02*
X1439047Y1111633D01*
G01Y1108484D02*
X1440094Y1108495D01*
G01X1438785Y1108484D02*
X1436420Y1108457D01*
G01X1437751Y1108469D02*
X1439047Y1108484D01*
G01Y1105334D02*
X1440094Y1105345D01*
G01X1438785Y1105334D02*
X1436420Y1105308D01*
G01X1437751Y1105320D02*
X1439047Y1105334D01*
G01Y1102184D02*
X1440094Y1102196D01*
G01X1438785Y1102184D02*
X1436420Y1102158D01*
G01X1437751Y1102170D02*
X1439047Y1102184D01*
G01Y1099035D02*
X1440094Y1099046D01*
G01X1438785Y1099035D02*
X1436420Y1099009D01*
G01X1437751Y1099020D02*
X1439047Y1099035D01*
G01Y1095885D02*
X1440094Y1095897D01*
G01X1438785Y1095885D02*
X1436420Y1095859D01*
G01X1437751Y1095871D02*
X1439047Y1095885D01*
G01Y1092735D02*
X1440094Y1092747D01*
G01X1438785Y1092735D02*
X1436420Y1092709D01*
G01X1437751Y1092721D02*
X1439047Y1092735D01*
G01Y1089586D02*
X1440094Y1089597D01*
G01X1438785Y1089586D02*
X1436420Y1089560D01*
G01X1437751Y1089572D02*
X1439047Y1089586D01*
G01Y1086436D02*
X1440094Y1086448D01*
G01X1438785Y1086436D02*
X1436420Y1086410D01*
G01X1437751Y1086422D02*
X1439047Y1086436D01*
G01Y1083287D02*
X1440094Y1083298D01*
G01X1438785Y1083287D02*
X1436420Y1083261D01*
G01X1437751Y1083272D02*
X1439047Y1083287D01*
G01Y1080137D02*
X1440094Y1080149D01*
G01X1438785Y1080137D02*
X1436420Y1080111D01*
G01X1437751Y1080123D02*
X1439047Y1080137D01*
G01Y1076987D02*
X1440094Y1076999D01*
G01X1438785Y1076987D02*
X1436420Y1076961D01*
G01X1437751Y1076973D02*
X1439047Y1076987D01*
G01Y1073838D02*
X1440094Y1073849D01*
G01X1438785Y1073838D02*
X1436420Y1073812D01*
G01X1437751Y1073824D02*
X1439047Y1073838D01*
G01Y1070688D02*
X1440094Y1070700D01*
G01X1438785Y1070688D02*
X1436420Y1070662D01*
G01X1437751Y1070674D02*
X1439047Y1070688D01*
G01X1441235Y1070710D02*
Y1069758D01*
G01Y1073859D02*
Y1072908D01*
G01Y1077009D02*
Y1076058D01*
G01Y1083308D02*
Y1082357D01*
G01Y1080159D02*
Y1079207D01*
G01Y1086458D02*
Y1085507D01*
G01Y1092757D02*
Y1091806D01*
G01Y1089607D02*
Y1088656D01*
G01Y1095907D02*
Y1094955D01*
G01Y1102206D02*
Y1101255D01*
G01Y1099056D02*
Y1098105D01*
G01Y1105355D02*
Y1104404D01*
G01Y1111655D02*
Y1110703D01*
G01Y1108505D02*
Y1107554D01*
G01Y1114804D02*
Y1113853D01*
G01Y1121103D02*
Y1120152D01*
G01Y1117954D02*
Y1117003D01*
G01Y1124253D02*
Y1123302D01*
G01Y1130552D02*
Y1129601D01*
G01Y1127403D02*
Y1126451D01*
G01Y1133702D02*
Y1132751D01*
G01Y1136851D02*
Y1135900D01*
G01X1441007Y1070710D02*
Y1069758D01*
G01Y1073859D02*
Y1072908D01*
G01Y1077009D02*
Y1076058D01*
G01Y1083308D02*
Y1082357D01*
G01Y1080159D02*
Y1079207D01*
G01Y1086458D02*
Y1085507D01*
G01Y1092757D02*
Y1091806D01*
G01Y1089607D02*
Y1088656D01*
G01Y1095907D02*
Y1094955D01*
G01Y1102206D02*
Y1101255D01*
G01Y1099056D02*
Y1098105D01*
G01Y1105355D02*
Y1104404D01*
G01Y1111655D02*
Y1110703D01*
G01Y1108505D02*
Y1107554D01*
G01Y1114804D02*
Y1113853D01*
G01Y1121104D02*
Y1120152D01*
G01Y1117954D02*
Y1117003D01*
G01Y1124253D02*
Y1123302D01*
G01Y1130552D02*
Y1129601D01*
G01Y1127403D02*
Y1126451D01*
G01Y1133702D02*
Y1132751D01*
G01Y1136852D02*
Y1135900D01*
G01X1439047Y1070688D02*
Y1069780D01*
G01Y1073838D02*
Y1072930D01*
G01Y1080137D02*
Y1079229D01*
G01Y1076988D02*
Y1076079D01*
G01Y1083287D02*
Y1082378D01*
G01Y1086436D02*
Y1085528D01*
G01Y1092736D02*
Y1091827D01*
G01Y1089586D02*
Y1088678D01*
G01Y1095885D02*
Y1094977D01*
G01Y1102184D02*
Y1101276D01*
G01Y1099035D02*
Y1098126D01*
G01Y1105334D02*
Y1104426D01*
G01Y1111633D02*
Y1110725D01*
G01Y1108484D02*
Y1107575D01*
G01Y1114783D02*
Y1113874D01*
G01Y1121082D02*
Y1120174D01*
G01Y1117932D02*
Y1117024D01*
G01Y1124232D02*
Y1123323D01*
G01Y1130531D02*
Y1129623D01*
G01Y1127381D02*
Y1126473D01*
G01Y1133680D02*
Y1132772D01*
G01Y1136830D02*
Y1135922D01*
G01X1438785Y1070688D02*
Y1069780D01*
G01Y1073838D02*
Y1072930D01*
G01Y1080137D02*
Y1079229D01*
G01Y1076988D02*
Y1076079D01*
G01Y1083287D02*
Y1082378D01*
G01Y1086436D02*
Y1085528D01*
G01Y1092736D02*
Y1091827D01*
G01Y1089586D02*
Y1088678D01*
G01Y1095885D02*
Y1094977D01*
G01Y1102184D02*
Y1101276D01*
G01Y1099035D02*
Y1098127D01*
G01Y1105334D02*
Y1104426D01*
G01Y1111633D02*
Y1110725D01*
G01Y1108484D02*
Y1107575D01*
G01Y1114783D02*
Y1113875D01*
G01Y1121082D02*
Y1120174D01*
G01Y1117932D02*
Y1117024D01*
G01Y1124232D02*
Y1123323D01*
G01Y1130531D02*
Y1129623D01*
G01Y1127381D02*
Y1126473D01*
G01Y1133680D02*
Y1132772D01*
G01Y1136830D02*
Y1135922D01*
G01X1437751Y1070668D02*
Y1069800D01*
G01Y1073818D02*
Y1072950D01*
G01Y1080117D02*
Y1079249D01*
G01Y1076967D02*
Y1076099D01*
G01Y1083267D02*
Y1082399D01*
G01Y1086416D02*
Y1085548D01*
G01Y1092715D02*
Y1091847D01*
G01Y1089566D02*
Y1088698D01*
G01Y1095865D02*
Y1094997D01*
G01Y1102164D02*
Y1101296D01*
G01Y1099015D02*
Y1098147D01*
G01Y1105314D02*
Y1104446D01*
G01Y1111613D02*
Y1110745D01*
G01Y1108463D02*
Y1107596D01*
G01Y1114763D02*
Y1113895D01*
G01Y1121062D02*
Y1120194D01*
G01Y1117912D02*
Y1117044D01*
G01Y1124211D02*
Y1123344D01*
G01Y1130511D02*
Y1129643D01*
G01Y1127361D02*
Y1126493D01*
G01Y1133660D02*
Y1132792D01*
G01Y1136810D02*
Y1135942D01*
G01X1436420Y1070662D02*
Y1069806D01*
G01Y1073812D02*
Y1072956D01*
G01Y1080111D02*
Y1079255D01*
G01Y1076961D02*
Y1076105D01*
G01Y1083261D02*
Y1082405D01*
G01Y1086410D02*
Y1085554D01*
G01Y1092709D02*
Y1091853D01*
G01Y1089560D02*
Y1088704D01*
G01Y1095859D02*
Y1095003D01*
G01Y1102158D02*
Y1101302D01*
G01Y1099009D02*
Y1098153D01*
G01Y1105308D02*
Y1104452D01*
G01Y1111607D02*
Y1110751D01*
G01Y1108457D02*
Y1107601D01*
G01Y1114757D02*
Y1113901D01*
G01Y1121056D02*
Y1120200D01*
G01Y1117906D02*
Y1117050D01*
G01Y1124205D02*
Y1123349D01*
G01Y1130505D02*
Y1129649D01*
G01Y1127355D02*
Y1126499D01*
G01Y1133654D02*
Y1132798D01*
G01Y1136804D02*
Y1135948D01*
G01X1443073Y1067872D02*
X1442684Y1067664D01*
G01X1443243Y1067872D02*
X1442772Y1067577D01*
G01X1442684Y1067664D02*
X1442543Y1067577D01*
G01X1457732Y1068266D02*
X1457220D01*
G01X1444212Y1067872D02*
X1443073D01*
G01X1469631Y1067675D02*
X1457535D01*
G01X1442772Y1067577D02*
X1442543D01*
G01X1470921Y1067419D02*
X1469507D01*
G01X1470921Y1066750D02*
X1469507D01*
G01X1442772Y1066592D02*
X1442543D01*
G01X1469631Y1066494D02*
X1457535D01*
G01X1444212Y1066297D02*
X1443073D01*
G01X1469507Y1066750D02*
X1469278Y1066494D01*
G01X1469855Y1066750D02*
X1469636Y1066480D01*
G01X1442772Y1066592D02*
X1443243Y1066297D01*
G01X1442543Y1066592D02*
X1442684Y1066505D01*
G01D02*
X1443073Y1066297D01*
G01X1469636Y1067689D02*
X1469855Y1067419D01*
G01X1469278Y1067675D02*
X1469507Y1067419D01*
G01X1470921D02*
Y1066750D01*
G01X1470574Y1067419D02*
Y1066750D01*
G01X1469631Y1067675D02*
Y1066494D01*
G01X1469278Y1067675D02*
Y1066494D01*
G01X1467296Y1067675D02*
Y1066494D01*
G01X1467186Y1067675D02*
Y1066494D01*
G01X1458405Y1067675D02*
Y1066494D01*
G01X1458295Y1067675D02*
Y1066494D01*
G01X1457929Y1067675D02*
Y1066494D01*
G01X1457732Y1068266D02*
Y1067675D01*
G01X1457535Y1068266D02*
Y1067675D01*
G01X1444212Y1067872D02*
Y1066297D01*
G01X1442684Y1067664D02*
Y1066505D01*
G01X1444212Y1138738D02*
X1443073D01*
G01X1457732Y1138344D02*
X1457220D01*
G01X1457732Y1137557D02*
X1457220D01*
G01X1444212Y1137163D02*
X1443073D01*
G01X1469631Y1136966D02*
X1457535D01*
G01X1442772Y1136868D02*
X1442543D01*
G01X1470921Y1136711D02*
X1469507D01*
G01X1470921Y1136041D02*
X1469507D01*
G01X1442772Y1135884D02*
X1442543D01*
G01X1469631Y1135785D02*
X1457535D01*
G01X1444212Y1135588D02*
X1443073D01*
G01X1457732Y1135195D02*
X1457220D01*
G01X1457732Y1134407D02*
X1457220D01*
G01X1444212Y1134014D02*
X1443073D01*
G01X1469631Y1133817D02*
X1457535D01*
G01X1442772Y1133718D02*
X1442543D01*
G01X1470921Y1133561D02*
X1469507D01*
G01X1470921Y1132892D02*
X1469507D01*
G01X1442772Y1132734D02*
X1442543D01*
G01X1469631Y1132636D02*
X1457535D01*
G01X1444212Y1132439D02*
X1443073D01*
G01X1457732Y1132045D02*
X1457220D01*
G01X1457732Y1131258D02*
X1457220D01*
G01X1444212Y1130864D02*
X1443073D01*
G01X1469631Y1130667D02*
X1457535D01*
G01X1442772Y1130569D02*
X1442543D01*
G01X1470921Y1130411D02*
X1469507D01*
G01X1470921Y1129742D02*
X1469507D01*
G01X1442772Y1129585D02*
X1442543D01*
G01X1469631Y1129486D02*
X1457535D01*
G01X1444212Y1129289D02*
X1443073D01*
G01X1457732Y1128896D02*
X1457220D01*
G01X1457732Y1128108D02*
X1457220D01*
G01X1444212Y1127714D02*
X1443073D01*
G01X1469631Y1127518D02*
X1457535D01*
G01X1442772Y1127419D02*
X1442543D01*
G01X1470921Y1127262D02*
X1469507D01*
G01X1470921Y1126592D02*
X1469507D01*
G01X1442772Y1126435D02*
X1442543D01*
G01X1469631Y1126337D02*
X1457535D01*
G01X1444212Y1126140D02*
X1443073D01*
G01X1457732Y1125746D02*
X1457220D01*
G01X1457732Y1124959D02*
X1457220D01*
G01X1444212Y1124565D02*
X1443073D01*
G01X1469631Y1124368D02*
X1457535D01*
G01X1442772Y1124270D02*
X1442543D01*
G01X1470921Y1124112D02*
X1469507D01*
G01X1470921Y1123443D02*
X1469507D01*
G01X1442772Y1123285D02*
X1442543D01*
G01X1469631Y1123187D02*
X1457535D01*
G01X1444212Y1122990D02*
X1443073D01*
G01X1457732Y1122596D02*
X1457220D01*
G01X1457732Y1121809D02*
X1457220D01*
G01X1444212Y1121415D02*
X1443073D01*
G01X1469631Y1121218D02*
X1457535D01*
G01X1442772Y1121120D02*
X1442543D01*
G01X1470921Y1120963D02*
X1469507D01*
G01X1470921Y1120293D02*
X1469507D01*
G01X1443073Y1071022D02*
X1442684Y1070814D01*
G01X1443073Y1074171D02*
X1442684Y1073964D01*
G01X1443073Y1077321D02*
X1442684Y1077113D01*
G01X1443073Y1080470D02*
X1442684Y1080263D01*
G01X1443073Y1083620D02*
X1442684Y1083413D01*
G01X1443073Y1086770D02*
X1442684Y1086562D01*
G01X1443073Y1089919D02*
X1442684Y1089712D01*
G01X1443073Y1093069D02*
X1442684Y1092861D01*
G01X1443073Y1096218D02*
X1442684Y1096011D01*
G01X1443073Y1099368D02*
X1442684Y1099161D01*
G01X1443073Y1102518D02*
X1442684Y1102310D01*
G01X1443073Y1105667D02*
X1442684Y1105460D01*
G01X1443073Y1108817D02*
X1442684Y1108609D01*
G01X1443073Y1111966D02*
X1442684Y1111759D01*
G01X1443073Y1115116D02*
X1442684Y1114909D01*
G01X1443073Y1118266D02*
X1442684Y1118058D01*
G01X1443073Y1121415D02*
X1442684Y1121208D01*
G01X1443073Y1124565D02*
X1442684Y1124357D01*
G01X1443073Y1127714D02*
X1442684Y1127507D01*
G01X1443073Y1130864D02*
X1442684Y1130657D01*
G01X1443073Y1134014D02*
X1442684Y1133806D01*
G01X1443073Y1137163D02*
X1442684Y1136956D01*
G01X1496457Y1117057D02*
X1493047Y1115088D01*
G01X1443243Y1071022D02*
X1442772Y1070726D01*
G01X1442684Y1070814D02*
X1442543Y1070726D01*
G01X1443243Y1074171D02*
X1442772Y1073876D01*
G01X1442684Y1073964D02*
X1442543Y1073876D01*
G01X1443243Y1077321D02*
X1442772Y1077025D01*
G01X1442684Y1077113D02*
X1442543Y1077025D01*
G01X1443243Y1080470D02*
X1442772Y1080175D01*
G01X1442684Y1080263D02*
X1442543Y1080175D01*
G01X1443243Y1083620D02*
X1442772Y1083325D01*
G01X1442684Y1083413D02*
X1442543Y1083325D01*
G01X1443243Y1086770D02*
X1442772Y1086474D01*
G01X1442684Y1086562D02*
X1442543Y1086474D01*
G01X1443243Y1089919D02*
X1442772Y1089624D01*
G01X1442684Y1089712D02*
X1442543Y1089624D01*
G01X1443243Y1093069D02*
X1442772Y1092774D01*
G01X1442684Y1092861D02*
X1442543Y1092774D01*
G01X1443243Y1096218D02*
X1442772Y1095923D01*
G01X1442684Y1096011D02*
X1442543Y1095923D01*
G01X1443243Y1099368D02*
X1442772Y1099073D01*
G01X1442684Y1099161D02*
X1442543Y1099073D01*
G01X1443243Y1102518D02*
X1442772Y1102222D01*
G01X1442684Y1102310D02*
X1442543Y1102222D01*
G01X1442772Y1120136D02*
X1442543D01*
G01X1469631Y1120037D02*
X1457535D01*
G01X1444212Y1119840D02*
X1443073D01*
G01X1457732Y1119447D02*
X1457220D01*
G01X1457732Y1118659D02*
X1457220D01*
G01X1444212Y1118266D02*
X1443073D01*
G01X1469631Y1118069D02*
X1457535D01*
G01X1442772Y1117970D02*
X1442543D01*
G01X1470921Y1117813D02*
X1469507D01*
G01X1470921Y1117144D02*
X1469507D01*
G01X1442772Y1116986D02*
X1442543D01*
G01X1469631Y1116888D02*
X1457535D01*
G01X1444212Y1116691D02*
X1443073D01*
G01X1457732Y1116297D02*
X1457220D01*
G01X1457732Y1115510D02*
X1457220D01*
G01X1444212Y1115116D02*
X1443073D01*
G01X1469631Y1114919D02*
X1457535D01*
G01X1442772Y1114821D02*
X1442543D01*
G01X1470921Y1114663D02*
X1469507D01*
G01X1470921Y1113994D02*
X1469507D01*
G01X1442772Y1113837D02*
X1442543D01*
G01X1469631Y1113738D02*
X1457535D01*
G01X1444212Y1113541D02*
X1443073D01*
G01X1457732Y1113148D02*
X1457220D01*
G01X1457732Y1112360D02*
X1457220D01*
G01X1444212Y1111966D02*
X1443073D01*
G01X1469631Y1111770D02*
X1457535D01*
G01X1442772Y1111671D02*
X1442543D01*
G01X1470921Y1111514D02*
X1469507D01*
G01X1470921Y1110844D02*
X1469507D01*
G01X1442772Y1110687D02*
X1442543D01*
G01X1469631Y1110588D02*
X1457535D01*
G01X1444212Y1110392D02*
X1443073D01*
G01X1457732Y1109998D02*
X1457220D01*
G01X1457732Y1109211D02*
X1457220D01*
G01X1444212Y1108817D02*
X1443073D01*
G01X1469631Y1108620D02*
X1457535D01*
G01X1442772Y1108522D02*
X1442543D01*
G01X1470921Y1108364D02*
X1469507D01*
G01X1470921Y1107695D02*
X1469507D01*
G01X1442772Y1107537D02*
X1442543D01*
G01X1469631Y1107439D02*
X1457535D01*
G01X1444212Y1107242D02*
X1443073D01*
G01X1457732Y1106848D02*
X1457220D01*
G01X1457732Y1106061D02*
X1457220D01*
G01X1444212Y1105667D02*
X1443073D01*
G01X1469631Y1105470D02*
X1457535D01*
G01X1442772Y1105372D02*
X1442543D01*
G01X1470921Y1105214D02*
X1469507D01*
G01X1470921Y1104545D02*
X1469507D01*
G01X1442772Y1104388D02*
X1442543D01*
G01X1469631Y1104289D02*
X1457535D01*
G01X1444212Y1104092D02*
X1443073D01*
G01X1457732Y1103699D02*
X1457220D01*
G01X1457732Y1102911D02*
X1457220D01*
G01X1444212Y1102518D02*
X1443073D01*
G01X1469631Y1102321D02*
X1457535D01*
G01X1442772Y1102222D02*
X1442543D01*
G01X1470921Y1102065D02*
X1469507D01*
G01X1470921Y1101396D02*
X1469507D01*
G01X1442772Y1101238D02*
X1442543D01*
G01X1469631Y1101140D02*
X1457535D01*
G01X1444212Y1100943D02*
X1443073D01*
G01X1457732Y1100549D02*
X1457220D01*
G01X1457732Y1099762D02*
X1457220D01*
G01X1444212Y1099368D02*
X1443073D01*
G01X1469631Y1099171D02*
X1457535D01*
G01X1442772Y1099073D02*
X1442543D01*
G01X1470921Y1098915D02*
X1469507D01*
G01X1470921Y1098246D02*
X1469507D01*
G01X1442772Y1098088D02*
X1442543D01*
G01X1469631Y1097990D02*
X1457535D01*
G01X1444212Y1097793D02*
X1443073D01*
G01X1457732Y1097400D02*
X1457220D01*
G01X1457732Y1096612D02*
X1457220D01*
G01X1444212Y1096218D02*
X1443073D01*
G01X1469631Y1096022D02*
X1457535D01*
G01X1442772Y1095923D02*
X1442543D01*
G01X1470921Y1095766D02*
X1469507D01*
G01X1470921Y1095096D02*
X1469507D01*
G01X1442772Y1094939D02*
X1442543D01*
G01X1469631Y1094840D02*
X1457535D01*
G01X1444212Y1094644D02*
X1443073D01*
G01X1457732Y1094250D02*
X1457220D01*
G01X1457732Y1093463D02*
X1457220D01*
G01X1444212Y1093069D02*
X1443073D01*
G01X1469631Y1092872D02*
X1457535D01*
G01X1442772Y1092774D02*
X1442543D01*
G01X1470921Y1092616D02*
X1469507D01*
G01X1470921Y1091947D02*
X1469507D01*
G01X1442772Y1091789D02*
X1442543D01*
G01X1469631Y1091691D02*
X1457535D01*
G01X1444212Y1091494D02*
X1443073D01*
G01X1457732Y1091100D02*
X1457220D01*
G01X1457732Y1090313D02*
X1457220D01*
G01X1444212Y1089919D02*
X1443073D01*
G01X1469631Y1089722D02*
X1457535D01*
G01X1442772Y1089624D02*
X1442543D01*
G01X1470921Y1089466D02*
X1469507D01*
G01X1470921Y1088797D02*
X1469507D01*
G01X1442772Y1088640D02*
X1442543D01*
G01X1469631Y1088541D02*
X1457535D01*
G01X1444212Y1088344D02*
X1443073D01*
G01X1457732Y1087951D02*
X1457220D01*
G01X1457732Y1087163D02*
X1457220D01*
G01X1444212Y1086770D02*
X1443073D01*
G01X1469631Y1086573D02*
X1457535D01*
G01X1442772Y1086474D02*
X1442543D01*
G01X1470921Y1086317D02*
X1469507D01*
G01X1470921Y1085648D02*
X1469507D01*
G01X1442772Y1085490D02*
X1442543D01*
G01X1469631Y1085392D02*
X1457535D01*
G01X1444212Y1085195D02*
X1443073D01*
G01X1457732Y1084801D02*
X1457220D01*
G01X1457732Y1084014D02*
X1457220D01*
G01X1444212Y1083620D02*
X1443073D01*
G01X1469631Y1083423D02*
X1457535D01*
G01X1442772Y1083325D02*
X1442543D01*
G01X1470921Y1083167D02*
X1469507D01*
G01X1470921Y1082498D02*
X1469507D01*
G01X1442772Y1082340D02*
X1442543D01*
G01X1469631Y1082242D02*
X1457535D01*
G01X1444212Y1082045D02*
X1443073D01*
G01X1457732Y1081651D02*
X1457220D01*
G01X1457732Y1080864D02*
X1457220D01*
G01X1444212Y1080470D02*
X1443073D01*
G01X1469631Y1080274D02*
X1457535D01*
G01X1442772Y1080175D02*
X1442543D01*
G01X1470921Y1080018D02*
X1469507D01*
G01X1470921Y1079348D02*
X1469507D01*
G01X1442772Y1079191D02*
X1442543D01*
G01X1469631Y1079092D02*
X1457535D01*
G01X1444212Y1078896D02*
X1443073D01*
G01X1457732Y1078502D02*
X1457220D01*
G01X1457732Y1077714D02*
X1457220D01*
G01X1444212Y1077321D02*
X1443073D01*
G01X1469631Y1077124D02*
X1457535D01*
G01X1442772Y1077025D02*
X1442543D01*
G01X1470921Y1076868D02*
X1469507D01*
G01X1470921Y1076199D02*
X1469507D01*
G01X1442772Y1076041D02*
X1442543D01*
G01X1469631Y1075943D02*
X1457535D01*
G01X1444212Y1075746D02*
X1443073D01*
G01X1457732Y1075352D02*
X1457220D01*
G01X1457732Y1074565D02*
X1457220D01*
G01X1444212Y1074171D02*
X1443073D01*
G01X1469631Y1073974D02*
X1457535D01*
G01X1442772Y1073876D02*
X1442543D01*
G01X1470921Y1073718D02*
X1469507D01*
G01X1470921Y1073049D02*
X1469507D01*
G01X1442772Y1072892D02*
X1442543D01*
G01X1469631Y1072793D02*
X1457535D01*
G01X1444212Y1072596D02*
X1443073D01*
G01X1457732Y1072203D02*
X1457220D01*
G01X1457732Y1071415D02*
X1457220D01*
G01X1444212Y1071022D02*
X1443073D01*
G01X1469631Y1070825D02*
X1457535D01*
G01X1442772Y1070726D02*
X1442543D01*
G01X1470921Y1070569D02*
X1469507D01*
G01X1470921Y1069900D02*
X1469507D01*
G01X1442772Y1069742D02*
X1442543D01*
G01X1469631Y1069644D02*
X1457535D01*
G01X1444212Y1069447D02*
X1443073D01*
G01X1457732Y1069053D02*
X1457220D01*
G01X1443243Y1105667D02*
X1442772Y1105372D01*
G01X1442684Y1105460D02*
X1442543Y1105372D01*
G01X1443243Y1108817D02*
X1442772Y1108522D01*
G01X1442684Y1108609D02*
X1442543Y1108522D01*
G01X1443243Y1111966D02*
X1442772Y1111671D01*
G01X1442684Y1111759D02*
X1442543Y1111671D01*
G01X1443243Y1115116D02*
X1442772Y1114821D01*
G01X1442684Y1114909D02*
X1442543Y1114821D01*
G01X1443243Y1118266D02*
X1442772Y1117970D01*
G01X1442684Y1118058D02*
X1442543Y1117970D01*
G01X1443243Y1121415D02*
X1442772Y1121120D01*
G01X1442684Y1121208D02*
X1442543Y1121120D01*
G01X1443243Y1124565D02*
X1442772Y1124270D01*
G01X1442684Y1124357D02*
X1442543Y1124270D01*
G01X1443243Y1127714D02*
X1442772Y1127419D01*
G01X1442684Y1127507D02*
X1442543Y1127419D01*
G01X1443243Y1130864D02*
X1442772Y1130569D01*
G01X1442684Y1130657D02*
X1442543Y1130569D01*
G01X1443243Y1134014D02*
X1442772Y1133718D01*
G01X1442684Y1133806D02*
X1442543Y1133718D01*
G01X1443243Y1137163D02*
X1442772Y1136868D01*
G01X1442684Y1136956D02*
X1442543Y1136868D01*
G01X1469507Y1069900D02*
X1469278Y1069644D01*
G01X1469507Y1073049D02*
X1469278Y1072793D01*
G01X1469507Y1076199D02*
X1469278Y1075943D01*
G01X1469507Y1079348D02*
X1469278Y1079092D01*
G01X1469507Y1082498D02*
X1469278Y1082242D01*
G01X1469507Y1085648D02*
X1469278Y1085392D01*
G01X1469507Y1088797D02*
X1469278Y1088541D01*
G01X1469507Y1091947D02*
X1469278Y1091691D01*
G01X1469507Y1095096D02*
X1469278Y1094840D01*
G01X1469507Y1098246D02*
X1469278Y1097990D01*
G01X1469507Y1101396D02*
X1469278Y1101140D01*
G01X1469507Y1104545D02*
X1469278Y1104289D01*
G01X1469507Y1107695D02*
X1469278Y1107439D01*
G01X1469507Y1110844D02*
X1469278Y1110588D01*
G01X1469507Y1113994D02*
X1469278Y1113738D01*
G01X1469507Y1117144D02*
X1469278Y1116888D01*
G01X1469507Y1120293D02*
X1469278Y1120037D01*
G01X1469507Y1123443D02*
X1469278Y1123187D01*
G01X1469507Y1126592D02*
X1469278Y1126337D01*
G01X1469507Y1129742D02*
X1469278Y1129486D01*
G01X1469507Y1132892D02*
X1469278Y1132636D01*
G01X1469507Y1136041D02*
X1469278Y1135785D01*
G01X1469507Y1139191D02*
X1469278Y1138935D01*
G01X1469855Y1069900D02*
X1469636Y1069629D01*
G01X1469855Y1073049D02*
X1469636Y1072779D01*
G01X1469855Y1076199D02*
X1469636Y1075929D01*
G01X1469855Y1079348D02*
X1469636Y1079078D01*
G01X1469855Y1082498D02*
X1469636Y1082228D01*
G01X1469855Y1085648D02*
X1469636Y1085378D01*
G01X1469855Y1088797D02*
X1469636Y1088527D01*
G01X1469855Y1091947D02*
X1469636Y1091677D01*
G01X1469855Y1095096D02*
X1469636Y1094826D01*
G01X1469855Y1098246D02*
X1469636Y1097976D01*
G01X1469855Y1101396D02*
X1469636Y1101126D01*
G01X1469855Y1104545D02*
X1469636Y1104275D01*
G01X1469855Y1107695D02*
X1469636Y1107425D01*
G01X1469855Y1110844D02*
X1469636Y1110574D01*
G01X1469855Y1113994D02*
X1469636Y1113724D01*
G01X1469855Y1117144D02*
X1469636Y1116874D01*
G01X1469855Y1120293D02*
X1469636Y1120023D01*
G01X1442684Y1138946D02*
X1443073Y1138738D01*
G01X1442684Y1135796D02*
X1443073Y1135588D01*
G01X1442684Y1132646D02*
X1443073Y1132439D01*
G01X1442684Y1129497D02*
X1443073Y1129289D01*
G01X1442684Y1126347D02*
X1443073Y1126140D01*
G01X1442684Y1123198D02*
X1443073Y1122990D01*
G01X1442684Y1120048D02*
X1443073Y1119840D01*
G01X1469855Y1123443D02*
X1469636Y1123173D01*
G01X1469855Y1126592D02*
X1469636Y1126322D01*
G01X1469855Y1129742D02*
X1469636Y1129472D01*
G01X1469855Y1132892D02*
X1469636Y1132622D01*
G01X1469855Y1136041D02*
X1469636Y1135771D01*
G01X1469855Y1139191D02*
X1469636Y1138921D01*
G01X1493047Y1114460D02*
X1497767Y1109818D01*
G01X1493047Y1113356D02*
X1497772Y1108711D01*
G01X1442772Y1139033D02*
X1443243Y1138738D01*
G01X1442543Y1139033D02*
X1442684Y1138946D01*
G01X1442772Y1135884D02*
X1443243Y1135588D01*
G01X1442543Y1135884D02*
X1442684Y1135796D01*
G01X1442772Y1132734D02*
X1443243Y1132439D01*
G01X1442543Y1132734D02*
X1442684Y1132646D01*
G01X1442772Y1129585D02*
X1443243Y1129289D01*
G01X1442543Y1129585D02*
X1442684Y1129497D01*
G01X1442772Y1126435D02*
X1443243Y1126140D01*
G01X1442543Y1126435D02*
X1442684Y1126347D01*
G01X1442772Y1123285D02*
X1443243Y1122990D01*
G01X1442543Y1123285D02*
X1442684Y1123198D01*
G01X1442772Y1120136D02*
X1443243Y1119840D01*
G01X1442543Y1120136D02*
X1442684Y1120048D01*
G01X1442772Y1116986D02*
X1443243Y1116691D01*
G01X1442543Y1116986D02*
X1442684Y1116898D01*
G01X1442772Y1113837D02*
X1443243Y1113541D01*
G01X1442543Y1113837D02*
X1442684Y1113749D01*
G01X1442772Y1110687D02*
X1443243Y1110392D01*
G01X1442543Y1110687D02*
X1442684Y1110599D01*
G01X1442772Y1107537D02*
X1443243Y1107242D01*
G01X1442543Y1107537D02*
X1442684Y1107449D01*
G01X1442772Y1104388D02*
X1443243Y1104092D01*
G01X1442543Y1104388D02*
X1442684Y1104300D01*
G01X1442772Y1101238D02*
X1443243Y1100943D01*
G01X1442543Y1101238D02*
X1442684Y1101150D01*
G01X1442772Y1098088D02*
X1443243Y1097793D01*
G01X1442543Y1098088D02*
X1442684Y1098001D01*
G01X1442772Y1094939D02*
X1443243Y1094644D01*
G01X1442543Y1094939D02*
X1442684Y1094851D01*
G01X1442772Y1091789D02*
X1443243Y1091494D01*
G01X1442543Y1091789D02*
X1442684Y1091701D01*
G01X1442772Y1088640D02*
X1443243Y1088344D01*
G01X1442543Y1088640D02*
X1442684Y1088552D01*
G01X1442772Y1085490D02*
X1443243Y1085195D01*
G01X1442543Y1085490D02*
X1442684Y1085402D01*
G01X1442772Y1082340D02*
X1443243Y1082045D01*
G01X1442543Y1082340D02*
X1442684Y1082253D01*
G01X1442772Y1079191D02*
X1443243Y1078896D01*
G01X1442543Y1079191D02*
X1442684Y1079103D01*
G01X1442772Y1076041D02*
X1443243Y1075746D01*
G01X1442543Y1076041D02*
X1442684Y1075953D01*
G01X1442772Y1072892D02*
X1443243Y1072596D01*
G01X1442543Y1072892D02*
X1442684Y1072804D01*
G01X1442772Y1069742D02*
X1443243Y1069447D01*
G01X1442543Y1069742D02*
X1442684Y1069654D01*
G01Y1116898D02*
X1443073Y1116691D01*
G01X1442684Y1113749D02*
X1443073Y1113541D01*
G01X1442684Y1110599D02*
X1443073Y1110392D01*
G01X1442684Y1107449D02*
X1443073Y1107242D01*
G01X1442684Y1104300D02*
X1443073Y1104092D01*
G01X1442684Y1101150D02*
X1443073Y1100943D01*
G01X1442684Y1098001D02*
X1443073Y1097793D01*
G01X1442684Y1094851D02*
X1443073Y1094644D01*
G01X1442684Y1091701D02*
X1443073Y1091494D01*
G01X1442684Y1088552D02*
X1443073Y1088344D01*
G01X1442684Y1085402D02*
X1443073Y1085195D01*
G01X1442684Y1082253D02*
X1443073Y1082045D01*
G01X1442684Y1079103D02*
X1443073Y1078896D01*
G01X1442684Y1075953D02*
X1443073Y1075746D01*
G01X1442684Y1072804D02*
X1443073Y1072596D01*
G01X1442684Y1069654D02*
X1443073Y1069447D01*
G01X1469636Y1136981D02*
X1469855Y1136711D01*
G01X1469636Y1133831D02*
X1469855Y1133561D01*
G01X1469636Y1130681D02*
X1469855Y1130411D01*
G01X1469636Y1127532D02*
X1469855Y1127262D01*
G01X1469636Y1124382D02*
X1469855Y1124112D01*
G01X1469636Y1121233D02*
X1469855Y1120963D01*
G01X1469636Y1118083D02*
X1469855Y1117813D01*
G01X1469636Y1114933D02*
X1469855Y1114663D01*
G01X1469636Y1111784D02*
X1469855Y1111514D01*
G01X1469636Y1108634D02*
X1469855Y1108364D01*
G01X1469636Y1105485D02*
X1469855Y1105214D01*
G01X1469636Y1102335D02*
X1469855Y1102065D01*
G01X1469636Y1099185D02*
X1469855Y1098915D01*
G01X1469636Y1096036D02*
X1469855Y1095766D01*
G01X1469636Y1092886D02*
X1469855Y1092616D01*
G01X1469636Y1089736D02*
X1469855Y1089466D01*
G01X1469636Y1086587D02*
X1469855Y1086317D01*
G01X1469636Y1083437D02*
X1469855Y1083167D01*
G01X1469636Y1080288D02*
X1469855Y1080018D01*
G01X1469636Y1077138D02*
X1469855Y1076868D01*
G01X1469636Y1073988D02*
X1469855Y1073718D01*
G01X1469636Y1070839D02*
X1469855Y1070569D01*
G01X1469278Y1136966D02*
X1469507Y1136711D01*
G01X1469278Y1133817D02*
X1469507Y1133561D01*
G01X1469278Y1130667D02*
X1469507Y1130411D01*
G01X1469278Y1127518D02*
X1469507Y1127262D01*
G01X1469278Y1124368D02*
X1469507Y1124112D01*
G01X1469278Y1121218D02*
X1469507Y1120963D01*
G01X1469278Y1118069D02*
X1469507Y1117813D01*
G01X1469278Y1114919D02*
X1469507Y1114663D01*
G01X1469278Y1111770D02*
X1469507Y1111514D01*
G01X1469278Y1108620D02*
X1469507Y1108364D01*
G01X1469278Y1105470D02*
X1469507Y1105214D01*
G01X1469278Y1102321D02*
X1469507Y1102065D01*
G01X1469278Y1099171D02*
X1469507Y1098915D01*
G01X1469278Y1096022D02*
X1469507Y1095766D01*
G01X1469278Y1092872D02*
X1469507Y1092616D01*
G01X1469278Y1089722D02*
X1469507Y1089466D01*
G01X1469278Y1086573D02*
X1469507Y1086317D01*
G01X1469278Y1083423D02*
X1469507Y1083167D01*
G01X1469278Y1080274D02*
X1469507Y1080018D01*
G01X1469278Y1077124D02*
X1469507Y1076868D01*
G01X1469278Y1073974D02*
X1469507Y1073718D01*
G01X1469278Y1070825D02*
X1469507Y1070569D01*
G01X1493047Y1113356D02*
Y1115088D01*
G01X1470921Y1070569D02*
Y1069900D01*
G01Y1073718D02*
Y1073049D01*
G01Y1080018D02*
Y1079348D01*
G01Y1076868D02*
Y1076199D01*
G01Y1083167D02*
Y1082498D01*
G01Y1089466D02*
Y1088797D01*
G01Y1086317D02*
Y1085648D01*
G01Y1092616D02*
Y1091947D01*
G01Y1095766D02*
Y1095096D01*
G01Y1102065D02*
Y1101396D01*
G01Y1098915D02*
Y1098246D01*
G01Y1105214D02*
Y1104545D01*
G01Y1111514D02*
Y1110844D01*
G01Y1108364D02*
Y1107695D01*
G01Y1114663D02*
Y1113994D01*
G01Y1120963D02*
Y1120293D01*
G01Y1117813D02*
Y1117144D01*
G01Y1124112D02*
Y1123443D01*
G01Y1130411D02*
Y1129742D01*
G01Y1127262D02*
Y1126592D01*
G01Y1133561D02*
Y1132892D01*
G01Y1136711D02*
Y1136041D01*
G01X1470574Y1070569D02*
Y1069900D01*
G01Y1073718D02*
Y1073049D01*
G01Y1080018D02*
Y1079348D01*
G01Y1076868D02*
Y1076199D01*
G01Y1083167D02*
Y1082498D01*
G01Y1089466D02*
Y1088797D01*
G01Y1086317D02*
Y1085648D01*
G01Y1092616D02*
Y1091947D01*
G01Y1095766D02*
Y1095096D01*
G01Y1102065D02*
Y1101396D01*
G01Y1098915D02*
Y1098246D01*
G01Y1105214D02*
Y1104545D01*
G01Y1111514D02*
Y1110844D01*
G01Y1108364D02*
Y1107695D01*
G01Y1114663D02*
Y1113994D01*
G01Y1120963D02*
Y1120293D01*
G01Y1117813D02*
Y1117144D01*
G01Y1124112D02*
Y1123443D01*
G01Y1130411D02*
Y1129742D01*
G01Y1127262D02*
Y1126592D01*
G01Y1133561D02*
Y1132892D01*
G01Y1136711D02*
Y1136041D01*
G01X1469631Y1073974D02*
Y1072793D01*
G01Y1070825D02*
Y1069644D01*
G01Y1077124D02*
Y1075943D01*
G01Y1083423D02*
Y1082242D01*
G01Y1080274D02*
Y1079092D01*
G01Y1086573D02*
Y1085392D01*
G01Y1092872D02*
Y1091691D01*
G01Y1089722D02*
Y1088541D01*
G01Y1096022D02*
Y1094840D01*
G01Y1102321D02*
Y1101140D01*
G01Y1099171D02*
Y1097990D01*
G01Y1105470D02*
Y1104289D01*
G01Y1111770D02*
Y1110588D01*
G01Y1108620D02*
Y1107439D01*
G01Y1114919D02*
Y1113738D01*
G01Y1121218D02*
Y1120037D01*
G01Y1118069D02*
Y1116888D01*
G01Y1124368D02*
Y1123187D01*
G01Y1130667D02*
Y1129486D01*
G01Y1127518D02*
Y1126337D01*
G01Y1133817D02*
Y1132636D01*
G01Y1136966D02*
Y1135785D01*
G01X1469278Y1073974D02*
Y1072793D01*
G01Y1070825D02*
Y1069644D01*
G01Y1077124D02*
Y1075943D01*
G01Y1083423D02*
Y1082242D01*
G01Y1080274D02*
Y1079092D01*
G01Y1086573D02*
Y1085392D01*
G01Y1092872D02*
Y1091691D01*
G01Y1089722D02*
Y1088541D01*
G01Y1096022D02*
Y1094840D01*
G01Y1102321D02*
Y1101140D01*
G01Y1099171D02*
Y1097990D01*
G01Y1105470D02*
Y1104289D01*
G01Y1111770D02*
Y1110588D01*
G01Y1108620D02*
Y1107439D01*
G01Y1114919D02*
Y1113738D01*
G01Y1121218D02*
Y1120037D01*
G01Y1118069D02*
Y1116888D01*
G01Y1124368D02*
Y1123187D01*
G01Y1130667D02*
Y1129486D01*
G01Y1127518D02*
Y1126337D01*
G01Y1133817D02*
Y1132636D01*
G01Y1136966D02*
Y1135785D01*
G01X1467296Y1073974D02*
Y1072793D01*
G01Y1070825D02*
Y1069644D01*
G01Y1077124D02*
Y1075943D01*
G01Y1083423D02*
Y1082242D01*
G01Y1080274D02*
Y1079092D01*
G01Y1086573D02*
Y1085392D01*
G01Y1092872D02*
Y1091691D01*
G01Y1089722D02*
Y1088541D01*
G01Y1096022D02*
Y1094840D01*
G01Y1102321D02*
Y1101140D01*
G01Y1099171D02*
Y1097990D01*
G01Y1105470D02*
Y1104289D01*
G01Y1111770D02*
Y1110588D01*
G01Y1108620D02*
Y1107439D01*
G01Y1114919D02*
Y1113738D01*
G01Y1121218D02*
Y1120037D01*
G01Y1118069D02*
Y1116888D01*
G01Y1124368D02*
Y1123187D01*
G01Y1130667D02*
Y1129486D01*
G01Y1127518D02*
Y1126337D01*
G01Y1133817D02*
Y1132636D01*
G01Y1136966D02*
Y1135785D01*
G01X1467186Y1073974D02*
Y1072793D01*
G01Y1070825D02*
Y1069644D01*
G01Y1077124D02*
Y1075943D01*
G01Y1083423D02*
Y1082242D01*
G01Y1080274D02*
Y1079092D01*
G01Y1086573D02*
Y1085392D01*
G01Y1092872D02*
Y1091691D01*
G01Y1089722D02*
Y1088541D01*
G01Y1096022D02*
Y1094840D01*
G01Y1102321D02*
Y1101140D01*
G01Y1099171D02*
Y1097990D01*
G01Y1105470D02*
Y1104289D01*
G01Y1111770D02*
Y1110588D01*
G01Y1108620D02*
Y1107439D01*
G01Y1114919D02*
Y1113738D01*
G01Y1121218D02*
Y1120037D01*
G01Y1118069D02*
Y1116888D01*
G01Y1124368D02*
Y1123187D01*
G01Y1130667D02*
Y1129486D01*
G01Y1127518D02*
Y1126337D01*
G01Y1133817D02*
Y1132636D01*
G01Y1136966D02*
Y1135785D01*
G01X1458405Y1073974D02*
Y1072793D01*
G01Y1070825D02*
Y1069644D01*
G01Y1077124D02*
Y1075943D01*
G01Y1083423D02*
Y1082242D01*
G01Y1080274D02*
Y1079092D01*
G01Y1086573D02*
Y1085392D01*
G01Y1092872D02*
Y1091691D01*
G01Y1089722D02*
Y1088541D01*
G01Y1096022D02*
Y1094840D01*
G01Y1102321D02*
Y1101140D01*
G01Y1099171D02*
Y1097990D01*
G01Y1105470D02*
Y1104289D01*
G01Y1111770D02*
Y1110588D01*
G01Y1108620D02*
Y1107439D01*
G01Y1114919D02*
Y1113738D01*
G01Y1121218D02*
Y1120037D01*
G01Y1118069D02*
Y1116888D01*
G01Y1124368D02*
Y1123187D01*
G01Y1130667D02*
Y1129486D01*
G01Y1127518D02*
Y1126337D01*
G01Y1133817D02*
Y1132636D01*
G01Y1136966D02*
Y1135785D01*
G01X1458295Y1073974D02*
Y1072793D01*
G01Y1070825D02*
Y1069644D01*
G01Y1077124D02*
Y1075943D01*
G01Y1083423D02*
Y1082242D01*
G01Y1080274D02*
Y1079092D01*
G01Y1086573D02*
Y1085392D01*
G01Y1092872D02*
Y1091691D01*
G01Y1089722D02*
Y1088541D01*
G01Y1096022D02*
Y1094840D01*
G01Y1102321D02*
Y1101140D01*
G01Y1099171D02*
Y1097990D01*
G01Y1105470D02*
Y1104289D01*
G01Y1111770D02*
Y1110588D01*
G01Y1108620D02*
Y1107439D01*
G01Y1114919D02*
Y1113738D01*
G01Y1121218D02*
Y1120037D01*
G01Y1118069D02*
Y1116888D01*
G01Y1124368D02*
Y1123187D01*
G01Y1130667D02*
Y1129486D01*
G01Y1127518D02*
Y1126337D01*
G01Y1133817D02*
Y1132636D01*
G01Y1136966D02*
Y1135785D01*
G01X1457929Y1073974D02*
Y1072793D01*
G01Y1070825D02*
Y1069644D01*
G01Y1077124D02*
Y1075943D01*
G01Y1083423D02*
Y1082242D01*
G01Y1080274D02*
Y1079092D01*
G01Y1086573D02*
Y1085392D01*
G01Y1092872D02*
Y1091691D01*
G01Y1089722D02*
Y1088541D01*
G01Y1096022D02*
Y1094840D01*
G01Y1102321D02*
Y1101140D01*
G01Y1099171D02*
Y1097990D01*
G01Y1105470D02*
Y1104289D01*
G01Y1111770D02*
Y1110588D01*
G01Y1108620D02*
Y1107439D01*
G01Y1114919D02*
Y1113738D01*
G01Y1121218D02*
Y1120037D01*
G01Y1118069D02*
Y1116888D01*
G01Y1124368D02*
Y1123187D01*
G01Y1130667D02*
Y1129486D01*
G01Y1127518D02*
Y1126337D01*
G01Y1133817D02*
Y1132636D01*
G01Y1136966D02*
Y1135785D01*
G01X1457732Y1069644D02*
Y1069053D01*
G01Y1072793D02*
Y1072203D01*
G01Y1074565D02*
Y1073974D01*
G01Y1071415D02*
Y1070825D01*
G01Y1079092D02*
Y1078502D01*
G01Y1075943D02*
Y1075352D01*
G01Y1077714D02*
Y1077124D01*
G01Y1082242D02*
Y1081651D01*
G01Y1084014D02*
Y1083423D01*
G01Y1080864D02*
Y1080274D01*
G01Y1088541D02*
Y1087951D01*
G01Y1085392D02*
Y1084801D01*
G01Y1087163D02*
Y1086573D01*
G01Y1091691D02*
Y1091100D01*
G01Y1093463D02*
Y1092872D01*
G01Y1090313D02*
Y1089722D01*
G01Y1097990D02*
Y1097400D01*
G01Y1094840D02*
Y1094250D01*
G01Y1096612D02*
Y1096022D01*
G01Y1101140D02*
Y1100549D01*
G01Y1102911D02*
Y1102321D01*
G01Y1099762D02*
Y1099171D01*
G01Y1107439D02*
Y1106848D01*
G01Y1104289D02*
Y1103699D01*
G01Y1106061D02*
Y1105470D01*
G01Y1110588D02*
Y1109998D01*
G01Y1112360D02*
Y1111770D01*
G01Y1109211D02*
Y1108620D01*
G01Y1116888D02*
Y1116297D01*
G01Y1113738D02*
Y1113148D01*
G01Y1115510D02*
Y1114919D01*
G01Y1120037D02*
Y1119447D01*
G01Y1121809D02*
Y1121218D01*
G01Y1118659D02*
Y1118069D01*
G01Y1126337D02*
Y1125746D01*
G01Y1123187D02*
Y1122596D01*
G01Y1124959D02*
Y1124368D01*
G01Y1129486D02*
Y1128896D01*
G01Y1131258D02*
Y1130667D01*
G01Y1128108D02*
Y1127518D01*
G01Y1135785D02*
Y1135195D01*
G01Y1132636D02*
Y1132045D01*
G01Y1134407D02*
Y1133817D01*
G01Y1138935D02*
Y1138344D01*
G01Y1137557D02*
Y1136966D01*
G01X1457535Y1069644D02*
Y1069053D01*
G01Y1072793D02*
Y1072203D01*
G01Y1074565D02*
Y1073974D01*
G01Y1071415D02*
Y1070825D01*
G01Y1079092D02*
Y1078502D01*
G01Y1075943D02*
Y1075352D01*
G01Y1077714D02*
Y1077124D01*
G01Y1082242D02*
Y1081651D01*
G01Y1084014D02*
Y1083423D01*
G01Y1080864D02*
Y1080274D01*
G01Y1088541D02*
Y1087951D01*
G01Y1085392D02*
Y1084801D01*
G01Y1087163D02*
Y1086573D01*
G01Y1091691D02*
Y1091100D01*
G01Y1093463D02*
Y1092872D01*
G01Y1090313D02*
Y1089722D01*
G01Y1097990D02*
Y1097400D01*
G01Y1094840D02*
Y1094250D01*
G01Y1096612D02*
Y1096022D01*
G01Y1101140D02*
Y1100549D01*
G01Y1102911D02*
Y1102321D01*
G01Y1099762D02*
Y1099171D01*
G01Y1107439D02*
Y1106848D01*
G01Y1104289D02*
Y1103699D01*
G01Y1106061D02*
Y1105470D01*
G01Y1110588D02*
Y1109998D01*
G01Y1112360D02*
Y1111770D01*
G01Y1109211D02*
Y1108620D01*
G01Y1116888D02*
Y1116297D01*
G01Y1113738D02*
Y1113148D01*
G01Y1115510D02*
Y1114919D01*
G01Y1120037D02*
Y1119447D01*
G01Y1121809D02*
Y1121218D01*
G01Y1118659D02*
Y1118069D01*
G01Y1126337D02*
Y1125746D01*
G01Y1123187D02*
Y1122596D01*
G01Y1124959D02*
Y1124368D01*
G01Y1129486D02*
Y1128896D01*
G01Y1131258D02*
Y1130667D01*
G01Y1128108D02*
Y1127518D01*
G01Y1135785D02*
Y1135195D01*
G01Y1132636D02*
Y1132045D01*
G01Y1134407D02*
Y1133817D01*
G01Y1138935D02*
Y1138344D01*
G01Y1137557D02*
Y1136966D01*
G01X1444212Y1074171D02*
Y1072596D01*
G01Y1071022D02*
Y1069447D01*
G01Y1077321D02*
Y1075746D01*
G01Y1083620D02*
Y1082045D01*
G01Y1080470D02*
Y1078896D01*
G01Y1086770D02*
Y1085195D01*
G01Y1093069D02*
Y1091494D01*
G01Y1089919D02*
Y1088344D01*
G01Y1096218D02*
Y1094644D01*
G01Y1102518D02*
Y1100943D01*
G01Y1099368D02*
Y1097793D01*
G01Y1105667D02*
Y1104092D01*
G01Y1111966D02*
Y1110392D01*
G01Y1108817D02*
Y1107242D01*
G01Y1115116D02*
Y1113541D01*
G01Y1121415D02*
Y1119840D01*
G01Y1118266D02*
Y1116691D01*
G01Y1124565D02*
Y1122990D01*
G01Y1130864D02*
Y1129289D01*
G01Y1127714D02*
Y1126140D01*
G01Y1134014D02*
Y1132439D01*
G01Y1140313D02*
Y1138738D01*
G01Y1137163D02*
Y1135588D01*
G01X1442684Y1073964D02*
Y1072804D01*
G01Y1070814D02*
Y1069654D01*
G01Y1077113D02*
Y1075953D01*
G01Y1083413D02*
Y1082253D01*
G01Y1080263D02*
Y1079103D01*
G01Y1086562D02*
Y1085402D01*
G01Y1092861D02*
Y1091701D01*
G01Y1089712D02*
Y1088552D01*
G01Y1096011D02*
Y1094851D01*
G01Y1102310D02*
Y1101150D01*
G01Y1099161D02*
Y1098001D01*
G01Y1105460D02*
Y1104300D01*
G01Y1111759D02*
Y1110599D01*
G01Y1108609D02*
Y1107449D01*
G01Y1114909D02*
Y1113749D01*
G01Y1121208D02*
Y1120048D01*
G01Y1118058D02*
Y1116898D01*
G01Y1124357D02*
Y1123198D01*
G01Y1130657D02*
Y1129497D01*
G01Y1127507D02*
Y1126347D01*
G01Y1133806D02*
Y1132646D01*
G01Y1136956D02*
Y1135796D01*
G01X1439047Y1139071D02*
X1442543Y1139033D01*
G01X1437751Y1139086D02*
X1441007Y1139050D01*
G01X1438785Y1139071D02*
X1436420Y1139097D01*
G01X1441235Y1139050D02*
X1442772Y1139033D01*
G01X1441235Y1139050D02*
X1438785Y1139071D01*
G01X1437751Y1139086D02*
X1436420Y1139097D01*
G01X1441235Y1140001D02*
X1441007D01*
G01X1439047Y1139980D02*
X1438785D01*
G01X1439047Y1139071D02*
X1438785D01*
G01X1441235Y1139050D02*
X1441007D01*
G01X1440094Y1139991D02*
X1438785Y1139980D01*
G01X1441235Y1140001D02*
X1440094Y1139991D01*
G01X1437751Y1139965D02*
X1436420Y1139954D01*
G01X1442543Y1140018D02*
X1441007Y1140001D01*
G01X1442543Y1140018D02*
X1439047Y1139980D01*
G01X1441235Y1140001D02*
X1442772Y1140018D01*
G01X1439047Y1139980D02*
X1440094Y1139991D01*
G01X1438785Y1139980D02*
X1436420Y1139954D01*
G01X1437751Y1139965D02*
X1439047Y1139980D01*
G01X1441235Y1140001D02*
Y1139050D01*
G01X1441007Y1140001D02*
Y1139050D01*
G01X1439047Y1139980D02*
Y1139071D01*
G01X1438785Y1139980D02*
Y1139071D01*
G01X1437751Y1139959D02*
Y1139092D01*
G01X1436420Y1139954D02*
Y1139097D01*
G01X1438289Y1181947D02*
X1437452Y1181783D01*
G01X1438289Y1181127D02*
X1437452Y1180963D01*
G01X1438457Y1188508D02*
X1437787Y1188344D01*
G01X1438457Y1187688D02*
X1437787Y1187524D01*
G01X1439797Y1184243D02*
X1439127Y1184079D01*
G01X1438122Y1176041D02*
X1437452Y1175877D01*
G01X1438122Y1168659D02*
X1437452Y1168495D01*
G01X1438122Y1163574D02*
X1437452Y1163410D01*
G01X1440300Y1183587D02*
X1439127Y1183259D01*
G01X1449937Y1200155D02*
X1430449D01*
G01X1440094Y1196684D02*
X1438785Y1196673D01*
G01X1441235Y1196694D02*
X1440094Y1196684D01*
G01Y1193534D02*
X1438785Y1193523D01*
G01X1441235Y1193544D02*
X1440094Y1193534D01*
G01X1437751Y1196658D02*
X1436420Y1196646D01*
G01X1437751Y1193509D02*
X1436420Y1193497D01*
G01X1442543Y1196711D02*
X1441007Y1196694D01*
G01X1442543Y1196711D02*
X1439047Y1196673D01*
G01X1441235Y1196694D02*
X1442772Y1196711D01*
G01X1442543Y1193561D02*
X1441007Y1193544D01*
G01X1442543Y1193561D02*
X1439047Y1193523D01*
G01X1441235Y1193544D02*
X1442772Y1193561D01*
G01X1439047Y1196673D02*
X1440094Y1196684D01*
G01X1438785Y1196673D02*
X1436420Y1196646D01*
G01X1437751Y1196658D02*
X1439047Y1196673D01*
G01Y1193523D02*
X1440094Y1193534D01*
G01X1438785Y1193523D02*
X1436420Y1193497D01*
G01X1437751Y1193509D02*
X1439047Y1193523D01*
G01X1439797Y1170956D02*
X1438792Y1170792D01*
G01X1438122Y1169480D02*
X1437284Y1169316D01*
G01X1441472Y1148646D02*
X1439462Y1147990D01*
G01X1438792Y1147826D02*
X1434268Y1146350D01*
G01X1441472Y1149630D02*
X1433598Y1147006D01*
G01X1439047Y1195764D02*
X1442543Y1195726D01*
G01X1437751Y1195779D02*
X1441007Y1195743D01*
G01X1439047Y1192615D02*
X1442543Y1192577D01*
G01X1437751Y1192629D02*
X1441007Y1192593D01*
G01X1439047Y1189465D02*
X1442543Y1189427D01*
G01X1437751Y1189479D02*
X1441007Y1189444D01*
G01X1439047Y1186315D02*
X1442543Y1186277D01*
G01X1437751Y1186330D02*
X1441007Y1186294D01*
G01X1439047Y1183166D02*
X1442543Y1183128D01*
G01X1437751Y1183180D02*
X1441007Y1183144D01*
G01X1439047Y1180016D02*
X1442543Y1179978D01*
G01X1437751Y1180031D02*
X1441007Y1179995D01*
G01X1439047Y1176867D02*
X1442543Y1176829D01*
G01X1437751Y1176881D02*
X1441007Y1176845D01*
G01X1439047Y1173717D02*
X1442543Y1173679D01*
G01X1437751Y1173731D02*
X1441007Y1173695D01*
G01X1439047Y1170567D02*
X1442543Y1170529D01*
G01X1437751Y1170582D02*
X1441007Y1170546D01*
G01X1439047Y1167418D02*
X1442543Y1167380D01*
G01X1437751Y1167432D02*
X1441007Y1167396D01*
G01X1439047Y1164268D02*
X1442543Y1164230D01*
G01X1437751Y1164283D02*
X1441007Y1164247D01*
G01X1439047Y1161119D02*
X1442543Y1161081D01*
G01X1437751Y1161133D02*
X1441007Y1161097D01*
G01X1439047Y1157969D02*
X1442543Y1157931D01*
G01X1437751Y1157983D02*
X1441007Y1157947D01*
G01X1439047Y1154819D02*
X1442543Y1154781D01*
G01X1437751Y1154834D02*
X1441007Y1154798D01*
G01X1439047Y1151670D02*
X1442543Y1151632D01*
G01X1437751Y1151684D02*
X1441007Y1151648D01*
G01X1439047Y1148520D02*
X1442543Y1148482D01*
G01X1437751Y1148535D02*
X1441007Y1148499D01*
G01X1439047Y1145371D02*
X1442543Y1145333D01*
G01X1437751Y1145385D02*
X1441007Y1145349D01*
G01X1439047Y1142221D02*
X1442543Y1142183D01*
G01X1437751Y1142235D02*
X1441007Y1142199D01*
G01X1438785Y1195764D02*
X1436420Y1195790D01*
G01X1438785Y1192615D02*
X1436420Y1192641D01*
G01X1438785Y1189465D02*
X1436420Y1189491D01*
G01X1438785Y1186315D02*
X1436420Y1186342D01*
G01X1438785Y1183166D02*
X1436420Y1183192D01*
G01X1438785Y1180016D02*
X1436420Y1180042D01*
G01X1438785Y1176867D02*
X1436420Y1176893D01*
G01X1438785Y1173717D02*
X1436420Y1173743D01*
G01X1438785Y1170567D02*
X1436420Y1170594D01*
G01X1438785Y1167418D02*
X1436420Y1167444D01*
G01X1438785Y1164268D02*
X1436420Y1164294D01*
G01X1438785Y1161119D02*
X1436420Y1161145D01*
G01X1438785Y1157969D02*
X1436420Y1157995D01*
G01X1438785Y1154819D02*
X1436420Y1154846D01*
G01X1438785Y1151670D02*
X1436420Y1151696D01*
G01X1438785Y1148520D02*
X1436420Y1148546D01*
G01X1438785Y1145371D02*
X1436420Y1145397D01*
G01X1438785Y1142221D02*
X1436420Y1142247D01*
G01X1441235Y1195743D02*
X1442772Y1195726D01*
G01X1441235Y1192593D02*
X1442772Y1192577D01*
G01X1441235Y1189444D02*
X1442772Y1189427D01*
G01X1441235Y1186294D02*
X1442772Y1186277D01*
G01X1441235Y1183144D02*
X1442772Y1183128D01*
G01X1441235Y1179995D02*
X1442772Y1179978D01*
G01X1441235Y1176845D02*
X1442772Y1176829D01*
G01X1441235Y1173695D02*
X1442772Y1173679D01*
G01X1441235Y1170546D02*
X1442772Y1170529D01*
G01X1441235Y1167396D02*
X1442772Y1167380D01*
G01X1441235Y1164247D02*
X1442772Y1164230D01*
G01X1441235Y1161097D02*
X1442772Y1161081D01*
G01X1441235Y1157947D02*
X1442772Y1157931D01*
G01X1441235Y1154798D02*
X1442772Y1154781D01*
G01X1441235Y1151648D02*
X1442772Y1151632D01*
G01X1441235Y1148499D02*
X1442772Y1148482D01*
G01X1441235Y1145349D02*
X1442772Y1145333D01*
G01X1441235Y1142199D02*
X1442772Y1142183D01*
G01X1441235Y1195743D02*
X1438785Y1195764D01*
G01X1437751Y1195779D02*
X1436420Y1195790D01*
G01X1441235Y1192593D02*
X1438785Y1192615D01*
G01X1437751Y1192629D02*
X1436420Y1192641D01*
G01X1441235Y1189444D02*
X1438785Y1189465D01*
G01X1437751Y1189479D02*
X1436420Y1189491D01*
G01X1441235Y1186294D02*
X1438785Y1186315D01*
G01X1437751Y1186330D02*
X1436420Y1186342D01*
G01X1441235Y1183144D02*
X1438785Y1183166D01*
G01X1437751Y1183180D02*
X1436420Y1183192D01*
G01X1441235Y1179995D02*
X1438785Y1180016D01*
G01X1437751Y1180031D02*
X1436420Y1180042D01*
G01X1441235Y1176845D02*
X1438785Y1176867D01*
G01X1437751Y1176881D02*
X1436420Y1176893D01*
G01X1441235Y1173695D02*
X1438785Y1173717D01*
G01X1437751Y1173731D02*
X1436420Y1173743D01*
G01X1441235Y1170546D02*
X1438785Y1170567D01*
G01X1437751Y1170582D02*
X1436420Y1170594D01*
G01X1441235Y1167396D02*
X1438785Y1167418D01*
G01X1437751Y1167432D02*
X1436420Y1167444D01*
G01X1441235Y1164247D02*
X1438785Y1164268D01*
G01X1437751Y1164283D02*
X1436420Y1164294D01*
G01X1441235Y1161097D02*
X1438785Y1161119D01*
G01X1437751Y1161133D02*
X1436420Y1161145D01*
G01X1441235Y1157947D02*
X1438785Y1157969D01*
G01X1437751Y1157983D02*
X1436420Y1157995D01*
G01X1441235Y1154798D02*
X1438785Y1154819D01*
G01X1437751Y1154834D02*
X1436420Y1154846D01*
G01X1441235Y1151648D02*
X1438785Y1151670D01*
G01X1437751Y1151684D02*
X1436420Y1151696D01*
G01X1441235Y1148499D02*
X1438785Y1148520D01*
G01X1437751Y1148535D02*
X1436420Y1148546D01*
G01X1441235Y1145349D02*
X1438785Y1145371D01*
G01X1437751Y1145385D02*
X1436420Y1145397D01*
G01X1441235Y1142199D02*
X1438785Y1142221D01*
G01X1437751Y1142235D02*
X1436420Y1142247D01*
G01X1441235Y1196694D02*
X1441007D01*
G01X1439047Y1196673D02*
X1438785D01*
G01X1439047Y1195764D02*
X1438785D01*
G01X1441235Y1195743D02*
X1441007D01*
G01X1441235Y1193544D02*
X1441007D01*
G01X1439047Y1193523D02*
X1438785D01*
G01X1439047Y1192615D02*
X1438785D01*
G01X1441235Y1192593D02*
X1441007D01*
G01X1441472Y1190641D02*
X1433598D01*
G01X1441007Y1190395D02*
X1441235D01*
G01X1439047Y1190373D02*
X1438785D01*
G01X1441472Y1189821D02*
X1433598D01*
G01X1439047Y1189465D02*
X1438785D01*
G01X1441235Y1189444D02*
X1441007D01*
G01X1439127Y1188508D02*
X1438457D01*
G01X1439127Y1187688D02*
X1438457D01*
G01X1441235Y1187245D02*
X1441007D01*
G01X1439047Y1187224D02*
X1438785D01*
G01X1439047Y1186315D02*
X1438785D01*
G01X1441235Y1186294D02*
X1441007D01*
G01X1441235Y1184096D02*
X1441007D01*
G01X1439127Y1184079D02*
X1438457D01*
G01X1439047Y1184074D02*
X1438785D01*
G01X1439127Y1183259D02*
X1438457D01*
G01X1439047Y1183166D02*
X1438785D01*
G01X1441235Y1183144D02*
X1441007D01*
G01X1441472Y1181947D02*
X1438289D01*
G01X1441472Y1181127D02*
X1438289D01*
G01X1441235Y1180946D02*
X1441007D01*
G01X1439047Y1180924D02*
X1438785D01*
G01X1439047Y1180016D02*
X1438785D01*
G01X1441235Y1179995D02*
X1441007D01*
G01X1436949Y1178174D02*
X1436111D01*
G01X1441472D02*
X1437619D01*
G01X1441235Y1177796D02*
X1441007D01*
G01X1439047Y1177775D02*
X1438785D01*
G01X1441472Y1177354D02*
X1436111D01*
G01X1439047Y1176867D02*
X1438785D01*
G01X1441235Y1176845D02*
X1441007D01*
G01X1438792Y1176041D02*
X1438122D01*
G01Y1175221D02*
X1437787D01*
G01X1441235Y1174647D02*
X1441007D01*
G01X1439047Y1174625D02*
X1438785D01*
G01X1439047Y1173717D02*
X1438785D01*
G01X1441235Y1173695D02*
X1441007D01*
G01X1438122Y1171776D02*
X1437954D01*
G01X1439127Y1171612D02*
X1438792D01*
G01X1441235Y1171497D02*
X1441007D01*
G01X1439047Y1171476D02*
X1438785D01*
G01X1439047Y1170567D02*
X1438785D01*
G01X1441235Y1170546D02*
X1441007D01*
G01X1441472Y1169480D02*
X1438122D01*
G01X1441472Y1168659D02*
X1438122D01*
G01X1441235Y1168348D02*
X1441007D01*
G01X1439047Y1168326D02*
X1438785D01*
G01X1439047Y1167418D02*
X1438785D01*
G01X1441235Y1167396D02*
X1441007D01*
G01X1436949Y1165707D02*
X1433598D01*
G01X1441472D02*
X1437619D01*
G01X1441235Y1165198D02*
X1441007D01*
G01X1439047Y1165176D02*
X1438785D01*
G01X1441472Y1164886D02*
X1433598D01*
G01X1439047Y1164268D02*
X1438785D01*
G01X1441235Y1164247D02*
X1441007D01*
G01X1439462Y1163574D02*
X1438122D01*
G01X1439294Y1162754D02*
X1438289D01*
G01X1441235Y1162048D02*
X1441007D01*
G01X1439047Y1162027D02*
X1438785D01*
G01X1439047Y1161119D02*
X1438785D01*
G01X1441235Y1161097D02*
X1441007D01*
G01X1437117Y1159145D02*
X1436111D01*
G01X1439629D02*
X1437954D01*
G01X1444153D02*
X1440467D01*
G01X1441235Y1158899D02*
X1441007D01*
G01X1439047Y1158877D02*
X1438785D01*
G01X1444153Y1158325D02*
X1436111D01*
G01X1439047Y1157969D02*
X1438785D01*
G01X1441235Y1157947D02*
X1441007D01*
G01X1441472Y1157012D02*
X1437452D01*
G01X1441472Y1156192D02*
X1437452D01*
G01X1441235Y1155749D02*
X1441007D01*
G01X1439047Y1155728D02*
X1438785D01*
G01X1439047Y1154819D02*
X1438785D01*
G01X1441235Y1154798D02*
X1441007D01*
G01X1441472Y1154388D02*
X1437452D01*
G01X1441472Y1153567D02*
X1437452D01*
G01X1441235Y1152600D02*
X1441007D01*
G01X1439047Y1152578D02*
X1438785D01*
G01X1436614Y1151763D02*
X1436111D01*
G01X1441472D02*
X1437284D01*
G01X1439047Y1151670D02*
X1438785D01*
G01X1441235Y1151648D02*
X1441007D01*
G01X1441472Y1150943D02*
X1436111D01*
G01X1441235Y1149450D02*
X1441007D01*
G01X1439047Y1149428D02*
X1438785D01*
G01X1439047Y1148520D02*
X1438785D01*
G01X1441235Y1148499D02*
X1441007D01*
G01X1441235Y1146300D02*
X1441007D01*
G01X1439047Y1146279D02*
X1438785D01*
G01X1439047Y1145371D02*
X1438785D01*
G01X1441235Y1145349D02*
X1441007D01*
G01X1441235Y1143151D02*
X1441007D01*
G01X1439047Y1143129D02*
X1438785D01*
G01X1439047Y1142221D02*
X1438785D01*
G01X1441235Y1142199D02*
X1441007D01*
G01X1440094Y1190385D02*
X1438785Y1190373D01*
G01X1441235Y1190395D02*
X1440094Y1190385D01*
G01Y1187235D02*
X1438785Y1187224D01*
G01X1441235Y1187245D02*
X1440094Y1187235D01*
G01Y1184086D02*
X1438785Y1184074D01*
G01X1441235Y1184096D02*
X1440094Y1184086D01*
G01Y1180936D02*
X1438785Y1180924D01*
G01X1441235Y1180946D02*
X1440094Y1180936D01*
G01Y1177786D02*
X1438785Y1177775D01*
G01X1441235Y1177796D02*
X1440094Y1177786D01*
G01Y1174637D02*
X1438785Y1174625D01*
G01X1441235Y1174647D02*
X1440094Y1174637D01*
G01Y1171487D02*
X1438785Y1171476D01*
G01X1441235Y1171497D02*
X1440094Y1171487D01*
G01Y1168338D02*
X1438785Y1168326D01*
G01X1441235Y1168348D02*
X1440094Y1168338D01*
G01Y1165188D02*
X1438785Y1165176D01*
G01X1441235Y1165198D02*
X1440094Y1165188D01*
G01Y1162038D02*
X1438785Y1162027D01*
G01X1441235Y1162048D02*
X1440094Y1162038D01*
G01Y1158889D02*
X1438785Y1158877D01*
G01X1441235Y1158899D02*
X1440094Y1158889D01*
G01Y1155739D02*
X1438785Y1155728D01*
G01X1441235Y1155749D02*
X1440094Y1155739D01*
G01Y1152590D02*
X1438785Y1152578D01*
G01X1441235Y1152600D02*
X1440094Y1152590D01*
G01Y1149440D02*
X1438785Y1149428D01*
G01X1441235Y1149450D02*
X1440094Y1149440D01*
G01Y1146290D02*
X1438785Y1146279D01*
G01X1441235Y1146300D02*
X1440094Y1146290D01*
G01Y1143141D02*
X1438785Y1143129D01*
G01X1441235Y1143151D02*
X1440094Y1143141D01*
G01X1437751Y1190359D02*
X1436420Y1190347D01*
G01X1437751Y1187209D02*
X1436420Y1187198D01*
G01X1437751Y1184060D02*
X1436420Y1184048D01*
G01X1437751Y1180910D02*
X1436420Y1180898D01*
G01X1437751Y1177761D02*
X1436420Y1177749D01*
G01X1437751Y1174611D02*
X1436420Y1174599D01*
G01X1437751Y1171461D02*
X1436420Y1171450D01*
G01X1437751Y1168312D02*
X1436420Y1168300D01*
G01X1437751Y1165162D02*
X1436420Y1165150D01*
G01X1437751Y1162013D02*
X1436420Y1162001D01*
G01X1437751Y1158863D02*
X1436420Y1158851D01*
G01X1437751Y1155713D02*
X1436420Y1155702D01*
G01X1437751Y1152564D02*
X1436420Y1152552D01*
G01X1437751Y1149414D02*
X1436420Y1149402D01*
G01X1437751Y1146265D02*
X1436420Y1146253D01*
G01X1437751Y1143115D02*
X1436420Y1143103D01*
G01X1442543Y1190411D02*
X1441007Y1190395D01*
G01X1442543Y1190411D02*
X1439047Y1190373D01*
G01X1441235Y1190395D02*
X1442772Y1190411D01*
G01X1442543Y1187262D02*
X1441007Y1187245D01*
G01X1442543Y1187262D02*
X1439047Y1187224D01*
G01X1441235Y1187245D02*
X1442772Y1187262D01*
G01X1442543Y1184112D02*
X1441007Y1184096D01*
G01X1442543Y1184112D02*
X1439047Y1184074D01*
G01X1441235Y1184096D02*
X1442772Y1184112D01*
G01X1442543Y1180963D02*
X1441007Y1180946D01*
G01X1442543Y1180963D02*
X1439047Y1180925D01*
G01X1441235Y1180946D02*
X1442772Y1180963D01*
G01X1442543Y1177813D02*
X1441007Y1177796D01*
G01X1442543Y1177813D02*
X1439047Y1177775D01*
G01X1441235Y1177796D02*
X1442772Y1177813D01*
G01X1442543Y1174663D02*
X1441007Y1174647D01*
G01X1442543Y1174663D02*
X1439047Y1174625D01*
G01X1441235Y1174647D02*
X1442772Y1174663D01*
G01X1442543Y1171514D02*
X1441007Y1171497D01*
G01X1442543Y1171514D02*
X1439047Y1171476D01*
G01X1441235Y1171497D02*
X1442772Y1171514D01*
G01X1442543Y1168364D02*
X1441007Y1168348D01*
G01X1442543Y1168364D02*
X1439047Y1168326D01*
G01X1441235Y1168348D02*
X1442772Y1168364D01*
G01X1442543Y1165214D02*
X1441007Y1165198D01*
G01X1442543Y1165214D02*
X1439047Y1165177D01*
G01X1441235Y1165198D02*
X1442772Y1165214D01*
G01X1442543Y1162065D02*
X1441007Y1162048D01*
G01X1442543Y1162065D02*
X1439047Y1162027D01*
G01X1441235Y1162048D02*
X1442772Y1162065D01*
G01X1442543Y1158915D02*
X1441007Y1158899D01*
G01X1442543Y1158915D02*
X1439047Y1158877D01*
G01X1441235Y1158899D02*
X1442772Y1158915D01*
G01X1442543Y1155766D02*
X1441007Y1155749D01*
G01X1442543Y1155766D02*
X1439047Y1155728D01*
G01X1441235Y1155749D02*
X1442772Y1155766D01*
G01X1442543Y1152616D02*
X1441007Y1152600D01*
G01X1442543Y1152616D02*
X1439047Y1152578D01*
G01X1441235Y1152600D02*
X1442772Y1152616D01*
G01X1442543Y1149466D02*
X1441007Y1149450D01*
G01X1442543Y1149466D02*
X1439047Y1149428D01*
G01X1441235Y1149450D02*
X1442772Y1149466D01*
G01X1442543Y1146317D02*
X1441007Y1146300D01*
G01X1442543Y1146317D02*
X1439047Y1146279D01*
G01X1441235Y1146300D02*
X1442772Y1146317D01*
G01X1442543Y1143167D02*
X1441007Y1143151D01*
G01X1442543Y1143167D02*
X1439047Y1143129D01*
G01X1441235Y1143151D02*
X1442772Y1143167D01*
G01X1439047Y1190373D02*
X1440094Y1190385D01*
G01X1438785Y1190373D02*
X1436420Y1190347D01*
G01X1437751Y1190359D02*
X1439047Y1190373D01*
G01Y1187224D02*
X1440094Y1187235D01*
G01X1438785Y1187224D02*
X1436420Y1187198D01*
G01X1437751Y1187209D02*
X1439047Y1187224D01*
G01Y1184074D02*
X1440094Y1184086D01*
G01X1438785Y1184074D02*
X1436420Y1184048D01*
G01X1437751Y1184060D02*
X1439047Y1184074D01*
G01Y1180924D02*
X1440094Y1180936D01*
G01X1438785Y1180924D02*
X1436420Y1180898D01*
G01X1437751Y1180910D02*
X1439047Y1180924D01*
G01Y1177775D02*
X1440094Y1177786D01*
G01X1438785Y1177775D02*
X1436420Y1177749D01*
G01X1437751Y1177761D02*
X1439047Y1177775D01*
G01Y1174625D02*
X1440094Y1174637D01*
G01X1438785Y1174625D02*
X1436420Y1174599D01*
G01X1437751Y1174611D02*
X1439047Y1174625D01*
G01Y1171476D02*
X1440094Y1171487D01*
G01X1438785Y1171476D02*
X1436420Y1171450D01*
G01X1437751Y1171461D02*
X1439047Y1171476D01*
G01Y1168326D02*
X1440094Y1168338D01*
G01X1438785Y1168326D02*
X1436420Y1168300D01*
G01X1437751Y1168312D02*
X1439047Y1168326D01*
G01Y1165176D02*
X1440094Y1165188D01*
G01X1438785Y1165176D02*
X1436420Y1165150D01*
G01X1437751Y1165162D02*
X1439047Y1165176D01*
G01Y1162027D02*
X1440094Y1162038D01*
G01X1438785Y1162027D02*
X1436420Y1162001D01*
G01X1437751Y1162013D02*
X1439047Y1162027D01*
G01Y1158877D02*
X1440094Y1158889D01*
G01X1438785Y1158877D02*
X1436420Y1158851D01*
G01X1437751Y1158863D02*
X1439047Y1158877D01*
G01Y1155728D02*
X1440094Y1155739D01*
G01X1438785Y1155728D02*
X1436420Y1155702D01*
G01X1437751Y1155713D02*
X1439047Y1155728D01*
G01Y1152578D02*
X1440094Y1152590D01*
G01X1438785Y1152578D02*
X1436420Y1152552D01*
G01X1437751Y1152564D02*
X1439047Y1152578D01*
G01Y1149428D02*
X1440094Y1149440D01*
G01X1438785Y1149428D02*
X1436420Y1149402D01*
G01X1437751Y1149414D02*
X1439047Y1149428D01*
G01Y1146279D02*
X1440094Y1146290D01*
G01X1438785Y1146279D02*
X1436420Y1146253D01*
G01X1437751Y1146265D02*
X1439047Y1146279D01*
G01Y1143129D02*
X1440094Y1143141D01*
G01X1438785Y1143129D02*
X1436420Y1143103D01*
G01X1437751Y1143115D02*
X1439047Y1143129D01*
G01X1438289Y1162754D02*
X1437787Y1162590D01*
G01X1439629Y1171776D02*
X1439127Y1171612D01*
G01X1437452Y1181783D02*
X1436949Y1181619D01*
G01X1437787Y1188344D02*
X1437284Y1188180D01*
G01X1437452Y1157012D02*
X1436614Y1156684D01*
G01X1437452Y1153567D02*
X1437117Y1153403D01*
G01X1437452Y1156192D02*
X1437117Y1156028D01*
G01X1440802Y1159309D02*
X1440467Y1159145D01*
G01X1437452Y1163410D02*
X1437117Y1163246D01*
G01X1440300Y1188180D02*
X1439127Y1188508D01*
G01X1439797Y1187524D02*
X1439127Y1187688D01*
G01X1438457Y1184079D02*
X1437787Y1184243D01*
G01X1438457Y1183259D02*
X1437787Y1183423D01*
G01X1440467Y1175877D02*
X1439797Y1176041D01*
G01X1438792Y1170792D02*
X1437787Y1170956D01*
G01X1437284Y1169316D02*
X1436949Y1169151D01*
G01X1440467Y1171284D02*
X1439797Y1170956D01*
G01X1439965Y1171940D02*
X1439629Y1171776D01*
G01X1440132Y1159473D02*
X1439629Y1159145D01*
G01X1437787Y1162590D02*
X1437284Y1162262D01*
G01X1437787Y1175221D02*
X1437284Y1174893D01*
G01X1426512Y1202124D02*
X1430449Y1200155D01*
G01X1441472Y1143069D02*
X1433598Y1145693D01*
G01X1437787Y1183423D02*
X1437284Y1183587D01*
G01X1440300Y1175057D02*
X1439797Y1175221D01*
G01Y1162590D02*
X1439294Y1162754D01*
G01X1441472Y1144053D02*
X1439462Y1144709D01*
G01X1438792Y1144873D02*
X1434268Y1146350D01*
G01X1440132Y1163410D02*
X1439462Y1163574D01*
G01X1440802Y1183915D02*
X1440300Y1183587D01*
G01Y1184571D02*
X1439797Y1184243D01*
G01X1437787Y1187524D02*
X1437284Y1187196D01*
G01Y1188180D02*
X1436781Y1187852D01*
G01X1437452Y1175877D02*
X1436781Y1175385D01*
G01X1437117Y1153403D02*
X1436949Y1153239D01*
G01X1436781Y1154224D02*
X1436279Y1153732D01*
G01X1441137Y1159637D02*
X1440802Y1159309D01*
G01X1437117Y1156028D02*
X1436949Y1155864D01*
G01X1436614Y1156684D02*
X1436279Y1156356D01*
G01X1440300Y1188180D02*
X1440802Y1187852D01*
G01X1439797Y1187524D02*
X1440300Y1187196D01*
G01X1437284Y1184571D02*
X1437787Y1184243D01*
G01X1436781Y1183915D02*
X1437284Y1183587D01*
G01X1437619Y1171940D02*
X1437954Y1171776D01*
G01X1437117Y1171284D02*
X1437787Y1170956D01*
G01X1439797Y1162590D02*
X1440132Y1162426D01*
G01X1436781Y1159309D02*
X1437117Y1159145D01*
G01Y1154552D02*
X1437452Y1154388D01*
G01X1437117Y1163246D02*
X1436614Y1162754D01*
G01X1440802Y1171612D02*
X1440467Y1171284D01*
G01X1437452Y1168495D02*
X1437117Y1168167D01*
G01X1440467Y1172432D02*
X1439965Y1171940D01*
G01X1436949Y1169151D02*
X1436614Y1168823D01*
G01X1441137Y1184243D02*
X1440802Y1183915D01*
G01X1437452Y1180963D02*
X1437117Y1180634D01*
G01X1440635Y1184900D02*
X1440300Y1184571D01*
G01X1436949Y1181619D02*
X1436614Y1181291D01*
G01X1437284Y1187196D02*
X1436949Y1186868D01*
G01X1436781Y1187852D02*
X1436446Y1187524D01*
G01X1440802Y1187852D02*
X1441137Y1187524D01*
G01X1440300Y1187196D02*
X1440635Y1186868D01*
G01X1436949Y1184900D02*
X1437284Y1184571D01*
G01X1436446Y1184243D02*
X1436781Y1183915D01*
G01X1440467Y1175877D02*
X1440970Y1175385D01*
G01X1437284Y1178502D02*
X1437619Y1178174D01*
G01X1436614Y1178502D02*
X1436949Y1178174D01*
G01X1437117Y1172432D02*
X1437619Y1171940D01*
G01X1436781Y1171612D02*
X1437117Y1171284D01*
G01X1437284Y1166035D02*
X1437619Y1165707D01*
G01X1436614Y1166035D02*
X1436949Y1165707D01*
G01X1436446Y1159637D02*
X1436781Y1159309D01*
G01X1436949Y1154716D02*
X1437117Y1154552D01*
G01X1436279Y1154716D02*
X1436781Y1154224D01*
G01X1436949Y1152091D02*
X1437284Y1151763D01*
G01X1440132Y1163410D02*
X1440970Y1162754D01*
G01X1437452Y1159473D02*
X1437954Y1159145D01*
G01X1440467Y1159965D02*
X1440132Y1159473D01*
G01X1436614Y1162754D02*
X1436279Y1162262D01*
G01X1441137Y1172104D02*
X1440802Y1171612D01*
G01X1436614Y1168823D02*
X1436279Y1168331D01*
G01X1437284Y1174893D02*
X1436949Y1174401D01*
G01X1436614Y1181291D02*
X1436279Y1180798D01*
G01X1436781Y1175385D02*
X1436279Y1174565D01*
G01X1441305Y1159965D02*
X1441137Y1159637D01*
G01X1436949Y1153239D02*
X1436781Y1152911D01*
G01X1436949Y1155864D02*
X1436781Y1155536D01*
G01X1437284Y1162262D02*
X1436949Y1161606D01*
G01X1440635Y1172760D02*
X1440467Y1172432D01*
G01X1437117Y1168167D02*
X1436949Y1167839D01*
G01X1441305Y1184571D02*
X1441137Y1184243D01*
G01X1437117Y1180634D02*
X1436949Y1180306D01*
G01X1436446Y1187524D02*
X1436279Y1187196D01*
G01X1441137Y1187524D02*
X1441305Y1187196D01*
G01X1440970Y1175385D02*
X1441305Y1174729D01*
G01X1436279Y1184571D02*
X1436446Y1184243D01*
G01X1436949Y1172760D02*
X1437117Y1172432D01*
G01X1436279Y1159965D02*
X1436446Y1159637D01*
G01X1436781Y1155044D02*
X1436949Y1154716D01*
G01X1440300Y1175057D02*
X1440635Y1174565D01*
G01X1436949Y1178994D02*
X1437284Y1178502D01*
G01X1436279Y1178994D02*
X1436614Y1178502D01*
G01X1436446Y1172104D02*
X1436781Y1171612D01*
G01X1440970Y1162754D02*
X1441305Y1162262D01*
G01X1440132Y1162426D02*
X1440467Y1161934D01*
G01X1436949Y1166527D02*
X1437284Y1166035D01*
G01X1436279Y1166527D02*
X1436614Y1166035D01*
G01X1437117Y1159965D02*
X1437452Y1159473D01*
G01X1436279Y1152091D02*
X1436614Y1151763D01*
G01X1436279Y1153732D02*
X1436111Y1153239D01*
G01X1436279Y1156356D02*
X1436111Y1155864D01*
G01X1441305Y1172596D02*
X1441137Y1172104D01*
G01X1436279Y1168331D02*
X1436111Y1167839D01*
G01X1436279Y1180798D02*
X1436111Y1180306D01*
G01X1441472Y1160621D02*
X1441305Y1159965D01*
G01X1440635Y1160621D02*
X1440467Y1159965D01*
G01X1440802Y1173417D02*
X1440635Y1172760D01*
G01X1436279Y1162262D02*
X1436111Y1161606D01*
G01X1441472Y1185228D02*
X1441305Y1184571D01*
G01X1436949Y1167839D02*
X1436781Y1167183D01*
G01X1440802Y1185556D02*
X1440635Y1184900D01*
G01X1436949Y1180306D02*
X1436781Y1179650D01*
G01X1436949Y1186868D02*
X1436781Y1186212D01*
G01X1436279Y1187196D02*
X1436111Y1186540D01*
G01X1441472Y1173581D02*
X1441305Y1172596D01*
G01X1436949Y1174401D02*
X1436781Y1173417D01*
G01X1436279Y1174565D02*
X1436111Y1173581D01*
G01X1441235Y1143151D02*
Y1142199D01*
G01Y1149450D02*
Y1148499D01*
G01Y1146300D02*
Y1145349D01*
G01Y1152600D02*
Y1151648D01*
G01Y1158899D02*
Y1157947D01*
G01Y1155749D02*
Y1154798D01*
G01Y1162048D02*
Y1161097D01*
G01Y1168348D02*
Y1167396D01*
G01Y1165198D02*
Y1164247D01*
G01Y1171497D02*
Y1170546D01*
G01Y1177796D02*
Y1176845D01*
G01Y1174647D02*
Y1173695D01*
G01Y1180946D02*
Y1179995D01*
G01Y1187245D02*
Y1186294D01*
G01Y1184096D02*
Y1183144D01*
G01Y1190395D02*
Y1189444D01*
G01Y1196694D02*
Y1195743D01*
G01Y1193544D02*
Y1192593D01*
G01X1441007Y1143151D02*
Y1142199D01*
G01Y1149450D02*
Y1148499D01*
G01Y1146300D02*
Y1145349D01*
G01Y1152600D02*
Y1151648D01*
G01Y1158899D02*
Y1157947D01*
G01Y1155749D02*
Y1154798D01*
G01Y1162048D02*
Y1161097D01*
G01Y1168348D02*
Y1167396D01*
G01Y1165198D02*
Y1164247D01*
G01Y1171497D02*
Y1170546D01*
G01Y1177796D02*
Y1176845D01*
G01Y1174647D02*
Y1173695D01*
G01Y1180946D02*
Y1179995D01*
G01Y1187245D02*
Y1186294D01*
G01Y1184096D02*
Y1183144D01*
G01Y1190395D02*
Y1189444D01*
G01Y1196694D02*
Y1195743D01*
G01Y1193544D02*
Y1192593D01*
G01X1440802Y1186212D02*
Y1185556D01*
G01X1440635Y1161277D02*
Y1160621D01*
G01X1439797Y1176041D02*
Y1175221D01*
G01X1441305Y1174729D02*
X1441472Y1173581D01*
G01X1440635Y1174565D02*
X1440802Y1173417D01*
G01X1436111Y1173581D02*
X1436279Y1172596D01*
G01X1441305Y1187196D02*
X1441472Y1186540D01*
G01X1440635Y1186868D02*
X1440802Y1186212D01*
G01X1436781Y1185556D02*
X1436949Y1184900D01*
G01X1436111Y1185228D02*
X1436279Y1184571D01*
G01X1441305Y1162262D02*
X1441472Y1161606D01*
G01X1436781Y1179650D02*
X1436949Y1178994D01*
G01X1436111Y1179650D02*
X1436279Y1178994D01*
G01X1440467Y1161934D02*
X1440635Y1161277D01*
G01X1436781Y1173417D02*
X1436949Y1172760D01*
G01X1436781Y1167183D02*
X1436949Y1166527D01*
G01X1436111Y1167183D02*
X1436279Y1166527D01*
G01X1436949Y1160621D02*
X1437117Y1159965D01*
G01X1436111Y1160621D02*
X1436279Y1159965D01*
G01Y1172596D02*
X1436446Y1172104D01*
G01X1436111Y1155208D02*
X1436279Y1154716D01*
G01X1436781Y1152583D02*
X1436949Y1152091D01*
G01X1436111Y1152583D02*
X1436279Y1152091D01*
G01X1439462Y1147990D02*
Y1144709D01*
G01X1439047Y1143129D02*
Y1142221D01*
G01Y1149428D02*
Y1148520D01*
G01Y1146279D02*
Y1145371D01*
G01Y1152578D02*
Y1151670D01*
G01Y1158877D02*
Y1157969D01*
G01Y1155728D02*
Y1154819D01*
G01Y1162027D02*
Y1161119D01*
G01Y1168326D02*
Y1167418D01*
G01Y1165177D02*
Y1164268D01*
G01Y1171476D02*
Y1170567D01*
G01Y1177775D02*
Y1176867D01*
G01Y1174625D02*
Y1173717D01*
G01Y1180925D02*
Y1180016D01*
G01Y1187224D02*
Y1186315D01*
G01Y1184074D02*
Y1183166D01*
G01Y1190373D02*
Y1189465D01*
G01Y1196673D02*
Y1195764D01*
G01Y1193523D02*
Y1192615D01*
G01X1438792Y1147826D02*
Y1144873D01*
G01Y1176041D02*
Y1171612D01*
G01X1438785Y1143129D02*
Y1142221D01*
G01Y1149428D02*
Y1148520D01*
G01Y1146279D02*
Y1145371D01*
G01Y1152578D02*
Y1151670D01*
G01Y1158877D02*
Y1157969D01*
G01Y1155728D02*
Y1154819D01*
G01Y1162027D02*
Y1161119D01*
G01Y1168326D02*
Y1167418D01*
G01Y1165177D02*
Y1164268D01*
G01Y1171476D02*
Y1170567D01*
G01Y1177775D02*
Y1176867D01*
G01Y1174625D02*
Y1173717D01*
G01Y1180925D02*
Y1180016D01*
G01Y1187224D02*
Y1186315D01*
G01Y1184074D02*
Y1183166D01*
G01Y1190373D02*
Y1189465D01*
G01Y1196673D02*
Y1195764D01*
G01Y1193523D02*
Y1192615D01*
G01X1438122Y1175221D02*
Y1171776D01*
G01X1437751Y1143109D02*
Y1142241D01*
G01Y1149408D02*
Y1148540D01*
G01Y1146259D02*
Y1145391D01*
G01Y1152558D02*
Y1151690D01*
G01Y1158857D02*
Y1157989D01*
G01Y1155707D02*
Y1154840D01*
G01Y1162007D02*
Y1161139D01*
G01Y1168306D02*
Y1167438D01*
G01Y1165156D02*
Y1164288D01*
G01Y1171455D02*
Y1170588D01*
G01Y1177755D02*
Y1176887D01*
G01Y1174605D02*
Y1173737D01*
G01Y1180904D02*
Y1180036D01*
G01Y1187204D02*
Y1186336D01*
G01Y1184054D02*
Y1183186D01*
G01Y1190353D02*
Y1189485D01*
G01Y1196652D02*
Y1195784D01*
G01Y1193503D02*
Y1192635D01*
G01X1436949Y1161606D02*
Y1160621D01*
G01X1436781Y1152911D02*
Y1152583D01*
G01Y1155536D02*
Y1155044D01*
G01Y1186212D02*
Y1185556D01*
G01X1436420Y1143103D02*
Y1142247D01*
G01Y1149402D02*
Y1148546D01*
G01Y1146253D02*
Y1145397D01*
G01Y1152552D02*
Y1151696D01*
G01Y1158851D02*
Y1157995D01*
G01Y1155702D02*
Y1154846D01*
G01Y1162001D02*
Y1161145D01*
G01Y1168300D02*
Y1167444D01*
G01Y1165150D02*
Y1164294D01*
G01Y1171450D02*
Y1170594D01*
G01Y1177749D02*
Y1176893D01*
G01Y1174599D02*
Y1173743D01*
G01Y1180898D02*
Y1180042D01*
G01Y1187198D02*
Y1186342D01*
G01Y1184048D02*
Y1183192D01*
G01Y1190347D02*
Y1189491D01*
G01Y1196646D02*
Y1195790D01*
G01Y1193497D02*
Y1192641D01*
G01X1436111Y1151763D02*
Y1150943D01*
G01Y1153239D02*
Y1152583D01*
G01Y1159145D02*
Y1158325D01*
G01Y1155864D02*
Y1155208D01*
G01Y1161606D02*
Y1160621D01*
G01Y1167839D02*
Y1167183D01*
G01Y1178174D02*
Y1177354D01*
G01Y1180306D02*
Y1179650D01*
G01Y1186540D02*
Y1185228D01*
G01X1433598Y1147006D02*
Y1145693D01*
G01Y1165707D02*
Y1164886D01*
G01Y1190641D02*
Y1189821D01*
G01X1426512Y1207242D02*
Y1202124D01*
G01X1457732Y1140707D02*
X1457220D01*
G01X1444212Y1140313D02*
X1443073D01*
G01X1469631Y1140116D02*
X1457535D01*
G01X1442772Y1140018D02*
X1442543D01*
G01X1470921Y1139860D02*
X1469507D01*
G01X1470921Y1139191D02*
X1469507D01*
G01X1442772Y1139033D02*
X1442543D01*
G01X1469631Y1138935D02*
X1457535D01*
G01X1443073Y1140313D02*
X1442684Y1140105D01*
G01X1443243Y1140313D02*
X1442772Y1140018D01*
G01X1442684Y1140105D02*
X1442543Y1140018D01*
G01X1469636Y1140130D02*
X1469855Y1139860D01*
G01X1469278Y1140116D02*
X1469507Y1139860D01*
G01X1470921D02*
Y1139191D01*
G01X1470574Y1139860D02*
Y1139191D01*
G01X1469631Y1140116D02*
Y1138935D01*
G01X1469278Y1140116D02*
Y1138935D01*
G01X1467296Y1140116D02*
Y1138935D01*
G01X1467186Y1140116D02*
Y1138935D01*
G01X1458405Y1140116D02*
Y1138935D01*
G01X1458295Y1140116D02*
Y1138935D01*
G01X1457929Y1140116D02*
Y1138935D01*
G01X1457732Y1140707D02*
Y1140116D01*
G01X1457535Y1140707D02*
Y1140116D01*
G01X1442684Y1140105D02*
Y1138946D01*
G01X1479661Y1207242D02*
X1461157D01*
G01X1457732Y1197400D02*
X1457220D01*
G01X1444212Y1197006D02*
X1443073D01*
G01X1469631Y1196809D02*
X1457535D01*
G01X1442772Y1196711D02*
X1442543D01*
G01X1470921Y1196553D02*
X1469507D01*
G01X1470921Y1195884D02*
X1469507D01*
G01X1442772Y1195726D02*
X1442543D01*
G01X1469631Y1195628D02*
X1457535D01*
G01X1444212Y1195431D02*
X1443073D01*
G01X1457732Y1195037D02*
X1457220D01*
G01X1457732Y1194250D02*
X1457220D01*
G01X1444212Y1193856D02*
X1443073D01*
G01X1469631Y1193659D02*
X1457535D01*
G01X1442772Y1193561D02*
X1442543D01*
G01X1470921Y1193403D02*
X1469507D01*
G01X1470921Y1192734D02*
X1469507D01*
G01X1442772Y1192577D02*
X1442543D01*
G01X1469631Y1192478D02*
X1457535D01*
G01X1444212Y1192281D02*
X1443073D01*
G01X1457732Y1191888D02*
X1457220D01*
G01X1457732Y1191100D02*
X1457220D01*
G01X1444212Y1190707D02*
X1443073D01*
G01X1469631Y1190510D02*
X1457535D01*
G01X1442772Y1190411D02*
X1442543D01*
G01X1470921Y1190254D02*
X1469507D01*
G01X1470921Y1189585D02*
X1469507D01*
G01X1442772Y1189427D02*
X1442543D01*
G01X1469631Y1189329D02*
X1457535D01*
G01X1444212Y1189132D02*
X1443073D01*
G01X1457732Y1188738D02*
X1457220D01*
G01X1457732Y1187951D02*
X1457220D01*
G01X1444212Y1187557D02*
X1443073D01*
G01X1469631Y1187360D02*
X1457535D01*
G01X1442772Y1187262D02*
X1442543D01*
G01X1470921Y1187104D02*
X1469507D01*
G01X1470921Y1186435D02*
X1469507D01*
G01X1442772Y1186277D02*
X1442543D01*
G01X1469631Y1186179D02*
X1457535D01*
G01X1444212Y1185982D02*
X1443073D01*
G01X1457732Y1185588D02*
X1457220D01*
G01X1457732Y1184801D02*
X1457220D01*
G01X1444212Y1184407D02*
X1443073D01*
G01X1469631Y1184211D02*
X1457535D01*
G01X1442772Y1184112D02*
X1442543D01*
G01X1470921Y1183955D02*
X1469507D01*
G01X1470921Y1183285D02*
X1469507D01*
G01X1442772Y1183128D02*
X1442543D01*
G01X1469631Y1183029D02*
X1457535D01*
G01X1444212Y1182833D02*
X1443073D01*
G01X1457732Y1182439D02*
X1457220D01*
G01X1457732Y1181651D02*
X1457220D01*
G01X1444212Y1181258D02*
X1443073D01*
G01X1469631Y1181061D02*
X1457535D01*
G01X1442772Y1180963D02*
X1442543D01*
G01X1470921Y1180805D02*
X1469507D01*
G01X1470921Y1180136D02*
X1469507D01*
G01X1442772Y1179978D02*
X1442543D01*
G01X1469631Y1179880D02*
X1457535D01*
G01X1444212Y1179683D02*
X1443073D01*
G01X1457732Y1179289D02*
X1457220D01*
G01X1457732Y1178502D02*
X1457220D01*
G01X1444212Y1178108D02*
X1443073D01*
G01X1469631Y1177911D02*
X1457535D01*
G01X1442772Y1177813D02*
X1442543D01*
G01X1470921Y1177655D02*
X1469507D01*
G01X1470921Y1176986D02*
X1469507D01*
G01X1442772Y1176829D02*
X1442543D01*
G01X1469631Y1176730D02*
X1457535D01*
G01X1444212Y1176533D02*
X1443073D01*
G01X1457732Y1176140D02*
X1457220D01*
G01X1457732Y1175352D02*
X1457220D01*
G01X1444212Y1174959D02*
X1443073D01*
G01X1469631Y1174762D02*
X1457535D01*
G01X1442772Y1174663D02*
X1442543D01*
G01X1470921Y1174506D02*
X1469507D01*
G01X1470921Y1173837D02*
X1469507D01*
G01X1442772Y1173679D02*
X1442543D01*
G01X1469631Y1173581D02*
X1457535D01*
G01X1444212Y1173384D02*
X1443073D01*
G01X1457732Y1172990D02*
X1457220D01*
G01X1457732Y1172203D02*
X1457220D01*
G01X1444212Y1171809D02*
X1443073D01*
G01X1469631Y1171612D02*
X1457535D01*
G01X1442772Y1171514D02*
X1442543D01*
G01X1470921Y1171356D02*
X1469507D01*
G01X1470921Y1170687D02*
X1469507D01*
G01X1442772Y1170529D02*
X1442543D01*
G01X1469631Y1170431D02*
X1457535D01*
G01X1444212Y1170234D02*
X1443073D01*
G01X1457732Y1169840D02*
X1457220D01*
G01X1457732Y1169053D02*
X1457220D01*
G01X1444212Y1168659D02*
X1443073D01*
G01X1469631Y1168463D02*
X1457535D01*
G01X1442772Y1168364D02*
X1442543D01*
G01X1470921Y1168207D02*
X1469507D01*
G01X1470921Y1167537D02*
X1469507D01*
G01X1442772Y1167380D02*
X1442543D01*
G01X1469631Y1167281D02*
X1457535D01*
G01X1444212Y1167085D02*
X1443073D01*
G01X1457732Y1166691D02*
X1457220D01*
G01X1457732Y1165903D02*
X1457220D01*
G01X1444212Y1165510D02*
X1443073D01*
G01X1469631Y1165313D02*
X1457535D01*
G01X1442772Y1165214D02*
X1442543D01*
G01X1470921Y1165057D02*
X1469507D01*
G01X1470921Y1164388D02*
X1469507D01*
G01X1442772Y1164230D02*
X1442543D01*
G01X1469631Y1164132D02*
X1457535D01*
G01X1444212Y1163935D02*
X1443073D01*
G01X1457732Y1163541D02*
X1457220D01*
G01X1457732Y1162754D02*
X1457220D01*
G01X1444212Y1162360D02*
X1443073D01*
G01X1469631Y1162163D02*
X1457535D01*
G01X1442772Y1162065D02*
X1442543D01*
G01X1470921Y1161907D02*
X1469507D01*
G01X1470921Y1161238D02*
X1469507D01*
G01X1442772Y1161081D02*
X1442543D01*
G01X1469631Y1160982D02*
X1457535D01*
G01X1444212Y1160785D02*
X1443073D01*
G01X1457732Y1160392D02*
X1457220D01*
G01X1457732Y1159604D02*
X1457220D01*
G01X1444212Y1159211D02*
X1443073D01*
G01X1469631Y1159014D02*
X1457535D01*
G01X1442772Y1158915D02*
X1442543D01*
G01X1470921Y1158758D02*
X1469507D01*
G01X1470921Y1158088D02*
X1469507D01*
G01X1442772Y1157931D02*
X1442543D01*
G01X1469631Y1157833D02*
X1457535D01*
G01X1444212Y1157636D02*
X1443073D01*
G01X1457732Y1157242D02*
X1457220D01*
G01X1457732Y1156455D02*
X1457220D01*
G01X1444212Y1156061D02*
X1443073D01*
G01X1469631Y1155864D02*
X1457535D01*
G01X1442772Y1155766D02*
X1442543D01*
G01X1470921Y1155608D02*
X1469507D01*
G01X1470921Y1154939D02*
X1469507D01*
G01X1442772Y1154781D02*
X1442543D01*
G01X1469631Y1154683D02*
X1457535D01*
G01X1444212Y1154486D02*
X1443073D01*
G01X1457732Y1154092D02*
X1457220D01*
G01X1457732Y1153305D02*
X1457220D01*
G01X1444212Y1152911D02*
X1443073D01*
G01X1469631Y1152714D02*
X1457535D01*
G01X1442772Y1152616D02*
X1442543D01*
G01X1470921Y1152459D02*
X1469507D01*
G01X1470921Y1151789D02*
X1469507D01*
G01X1442772Y1151632D02*
X1442543D01*
G01X1469631Y1151533D02*
X1457535D01*
G01X1444212Y1151337D02*
X1443073D01*
G01X1457732Y1150943D02*
X1457220D01*
G01X1457732Y1150155D02*
X1457220D01*
G01X1444212Y1149762D02*
X1443073D01*
G01X1469631Y1149565D02*
X1457535D01*
G01X1442772Y1149466D02*
X1442543D01*
G01X1470921Y1149309D02*
X1469507D01*
G01X1470921Y1148640D02*
X1469507D01*
G01X1442772Y1148482D02*
X1442543D01*
G01X1469631Y1148384D02*
X1457535D01*
G01X1444212Y1148187D02*
X1443073D01*
G01X1457732Y1147793D02*
X1457220D01*
G01X1457732Y1147006D02*
X1457220D01*
G01X1444212Y1146612D02*
X1443073D01*
G01X1469631Y1146415D02*
X1457535D01*
G01X1442772Y1146317D02*
X1442543D01*
G01X1470921Y1146159D02*
X1469507D01*
G01X1470921Y1145490D02*
X1469507D01*
G01X1442772Y1145333D02*
X1442543D01*
G01X1469631Y1145234D02*
X1457535D01*
G01X1444212Y1145037D02*
X1443073D01*
G01X1457732Y1144644D02*
X1457220D01*
G01X1457732Y1143856D02*
X1457220D01*
G01X1444212Y1143463D02*
X1443073D01*
G01X1469631Y1143266D02*
X1457535D01*
G01X1442772Y1143167D02*
X1442543D01*
G01X1470921Y1143010D02*
X1469507D01*
G01X1470921Y1142340D02*
X1469507D01*
G01X1442772Y1142183D02*
X1442543D01*
G01X1469631Y1142085D02*
X1457535D01*
G01X1444212Y1141888D02*
X1443073D01*
G01X1457732Y1141494D02*
X1457220D01*
G01X1443073Y1143463D02*
X1442684Y1143255D01*
G01X1443073Y1146612D02*
X1442684Y1146405D01*
G01X1443073Y1149762D02*
X1442684Y1149554D01*
G01X1443073Y1152911D02*
X1442684Y1152704D01*
G01X1443073Y1156061D02*
X1442684Y1155853D01*
G01X1443073Y1159211D02*
X1442684Y1159003D01*
G01X1443073Y1162360D02*
X1442684Y1162153D01*
G01X1443073Y1165510D02*
X1442684Y1165302D01*
G01X1443073Y1168659D02*
X1442684Y1168452D01*
G01X1443073Y1171809D02*
X1442684Y1171601D01*
G01X1443073Y1174959D02*
X1442684Y1174751D01*
G01X1443073Y1178108D02*
X1442684Y1177901D01*
G01X1443073Y1181258D02*
X1442684Y1181050D01*
G01X1443073Y1184407D02*
X1442684Y1184200D01*
G01X1443073Y1187557D02*
X1442684Y1187350D01*
G01X1443073Y1190707D02*
X1442684Y1190499D01*
G01X1443073Y1193856D02*
X1442684Y1193649D01*
G01X1443073Y1197006D02*
X1442684Y1196798D01*
G01X1443243Y1143463D02*
X1442772Y1143167D01*
G01X1442684Y1143255D02*
X1442543Y1143167D01*
G01X1443243Y1146612D02*
X1442772Y1146317D01*
G01X1442684Y1146405D02*
X1442543Y1146317D01*
G01X1443243Y1149762D02*
X1442772Y1149466D01*
G01X1442684Y1149554D02*
X1442543Y1149466D01*
G01X1443243Y1152911D02*
X1442772Y1152616D01*
G01X1442684Y1152704D02*
X1442543Y1152616D01*
G01X1443243Y1156061D02*
X1442772Y1155766D01*
G01X1442684Y1155853D02*
X1442543Y1155766D01*
G01X1443243Y1159211D02*
X1442772Y1158915D01*
G01X1442684Y1159003D02*
X1442543Y1158915D01*
G01X1443243Y1162360D02*
X1442772Y1162065D01*
G01X1442684Y1162153D02*
X1442543Y1162065D01*
G01X1443243Y1165510D02*
X1442772Y1165214D01*
G01X1442684Y1165302D02*
X1442543Y1165214D01*
G01X1443243Y1168659D02*
X1442772Y1168364D01*
G01X1442684Y1168452D02*
X1442543Y1168364D01*
G01X1443243Y1171809D02*
X1442772Y1171514D01*
G01X1442684Y1171601D02*
X1442543Y1171514D01*
G01X1443243Y1174959D02*
X1442772Y1174663D01*
G01X1442684Y1174751D02*
X1442543Y1174663D01*
G01X1443243Y1178108D02*
X1442772Y1177813D01*
G01X1442684Y1177901D02*
X1442543Y1177813D01*
G01X1443243Y1181258D02*
X1442772Y1180963D01*
G01X1442684Y1181050D02*
X1442543Y1180963D01*
G01X1443243Y1184407D02*
X1442772Y1184112D01*
G01X1442684Y1184200D02*
X1442543Y1184112D01*
G01X1443243Y1187557D02*
X1442772Y1187262D01*
G01X1442684Y1187350D02*
X1442543Y1187262D01*
G01X1443243Y1190707D02*
X1442772Y1190411D01*
G01X1442684Y1190499D02*
X1442543Y1190411D01*
G01X1443243Y1193856D02*
X1442772Y1193561D01*
G01X1442684Y1193649D02*
X1442543Y1193561D01*
G01X1443243Y1197006D02*
X1442772Y1196711D01*
G01X1442684Y1196798D02*
X1442543Y1196711D01*
G01X1469507Y1142340D02*
X1469278Y1142085D01*
G01X1469507Y1145490D02*
X1469278Y1145234D01*
G01X1469507Y1148640D02*
X1469278Y1148384D01*
G01X1469507Y1151789D02*
X1469278Y1151533D01*
G01X1442772Y1195726D02*
X1443243Y1195431D01*
G01X1442543Y1195726D02*
X1442684Y1195638D01*
G01X1442772Y1192577D02*
X1443243Y1192281D01*
G01X1442543Y1192577D02*
X1442684Y1192489D01*
G01X1442772Y1189427D02*
X1443243Y1189132D01*
G01X1442543Y1189427D02*
X1442684Y1189339D01*
G01X1442772Y1186277D02*
X1443243Y1185982D01*
G01X1442543Y1186277D02*
X1442684Y1186190D01*
G01X1442772Y1183128D02*
X1443243Y1182833D01*
G01X1442543Y1183128D02*
X1442684Y1183040D01*
G01X1442772Y1179978D02*
X1443243Y1179683D01*
G01X1442543Y1179978D02*
X1442684Y1179890D01*
G01X1442772Y1176829D02*
X1443243Y1176533D01*
G01X1442543Y1176829D02*
X1442684Y1176741D01*
G01X1442772Y1173679D02*
X1443243Y1173384D01*
G01X1442543Y1173679D02*
X1442684Y1173591D01*
G01X1442772Y1170529D02*
X1443243Y1170234D01*
G01X1442543Y1170529D02*
X1442684Y1170442D01*
G01X1442772Y1167380D02*
X1443243Y1167085D01*
G01X1442543Y1167380D02*
X1442684Y1167292D01*
G01X1442772Y1164230D02*
X1443243Y1163935D01*
G01X1442543Y1164230D02*
X1442684Y1164142D01*
G01X1442772Y1161081D02*
X1443243Y1160785D01*
G01X1442543Y1161081D02*
X1442684Y1160993D01*
G01X1442772Y1157931D02*
X1443243Y1157636D01*
G01X1442543Y1157931D02*
X1442684Y1157843D01*
G01X1442772Y1154781D02*
X1443243Y1154486D01*
G01X1442543Y1154781D02*
X1442684Y1154694D01*
G01X1442772Y1151632D02*
X1443243Y1151337D01*
G01X1442543Y1151632D02*
X1442684Y1151544D01*
G01Y1195638D02*
X1443073Y1195431D01*
G01X1442684Y1192489D02*
X1443073Y1192281D01*
G01X1442684Y1189339D02*
X1443073Y1189132D01*
G01X1442684Y1186190D02*
X1443073Y1185982D01*
G01X1442684Y1183040D02*
X1443073Y1182833D01*
G01X1442684Y1179890D02*
X1443073Y1179683D01*
G01X1442684Y1176741D02*
X1443073Y1176533D01*
G01X1442684Y1173591D02*
X1443073Y1173384D01*
G01X1442684Y1170442D02*
X1443073Y1170234D01*
G01X1442684Y1167292D02*
X1443073Y1167085D01*
G01X1442684Y1164142D02*
X1443073Y1163935D01*
G01X1442684Y1160993D02*
X1443073Y1160785D01*
G01X1442684Y1157843D02*
X1443073Y1157636D01*
G01X1442684Y1154694D02*
X1443073Y1154486D01*
G01X1442684Y1151544D02*
X1443073Y1151337D01*
G01X1442684Y1148394D02*
X1443073Y1148187D01*
G01X1442684Y1145245D02*
X1443073Y1145037D01*
G01X1442684Y1142095D02*
X1443073Y1141888D01*
G01X1461157Y1207242D02*
X1457220Y1203305D01*
G01X1469507Y1154939D02*
X1469278Y1154683D01*
G01X1469507Y1158088D02*
X1469278Y1157833D01*
G01X1469507Y1161238D02*
X1469278Y1160982D01*
G01X1469507Y1164388D02*
X1469278Y1164132D01*
G01X1469507Y1167537D02*
X1469278Y1167281D01*
G01X1469507Y1170687D02*
X1469278Y1170431D01*
G01X1469507Y1173837D02*
X1469278Y1173581D01*
G01X1469507Y1176986D02*
X1469278Y1176730D01*
G01X1469507Y1180136D02*
X1469278Y1179880D01*
G01X1469507Y1183285D02*
X1469278Y1183029D01*
G01X1469507Y1186435D02*
X1469278Y1186179D01*
G01X1469507Y1189585D02*
X1469278Y1189329D01*
G01X1469507Y1192734D02*
X1469278Y1192478D01*
G01X1469507Y1195884D02*
X1469278Y1195628D01*
G01X1469855Y1142340D02*
X1469636Y1142070D01*
G01X1469855Y1145490D02*
X1469636Y1145220D01*
G01X1469855Y1148640D02*
X1469636Y1148370D01*
G01X1469855Y1151789D02*
X1469636Y1151519D01*
G01X1469855Y1154939D02*
X1469636Y1154669D01*
G01X1469855Y1158088D02*
X1469636Y1157818D01*
G01X1469855Y1161238D02*
X1469636Y1160968D01*
G01X1469855Y1164388D02*
X1469636Y1164118D01*
G01X1469855Y1167537D02*
X1469636Y1167267D01*
G01X1469855Y1170687D02*
X1469636Y1170417D01*
G01X1469855Y1173837D02*
X1469636Y1173566D01*
G01X1469855Y1176986D02*
X1469636Y1176716D01*
G01X1469855Y1180136D02*
X1469636Y1179866D01*
G01X1469855Y1183285D02*
X1469636Y1183015D01*
G01X1469855Y1186435D02*
X1469636Y1186165D01*
G01X1469855Y1189585D02*
X1469636Y1189315D01*
G01X1469855Y1192734D02*
X1469636Y1192464D01*
G01X1469855Y1195884D02*
X1469636Y1195614D01*
G01Y1196823D02*
X1469855Y1196553D01*
G01X1469636Y1193673D02*
X1469855Y1193403D01*
G01X1469636Y1190524D02*
X1469855Y1190254D01*
G01X1469636Y1187374D02*
X1469855Y1187104D01*
G01X1469636Y1184225D02*
X1469855Y1183955D01*
G01X1469636Y1181075D02*
X1469855Y1180805D01*
G01X1469636Y1177925D02*
X1469855Y1177655D01*
G01X1469636Y1174776D02*
X1469855Y1174506D01*
G01X1469636Y1171626D02*
X1469855Y1171356D01*
G01X1469636Y1168477D02*
X1469855Y1168207D01*
G01X1469636Y1165327D02*
X1469855Y1165057D01*
G01X1469636Y1162177D02*
X1469855Y1161907D01*
G01X1469278Y1196809D02*
X1469507Y1196553D01*
G01X1469278Y1193659D02*
X1469507Y1193403D01*
G01X1469278Y1190510D02*
X1469507Y1190254D01*
G01X1469278Y1187360D02*
X1469507Y1187104D01*
G01X1469278Y1184211D02*
X1469507Y1183955D01*
G01X1469278Y1181061D02*
X1469507Y1180805D01*
G01X1469278Y1177911D02*
X1469507Y1177655D01*
G01X1469278Y1174762D02*
X1469507Y1174506D01*
G01X1469278Y1171612D02*
X1469507Y1171356D01*
G01X1469278Y1168463D02*
X1469507Y1168207D01*
G01X1469278Y1165313D02*
X1469507Y1165057D01*
G01X1469278Y1162163D02*
X1469507Y1161907D01*
G01X1469278Y1159014D02*
X1469507Y1158758D01*
G01X1469278Y1155864D02*
X1469507Y1155608D01*
G01X1469278Y1152714D02*
X1469507Y1152459D01*
G01X1469278Y1149565D02*
X1469507Y1149309D01*
G01X1469278Y1146415D02*
X1469507Y1146159D01*
G01X1442772Y1148482D02*
X1443243Y1148187D01*
G01X1442543Y1148482D02*
X1442684Y1148394D01*
G01X1442772Y1145333D02*
X1443243Y1145037D01*
G01X1442543Y1145333D02*
X1442684Y1145245D01*
G01X1442772Y1142183D02*
X1443243Y1141888D01*
G01X1442543Y1142183D02*
X1442684Y1142095D01*
G01X1469636Y1159028D02*
X1469855Y1158758D01*
G01X1469636Y1155878D02*
X1469855Y1155608D01*
G01X1469636Y1152729D02*
X1469855Y1152459D01*
G01X1469636Y1149579D02*
X1469855Y1149309D01*
G01X1469636Y1146429D02*
X1469855Y1146159D01*
G01X1469636Y1143280D02*
X1469855Y1143010D01*
G01X1469278Y1143266D02*
X1469507Y1143010D01*
G01X1479661Y1236770D02*
Y1207242D01*
G01X1470921Y1143010D02*
Y1142340D01*
G01Y1149309D02*
Y1148640D01*
G01Y1146159D02*
Y1145490D01*
G01Y1152459D02*
Y1151789D01*
G01Y1158758D02*
Y1158088D01*
G01Y1155608D02*
Y1154939D01*
G01Y1161907D02*
Y1161238D01*
G01Y1168207D02*
Y1167537D01*
G01Y1165057D02*
Y1164388D01*
G01Y1171356D02*
Y1170687D01*
G01Y1177655D02*
Y1176986D01*
G01Y1174506D02*
Y1173837D01*
G01Y1180805D02*
Y1180136D01*
G01Y1187104D02*
Y1186435D01*
G01Y1183955D02*
Y1183285D01*
G01Y1190254D02*
Y1189585D01*
G01Y1196553D02*
Y1195884D01*
G01Y1193403D02*
Y1192734D01*
G01X1470574Y1143010D02*
Y1142340D01*
G01Y1149309D02*
Y1148640D01*
G01Y1146159D02*
Y1145490D01*
G01Y1152459D02*
Y1151789D01*
G01Y1158758D02*
Y1158088D01*
G01Y1155608D02*
Y1154939D01*
G01Y1161907D02*
Y1161238D01*
G01Y1168207D02*
Y1167537D01*
G01Y1165057D02*
Y1164388D01*
G01Y1171356D02*
Y1170687D01*
G01Y1177655D02*
Y1176986D01*
G01Y1174506D02*
Y1173837D01*
G01Y1180805D02*
Y1180136D01*
G01Y1187104D02*
Y1186435D01*
G01Y1183955D02*
Y1183285D01*
G01Y1190254D02*
Y1189585D01*
G01Y1196553D02*
Y1195884D01*
G01Y1193403D02*
Y1192734D01*
G01X1469631Y1143266D02*
Y1142085D01*
G01Y1149565D02*
Y1148384D01*
G01Y1146415D02*
Y1145234D01*
G01Y1152714D02*
Y1151533D01*
G01Y1159014D02*
Y1157833D01*
G01Y1155864D02*
Y1154683D01*
G01Y1162163D02*
Y1160982D01*
G01Y1168463D02*
Y1167281D01*
G01Y1165313D02*
Y1164132D01*
G01Y1171612D02*
Y1170431D01*
G01Y1177911D02*
Y1176730D01*
G01Y1174762D02*
Y1173581D01*
G01Y1181061D02*
Y1179880D01*
G01Y1187360D02*
Y1186179D01*
G01Y1184211D02*
Y1183029D01*
G01Y1190510D02*
Y1189329D01*
G01Y1196809D02*
Y1195628D01*
G01Y1193659D02*
Y1192478D01*
G01X1469278Y1143266D02*
Y1142085D01*
G01Y1149565D02*
Y1148384D01*
G01Y1146415D02*
Y1145234D01*
G01Y1152714D02*
Y1151533D01*
G01Y1159014D02*
Y1157833D01*
G01Y1155864D02*
Y1154683D01*
G01Y1162163D02*
Y1160982D01*
G01Y1168463D02*
Y1167281D01*
G01Y1165313D02*
Y1164132D01*
G01Y1171612D02*
Y1170431D01*
G01Y1177911D02*
Y1176730D01*
G01Y1174762D02*
Y1173581D01*
G01Y1181061D02*
Y1179880D01*
G01Y1187360D02*
Y1186179D01*
G01Y1184211D02*
Y1183029D01*
G01Y1190510D02*
Y1189329D01*
G01Y1196809D02*
Y1195628D01*
G01Y1193659D02*
Y1192478D01*
G01X1467296Y1143266D02*
Y1142085D01*
G01Y1149565D02*
Y1148384D01*
G01Y1146415D02*
Y1145234D01*
G01Y1152714D02*
Y1151533D01*
G01Y1159014D02*
Y1157833D01*
G01Y1155864D02*
Y1154683D01*
G01Y1162163D02*
Y1160982D01*
G01Y1168463D02*
Y1167281D01*
G01Y1165313D02*
Y1164132D01*
G01Y1171612D02*
Y1170431D01*
G01Y1177911D02*
Y1176730D01*
G01Y1174762D02*
Y1173581D01*
G01Y1181061D02*
Y1179880D01*
G01Y1187360D02*
Y1186179D01*
G01Y1184211D02*
Y1183029D01*
G01Y1190510D02*
Y1189329D01*
G01Y1196809D02*
Y1195628D01*
G01Y1193659D02*
Y1192478D01*
G01X1467186Y1143266D02*
Y1142085D01*
G01Y1149565D02*
Y1148384D01*
G01Y1146415D02*
Y1145234D01*
G01Y1152714D02*
Y1151533D01*
G01Y1159014D02*
Y1157833D01*
G01Y1155864D02*
Y1154683D01*
G01Y1162163D02*
Y1160982D01*
G01Y1168463D02*
Y1167281D01*
G01Y1165313D02*
Y1164132D01*
G01Y1171612D02*
Y1170431D01*
G01Y1177911D02*
Y1176730D01*
G01Y1174762D02*
Y1173581D01*
G01Y1181061D02*
Y1179880D01*
G01Y1187360D02*
Y1186179D01*
G01Y1184211D02*
Y1183029D01*
G01Y1190510D02*
Y1189329D01*
G01Y1196809D02*
Y1195628D01*
G01Y1193659D02*
Y1192478D01*
G01X1458405Y1143266D02*
Y1142085D01*
G01Y1149565D02*
Y1148384D01*
G01Y1146415D02*
Y1145234D01*
G01Y1152714D02*
Y1151533D01*
G01Y1159014D02*
Y1157833D01*
G01Y1155864D02*
Y1154683D01*
G01Y1162163D02*
Y1160982D01*
G01Y1168463D02*
Y1167281D01*
G01Y1165313D02*
Y1164132D01*
G01Y1171612D02*
Y1170431D01*
G01Y1177911D02*
Y1176730D01*
G01Y1174762D02*
Y1173581D01*
G01Y1181061D02*
Y1179880D01*
G01Y1187360D02*
Y1186179D01*
G01Y1184211D02*
Y1183029D01*
G01Y1190510D02*
Y1189329D01*
G01Y1196809D02*
Y1195628D01*
G01Y1193659D02*
Y1192478D01*
G01X1458295Y1143266D02*
Y1142085D01*
G01Y1149565D02*
Y1148384D01*
G01Y1146415D02*
Y1145234D01*
G01Y1152714D02*
Y1151533D01*
G01Y1159014D02*
Y1157833D01*
G01Y1155864D02*
Y1154683D01*
G01Y1162163D02*
Y1160982D01*
G01Y1168463D02*
Y1167281D01*
G01Y1165313D02*
Y1164132D01*
G01Y1171612D02*
Y1170431D01*
G01Y1177911D02*
Y1176730D01*
G01Y1174762D02*
Y1173581D01*
G01Y1181061D02*
Y1179880D01*
G01Y1187360D02*
Y1186179D01*
G01Y1184211D02*
Y1183029D01*
G01Y1190510D02*
Y1189329D01*
G01Y1196809D02*
Y1195628D01*
G01Y1193659D02*
Y1192478D01*
G01X1457929Y1143266D02*
Y1142085D01*
G01Y1149565D02*
Y1148384D01*
G01Y1146415D02*
Y1145234D01*
G01Y1152714D02*
Y1151533D01*
G01Y1159014D02*
Y1157833D01*
G01Y1155864D02*
Y1154683D01*
G01Y1162163D02*
Y1160982D01*
G01Y1168463D02*
Y1167281D01*
G01Y1165313D02*
Y1164132D01*
G01Y1171612D02*
Y1170431D01*
G01Y1177911D02*
Y1176730D01*
G01Y1174762D02*
Y1173581D01*
G01Y1181061D02*
Y1179880D01*
G01Y1187360D02*
Y1186179D01*
G01Y1184211D02*
Y1183029D01*
G01Y1190510D02*
Y1189329D01*
G01Y1196809D02*
Y1195628D01*
G01Y1193659D02*
Y1192478D01*
G01X1457732Y1145234D02*
Y1144644D01*
G01Y1142085D02*
Y1141494D01*
G01Y1143856D02*
Y1143266D01*
G01Y1148384D02*
Y1147793D01*
G01Y1150155D02*
Y1149565D01*
G01Y1147006D02*
Y1146415D01*
G01Y1154683D02*
Y1154092D01*
G01Y1151533D02*
Y1150943D01*
G01Y1153305D02*
Y1152714D01*
G01Y1157833D02*
Y1157242D01*
G01Y1159604D02*
Y1159014D01*
G01Y1156455D02*
Y1155864D01*
G01Y1164132D02*
Y1163541D01*
G01Y1160982D02*
Y1160392D01*
G01Y1162754D02*
Y1162163D01*
G01Y1167281D02*
Y1166691D01*
G01Y1169053D02*
Y1168463D01*
G01Y1165903D02*
Y1165313D01*
G01Y1173581D02*
Y1172990D01*
G01Y1170431D02*
Y1169840D01*
G01Y1172203D02*
Y1171612D01*
G01Y1176730D02*
Y1176140D01*
G01Y1175352D02*
Y1174762D01*
G01Y1183029D02*
Y1182439D01*
G01Y1179880D02*
Y1179289D01*
G01Y1181651D02*
Y1181061D01*
G01Y1178502D02*
Y1177911D01*
G01Y1186179D02*
Y1185588D01*
G01Y1184801D02*
Y1184211D01*
G01Y1192478D02*
Y1191888D01*
G01Y1189329D02*
Y1188738D01*
G01Y1191100D02*
Y1190510D01*
G01Y1187951D02*
Y1187360D01*
G01Y1195628D02*
Y1195037D01*
G01Y1194250D02*
Y1193659D01*
G01Y1197400D02*
Y1196809D01*
G01X1457535Y1145234D02*
Y1144644D01*
G01Y1142085D02*
Y1141494D01*
G01Y1143856D02*
Y1143266D01*
G01Y1148384D02*
Y1147793D01*
G01Y1150155D02*
Y1149565D01*
G01Y1147006D02*
Y1146415D01*
G01Y1154683D02*
Y1154092D01*
G01Y1151533D02*
Y1150943D01*
G01Y1153305D02*
Y1152714D01*
G01Y1157833D02*
Y1157242D01*
G01Y1159604D02*
Y1159014D01*
G01Y1156455D02*
Y1155864D01*
G01Y1164132D02*
Y1163541D01*
G01Y1160982D02*
Y1160392D01*
G01Y1162754D02*
Y1162163D01*
G01Y1167281D02*
Y1166691D01*
G01Y1169053D02*
Y1168463D01*
G01Y1165903D02*
Y1165313D01*
G01Y1173581D02*
Y1172990D01*
G01Y1170431D02*
Y1169840D01*
G01Y1172203D02*
Y1171612D01*
G01Y1176730D02*
Y1176140D01*
G01Y1175352D02*
Y1174762D01*
G01Y1183029D02*
Y1182439D01*
G01Y1179880D02*
Y1179289D01*
G01Y1181651D02*
Y1181061D01*
G01Y1178502D02*
Y1177911D01*
G01Y1186179D02*
Y1185588D01*
G01Y1184801D02*
Y1184211D01*
G01Y1192478D02*
Y1191888D01*
G01Y1189329D02*
Y1188738D01*
G01Y1191100D02*
Y1190510D01*
G01Y1187951D02*
Y1187360D01*
G01Y1195628D02*
Y1195037D01*
G01Y1194250D02*
Y1193659D01*
G01Y1197400D02*
Y1196809D01*
G01X1444212Y1143463D02*
Y1141888D01*
G01Y1149762D02*
Y1148187D01*
G01Y1146612D02*
Y1145037D01*
G01Y1152911D02*
Y1151337D01*
G01Y1159211D02*
Y1157636D01*
G01Y1156061D02*
Y1154486D01*
G01Y1162360D02*
Y1160785D01*
G01Y1168659D02*
Y1167085D01*
G01Y1165510D02*
Y1163935D01*
G01Y1171809D02*
Y1170234D01*
G01Y1178108D02*
Y1176533D01*
G01Y1174959D02*
Y1173384D01*
G01Y1181258D02*
Y1179683D01*
G01Y1187557D02*
Y1185982D01*
G01Y1184407D02*
Y1182833D01*
G01Y1190707D02*
Y1189132D01*
G01Y1197006D02*
Y1195431D01*
G01Y1193856D02*
Y1192281D01*
G01X1444153Y1159145D02*
Y1158325D01*
G01X1442684Y1143255D02*
Y1142095D01*
G01Y1149554D02*
Y1148394D01*
G01Y1146405D02*
Y1145245D01*
G01Y1152704D02*
Y1151544D01*
G01Y1159003D02*
Y1157843D01*
G01Y1155853D02*
Y1154694D01*
G01Y1162153D02*
Y1160993D01*
G01Y1168452D02*
Y1167292D01*
G01Y1165302D02*
Y1164142D01*
G01Y1171601D02*
Y1170442D01*
G01Y1177901D02*
Y1176741D01*
G01Y1174751D02*
Y1173591D01*
G01Y1181050D02*
Y1179890D01*
G01Y1187350D02*
Y1186190D01*
G01Y1184200D02*
Y1183040D01*
G01Y1190499D02*
Y1189339D01*
G01Y1196798D02*
Y1195638D01*
G01Y1193649D02*
Y1192489D01*
G01X1441472Y1144053D02*
Y1143069D01*
G01Y1149630D02*
Y1148646D01*
G01Y1154388D02*
Y1153567D01*
G01Y1151763D02*
Y1150943D01*
G01Y1157012D02*
Y1156192D01*
G01Y1161606D02*
Y1160621D01*
G01Y1165707D02*
Y1164886D01*
G01Y1169480D02*
Y1168659D01*
G01Y1178174D02*
Y1177354D01*
G01Y1181947D02*
Y1181127D01*
G01Y1186540D02*
Y1185228D01*
G01Y1190641D02*
Y1189821D01*
G01X1469048Y1227321D02*
G03Y1218659I-17J-4331D01*
G01X1469081Y1218660D02*
G03Y1227320I-50J4330D01*
G01X1473362Y1222990D02*
G03I-4331J0D01*
G01X1469113Y1227320D02*
X1448165Y1227714D01*
G01D02*
X1469034Y1227321D01*
G01X1479661Y1236770D02*
X1448165D01*
G01X1479661Y1227321D02*
X1469031D01*
G01X1479661Y1218659D02*
X1469031D01*
G01X1469038D02*
X1448165Y1218266D01*
G01X1469113Y1218660D02*
X1448165Y1218266D01*
G01X1496457Y1259537D02*
X1493047Y1261506D01*
G01X1497767Y1266776D02*
X1493047Y1262135D01*
G01Y1263238D02*
X1497772Y1267884D01*
G01X1493047Y1261506D02*
Y1263238D01*
G01X1448165Y1236770D02*
Y1215903D01*
G01X1426512Y1361966D02*
Y1356848D01*
G01X1469048Y1345431D02*
G03Y1336770I-17J-4331D01*
G01X1469081D02*
G03Y1345431I-50J4330D01*
G01X1473362Y1341100D02*
G03I-4331J0D01*
G01X1497673Y1303140D02*
G03I-6988J0D01*
G01X1506433D02*
G03I-15748J0D01*
G01X1479661Y1356848D02*
X1461157D01*
G01X1469113Y1345430D02*
X1448165Y1345825D01*
G01X1469038Y1345431D02*
X1448165Y1345825D01*
G01X1479661Y1345431D02*
X1469031D01*
G01X1479661Y1336770D02*
X1469031D01*
G01X1479661Y1327321D02*
X1448165D01*
G01Y1336376D02*
X1469034Y1336769D01*
G01X1469113Y1336770D02*
X1448165Y1336376D01*
G01X1457220Y1360785D02*
X1461157Y1356848D01*
G01X1479661D02*
Y1327321D01*
G01X1457220Y1732833D02*
Y1327321D01*
G01X1448165Y1350943D02*
Y1327321D01*
G01X1441007Y1428190D02*
X1441235D01*
G01X1439047Y1428169D02*
X1438785D01*
G01X1440094Y1428180D02*
X1438785Y1428169D01*
G01X1441235Y1428190D02*
X1440094Y1428180D01*
G01Y1425031D02*
X1438785Y1425019D01*
G01X1441235Y1425041D02*
X1440094Y1425031D01*
G01X1437751Y1428154D02*
X1436420Y1428142D01*
G01X1437751Y1425005D02*
X1436420Y1424993D01*
G01X1442543Y1428207D02*
X1441007Y1428190D01*
G01X1442543Y1428207D02*
X1439047Y1428169D01*
G01X1441235Y1428190D02*
X1442772Y1428207D01*
G01X1442543Y1425057D02*
X1441007Y1425041D01*
G01X1442543Y1425057D02*
X1439047Y1425019D01*
G01X1441235Y1425041D02*
X1442772Y1425057D01*
G01X1439047Y1428169D02*
X1440094Y1428180D01*
G01X1438785Y1428169D02*
X1436420Y1428142D01*
G01X1437751Y1428154D02*
X1439047Y1428169D01*
G01Y1425019D02*
X1440094Y1425031D01*
G01X1438785Y1425019D02*
X1436420Y1424993D01*
G01X1437751Y1425005D02*
X1439047Y1425019D01*
G01Y1427260D02*
X1442543Y1427222D01*
G01X1437751Y1427275D02*
X1441007Y1427239D01*
G01X1439047Y1424111D02*
X1442543Y1424073D01*
G01X1437751Y1424125D02*
X1441007Y1424089D01*
G01X1439047Y1420961D02*
X1442543Y1420923D01*
G01X1437751Y1420975D02*
X1441007Y1420940D01*
G01X1439047Y1417811D02*
X1442543Y1417774D01*
G01X1437751Y1417826D02*
X1441007Y1417790D01*
G01X1439047Y1414662D02*
X1442543Y1414624D01*
G01X1437751Y1414676D02*
X1441007Y1414640D01*
G01X1439047Y1411512D02*
X1442543Y1411474D01*
G01X1437751Y1411527D02*
X1441007Y1411491D01*
G01X1439047Y1408363D02*
X1442543Y1408325D01*
G01X1437751Y1408377D02*
X1441007Y1408341D01*
G01X1439047Y1405213D02*
X1442543Y1405175D01*
G01X1437751Y1405227D02*
X1441007Y1405192D01*
G01X1439047Y1402063D02*
X1442543Y1402025D01*
G01X1437751Y1402078D02*
X1441007Y1402042D01*
G01X1439047Y1398914D02*
X1442543Y1398876D01*
G01X1437751Y1398928D02*
X1441007Y1398892D01*
G01X1439047Y1395764D02*
X1442543Y1395726D01*
G01X1437751Y1395779D02*
X1441007Y1395743D01*
G01X1439047Y1392615D02*
X1442543Y1392577D01*
G01X1437751Y1392629D02*
X1441007Y1392593D01*
G01X1439047Y1389465D02*
X1442543Y1389427D01*
G01X1437751Y1389479D02*
X1441007Y1389444D01*
G01X1439047Y1386315D02*
X1442543Y1386277D01*
G01X1437751Y1386330D02*
X1441007Y1386294D01*
G01X1439047Y1383166D02*
X1442543Y1383128D01*
G01X1437751Y1383180D02*
X1441007Y1383144D01*
G01X1439047Y1380016D02*
X1442543Y1379978D01*
G01X1437751Y1380031D02*
X1441007Y1379995D01*
G01X1439047Y1376867D02*
X1442543Y1376829D01*
G01X1437751Y1376881D02*
X1441007Y1376845D01*
G01X1439047Y1373717D02*
X1442543Y1373679D01*
G01X1437751Y1373731D02*
X1441007Y1373695D01*
G01X1439047Y1370567D02*
X1442543Y1370529D01*
G01X1437751Y1370582D02*
X1441007Y1370546D01*
G01X1439047Y1367418D02*
X1442543Y1367380D01*
G01X1437751Y1367432D02*
X1441007Y1367396D01*
G01X1438785Y1427260D02*
X1436420Y1427286D01*
G01X1438785Y1424111D02*
X1436420Y1424137D01*
G01X1438785Y1420961D02*
X1436420Y1420987D01*
G01X1438785Y1417812D02*
X1436420Y1417838D01*
G01X1438785Y1414662D02*
X1436420Y1414688D01*
G01X1438785Y1411512D02*
X1436420Y1411538D01*
G01X1438785Y1408363D02*
X1436420Y1408389D01*
G01X1438785Y1405213D02*
X1436420Y1405239D01*
G01X1438785Y1402064D02*
X1436420Y1402090D01*
G01X1438785Y1398914D02*
X1436420Y1398940D01*
G01X1438785Y1395764D02*
X1436420Y1395790D01*
G01X1438785Y1392615D02*
X1436420Y1392641D01*
G01X1438785Y1389465D02*
X1436420Y1389491D01*
G01X1438785Y1386315D02*
X1436420Y1386342D01*
G01X1438785Y1383166D02*
X1436420Y1383192D01*
G01X1438785Y1380016D02*
X1436420Y1380042D01*
G01X1438785Y1376867D02*
X1436420Y1376893D01*
G01X1438785Y1373717D02*
X1436420Y1373743D01*
G01X1438785Y1370567D02*
X1436420Y1370594D01*
G01X1438785Y1367418D02*
X1436420Y1367444D01*
G01X1441235Y1427239D02*
X1442772Y1427222D01*
G01X1441235Y1424089D02*
X1442772Y1424073D01*
G01X1441235Y1420940D02*
X1442772Y1420923D01*
G01X1441235Y1417790D02*
X1442772Y1417774D01*
G01X1441235Y1414640D02*
X1442772Y1414624D01*
G01X1441235Y1411491D02*
X1442772Y1411474D01*
G01X1441235Y1408341D02*
X1442772Y1408325D01*
G01X1441235Y1405192D02*
X1442772Y1405175D01*
G01X1441235Y1402042D02*
X1442772Y1402025D01*
G01X1441235Y1398892D02*
X1442772Y1398876D01*
G01X1441235Y1395743D02*
X1442772Y1395726D01*
G01X1441235Y1392593D02*
X1442772Y1392577D01*
G01X1441235Y1389444D02*
X1442772Y1389427D01*
G01X1441235Y1386294D02*
X1442772Y1386277D01*
G01X1441235Y1383144D02*
X1442772Y1383128D01*
G01X1441235Y1379995D02*
X1442772Y1379978D01*
G01X1441235Y1376845D02*
X1442772Y1376829D01*
G01X1441235Y1373695D02*
X1442772Y1373679D01*
G01X1441235Y1370546D02*
X1442772Y1370529D01*
G01X1441235Y1367396D02*
X1442772Y1367380D01*
G01X1441235Y1427239D02*
X1438785Y1427260D01*
G01X1437751Y1427275D02*
X1436420Y1427286D01*
G01X1441235Y1424089D02*
X1438785Y1424111D01*
G01X1437751Y1424125D02*
X1436420Y1424137D01*
G01X1441235Y1420940D02*
X1438785Y1420961D01*
G01X1437751Y1420975D02*
X1436420Y1420987D01*
G01X1441235Y1417790D02*
X1438785Y1417812D01*
G01X1437751Y1417826D02*
X1436420Y1417838D01*
G01X1441235Y1414640D02*
X1438785Y1414662D01*
G01X1437751Y1414676D02*
X1436420Y1414688D01*
G01X1441235Y1411491D02*
X1438785Y1411512D01*
G01X1437751Y1411527D02*
X1436420Y1411538D01*
G01X1441235Y1408341D02*
X1438785Y1408363D01*
G01X1437751Y1408377D02*
X1436420Y1408389D01*
G01X1441235Y1405192D02*
X1438785Y1405213D01*
G01X1437751Y1405227D02*
X1436420Y1405239D01*
G01X1441235Y1402042D02*
X1438785Y1402064D01*
G01X1437751Y1402078D02*
X1436420Y1402090D01*
G01X1441235Y1398892D02*
X1438785Y1398914D01*
G01X1437751Y1398928D02*
X1436420Y1398940D01*
G01X1441235Y1395743D02*
X1438785Y1395764D01*
G01X1437751Y1395779D02*
X1436420Y1395790D01*
G01X1441235Y1392593D02*
X1438785Y1392615D01*
G01X1437751Y1392629D02*
X1436420Y1392641D01*
G01X1441235Y1389444D02*
X1438785Y1389465D01*
G01X1437751Y1389479D02*
X1436420Y1389491D01*
G01X1441235Y1386294D02*
X1438785Y1386315D01*
G01X1437751Y1386330D02*
X1436420Y1386342D01*
G01X1441235Y1383144D02*
X1438785Y1383166D01*
G01X1437751Y1383180D02*
X1436420Y1383192D01*
G01X1441235Y1379995D02*
X1438785Y1380016D01*
G01X1437751Y1380031D02*
X1436420Y1380042D01*
G01X1441235Y1376845D02*
X1438785Y1376867D01*
G01X1437751Y1376881D02*
X1436420Y1376893D01*
G01X1441235Y1373695D02*
X1438785Y1373717D01*
G01X1437751Y1373731D02*
X1436420Y1373743D01*
G01X1441235Y1370546D02*
X1438785Y1370567D01*
G01X1437751Y1370582D02*
X1436420Y1370594D01*
G01X1441235Y1367396D02*
X1438785Y1367418D01*
G01X1437751Y1367432D02*
X1436420Y1367444D01*
G01X1439047Y1427260D02*
X1438785D01*
G01X1441235Y1427239D02*
X1441007D01*
G01X1441235Y1425041D02*
X1441007D01*
G01X1439047Y1425019D02*
X1438785D01*
G01X1439047Y1424111D02*
X1438785D01*
G01X1441235Y1424089D02*
X1441007D01*
G01X1441235Y1421891D02*
X1441007D01*
G01X1439047Y1421869D02*
X1438785D01*
G01X1439047Y1420961D02*
X1438785D01*
G01X1441235Y1420940D02*
X1441007D01*
G01X1441235Y1418741D02*
X1441007D01*
G01X1439047Y1418720D02*
X1438785D01*
G01X1439047Y1417812D02*
X1438785D01*
G01X1441235Y1417790D02*
X1441007D01*
G01X1441235Y1415592D02*
X1441007D01*
G01X1439047Y1415570D02*
X1438785D01*
G01X1439047Y1414662D02*
X1438785D01*
G01X1441235Y1414640D02*
X1441007D01*
G01X1441235Y1412442D02*
X1441007D01*
G01X1439047Y1412421D02*
X1438785D01*
G01X1439047Y1411512D02*
X1438785D01*
G01X1441235Y1411491D02*
X1441007D01*
G01X1441235Y1409293D02*
X1441007D01*
G01X1439047Y1409271D02*
X1438785D01*
G01X1439047Y1408363D02*
X1438785D01*
G01X1441235Y1408341D02*
X1441007D01*
G01X1441235Y1406143D02*
X1441007D01*
G01X1439047Y1406121D02*
X1438785D01*
G01X1439047Y1405213D02*
X1438785D01*
G01X1441235Y1405192D02*
X1441007D01*
G01X1441235Y1402993D02*
X1441007D01*
G01X1439047Y1402972D02*
X1438785D01*
G01X1439047Y1402064D02*
X1438785D01*
G01X1441235Y1402042D02*
X1441007D01*
G01X1441235Y1399844D02*
X1441007D01*
G01X1439047Y1399822D02*
X1438785D01*
G01X1439047Y1398914D02*
X1438785D01*
G01X1441235Y1398892D02*
X1441007D01*
G01X1441235Y1396694D02*
X1441007D01*
G01X1439047Y1396673D02*
X1438785D01*
G01X1439047Y1395764D02*
X1438785D01*
G01X1441235Y1395743D02*
X1441007D01*
G01X1441235Y1393544D02*
X1441007D01*
G01X1439047Y1393523D02*
X1438785D01*
G01X1439047Y1392615D02*
X1438785D01*
G01X1441235Y1392593D02*
X1441007D01*
G01Y1390395D02*
X1441235D01*
G01X1439047Y1390373D02*
X1438785D01*
G01X1439047Y1389465D02*
X1438785D01*
G01X1441235Y1389444D02*
X1441007D01*
G01X1441235Y1387245D02*
X1441007D01*
G01X1439047Y1387224D02*
X1438785D01*
G01X1439047Y1386315D02*
X1438785D01*
G01X1441235Y1386294D02*
X1441007D01*
G01X1441235Y1384096D02*
X1441007D01*
G01X1439047Y1384074D02*
X1438785D01*
G01X1439047Y1383166D02*
X1438785D01*
G01X1441235Y1383144D02*
X1441007D01*
G01X1441235Y1380946D02*
X1441007D01*
G01X1438785Y1380924D02*
X1439047D01*
G01Y1380016D02*
X1438785D01*
G01X1441235Y1379995D02*
X1441007D01*
G01X1441235Y1377796D02*
X1441007D01*
G01X1439047Y1377775D02*
X1438785D01*
G01X1439047Y1376867D02*
X1438785D01*
G01X1441235Y1376845D02*
X1441007D01*
G01X1441235Y1374647D02*
X1441007D01*
G01X1439047Y1374625D02*
X1438785D01*
G01X1439047Y1373717D02*
X1438785D01*
G01X1441235Y1373695D02*
X1441007D01*
G01X1441235Y1371497D02*
X1441007D01*
G01X1439047Y1371476D02*
X1438785D01*
G01X1439047Y1370567D02*
X1438785D01*
G01X1441235Y1370546D02*
X1441007D01*
G01X1441235Y1368348D02*
X1441007D01*
G01X1439047Y1368326D02*
X1438785D01*
G01X1439047Y1367418D02*
X1438785D01*
G01X1441235Y1367396D02*
X1441007D01*
G01X1449937Y1363935D02*
X1430449D01*
G01X1440094Y1421881D02*
X1438785Y1421869D01*
G01X1441235Y1421891D02*
X1440094Y1421881D01*
G01Y1418731D02*
X1438785Y1418720D01*
G01X1441235Y1418741D02*
X1440094Y1418731D01*
G01Y1415582D02*
X1438785Y1415570D01*
G01X1441235Y1415592D02*
X1440094Y1415582D01*
G01Y1412432D02*
X1438785Y1412421D01*
G01X1441235Y1412442D02*
X1440094Y1412432D01*
G01Y1409283D02*
X1438785Y1409271D01*
G01X1441235Y1409293D02*
X1440094Y1409283D01*
G01Y1406133D02*
X1438785Y1406121D01*
G01X1441235Y1406143D02*
X1440094Y1406133D01*
G01Y1402983D02*
X1438785Y1402972D01*
G01X1441235Y1402993D02*
X1440094Y1402983D01*
G01Y1399834D02*
X1438785Y1399822D01*
G01X1441235Y1399844D02*
X1440094Y1399834D01*
G01Y1396684D02*
X1438785Y1396673D01*
G01X1441235Y1396694D02*
X1440094Y1396684D01*
G01Y1393534D02*
X1438785Y1393523D01*
G01X1441235Y1393544D02*
X1440094Y1393534D01*
G01Y1390385D02*
X1438785Y1390373D01*
G01X1441235Y1390395D02*
X1440094Y1390385D01*
G01Y1387235D02*
X1438785Y1387224D01*
G01X1441235Y1387245D02*
X1440094Y1387235D01*
G01Y1384086D02*
X1438785Y1384074D01*
G01X1441235Y1384096D02*
X1440094Y1384086D01*
G01Y1380936D02*
X1438785Y1380924D01*
G01X1441235Y1380946D02*
X1440094Y1380936D01*
G01Y1377786D02*
X1438785Y1377775D01*
G01X1441235Y1377796D02*
X1440094Y1377786D01*
G01Y1374637D02*
X1438785Y1374625D01*
G01X1441235Y1374647D02*
X1440094Y1374637D01*
G01Y1371487D02*
X1438785Y1371476D01*
G01X1441235Y1371497D02*
X1440094Y1371487D01*
G01Y1368338D02*
X1438785Y1368326D01*
G01X1441235Y1368348D02*
X1440094Y1368338D01*
G01X1437751Y1421855D02*
X1436420Y1421843D01*
G01X1437751Y1418705D02*
X1436420Y1418694D01*
G01X1437751Y1415556D02*
X1436420Y1415544D01*
G01X1437751Y1412406D02*
X1436420Y1412394D01*
G01X1437751Y1409257D02*
X1436420Y1409245D01*
G01X1437751Y1406107D02*
X1436420Y1406095D01*
G01X1437751Y1402957D02*
X1436420Y1402946D01*
G01X1437751Y1399808D02*
X1436420Y1399796D01*
G01X1437751Y1396658D02*
X1436420Y1396646D01*
G01X1437751Y1393509D02*
X1436420Y1393497D01*
G01X1437751Y1390359D02*
X1436420Y1390347D01*
G01X1437751Y1387209D02*
X1436420Y1387198D01*
G01X1437751Y1384060D02*
X1436420Y1384048D01*
G01X1437751Y1380910D02*
X1436420Y1380898D01*
G01X1437751Y1377761D02*
X1436420Y1377749D01*
G01X1437751Y1374611D02*
X1436420Y1374599D01*
G01X1437751Y1371461D02*
X1436420Y1371450D01*
G01X1437751Y1368312D02*
X1436420Y1368300D01*
G01X1442543Y1421907D02*
X1441007Y1421891D01*
G01X1442543Y1421907D02*
X1439047Y1421869D01*
G01X1441235Y1421891D02*
X1442772Y1421907D01*
G01X1442543Y1418758D02*
X1441007Y1418741D01*
G01X1442543Y1418758D02*
X1439047Y1418720D01*
G01X1441235Y1418741D02*
X1442772Y1418758D01*
G01X1442543Y1415608D02*
X1441007Y1415592D01*
G01X1442543Y1415608D02*
X1439047Y1415570D01*
G01X1441235Y1415592D02*
X1442772Y1415608D01*
G01X1442543Y1412459D02*
X1441007Y1412442D01*
G01X1442543Y1412459D02*
X1439047Y1412421D01*
G01X1441235Y1412442D02*
X1442772Y1412459D01*
G01X1442543Y1409309D02*
X1441007Y1409293D01*
G01X1442543Y1409309D02*
X1439047Y1409271D01*
G01X1441235Y1409293D02*
X1442772Y1409309D01*
G01X1442543Y1406159D02*
X1441007Y1406143D01*
G01X1442543Y1406159D02*
X1439047Y1406121D01*
G01X1441235Y1406143D02*
X1442772Y1406159D01*
G01X1442543Y1403010D02*
X1441007Y1402993D01*
G01X1442543Y1403010D02*
X1439047Y1402972D01*
G01X1441235Y1402993D02*
X1442772Y1403010D01*
G01X1442543Y1399860D02*
X1441007Y1399844D01*
G01X1442543Y1399860D02*
X1439047Y1399822D01*
G01X1441235Y1399844D02*
X1442772Y1399860D01*
G01X1442543Y1396711D02*
X1441007Y1396694D01*
G01X1442543Y1396711D02*
X1439047Y1396673D01*
G01X1441235Y1396694D02*
X1442772Y1396711D01*
G01X1442543Y1393561D02*
X1441007Y1393544D01*
G01X1442543Y1393561D02*
X1439047Y1393523D01*
G01X1441235Y1393544D02*
X1442772Y1393561D01*
G01X1442543Y1390411D02*
X1441007Y1390395D01*
G01X1442543Y1390411D02*
X1439047Y1390373D01*
G01X1441235Y1390395D02*
X1442772Y1390411D01*
G01X1442543Y1387262D02*
X1441007Y1387245D01*
G01X1442543Y1387262D02*
X1439047Y1387224D01*
G01X1441235Y1387245D02*
X1442772Y1387262D01*
G01X1442543Y1384112D02*
X1441007Y1384096D01*
G01X1442543Y1384112D02*
X1439047Y1384074D01*
G01X1441235Y1384096D02*
X1442772Y1384112D01*
G01X1442543Y1380963D02*
X1441007Y1380946D01*
G01X1442543Y1380963D02*
X1439047Y1380925D01*
G01X1441235Y1380946D02*
X1442772Y1380963D01*
G01X1442543Y1377813D02*
X1441007Y1377796D01*
G01X1442543Y1377813D02*
X1439047Y1377775D01*
G01X1441235Y1377796D02*
X1442772Y1377813D01*
G01X1442543Y1374663D02*
X1441007Y1374647D01*
G01X1442543Y1374663D02*
X1439047Y1374625D01*
G01X1441235Y1374647D02*
X1442772Y1374663D01*
G01X1442543Y1371514D02*
X1441007Y1371497D01*
G01X1442543Y1371514D02*
X1439047Y1371476D01*
G01X1441235Y1371497D02*
X1442772Y1371514D01*
G01X1442543Y1368364D02*
X1441007Y1368348D01*
G01X1442543Y1368364D02*
X1439047Y1368326D01*
G01X1441235Y1368348D02*
X1442772Y1368364D01*
G01X1439047Y1421869D02*
X1440094Y1421881D01*
G01X1438785Y1421869D02*
X1436420Y1421843D01*
G01X1437751Y1421855D02*
X1439047Y1421869D01*
G01Y1418720D02*
X1440094Y1418731D01*
G01X1438785Y1418720D02*
X1436420Y1418694D01*
G01X1437751Y1418705D02*
X1439047Y1418720D01*
G01Y1415570D02*
X1440094Y1415582D01*
G01X1438785Y1415570D02*
X1436420Y1415544D01*
G01X1437751Y1415556D02*
X1439047Y1415570D01*
G01Y1412421D02*
X1440094Y1412432D01*
G01X1438785Y1412421D02*
X1436420Y1412394D01*
G01X1437751Y1412406D02*
X1439047Y1412421D01*
G01Y1409271D02*
X1440094Y1409283D01*
G01X1438785Y1409271D02*
X1436420Y1409245D01*
G01X1437751Y1409257D02*
X1439047Y1409271D01*
G01Y1406121D02*
X1440094Y1406133D01*
G01X1438785Y1406121D02*
X1436420Y1406095D01*
G01X1437751Y1406107D02*
X1439047Y1406121D01*
G01Y1402972D02*
X1440094Y1402983D01*
G01X1438785Y1402972D02*
X1436420Y1402946D01*
G01X1437751Y1402957D02*
X1439047Y1402972D01*
G01Y1399822D02*
X1440094Y1399834D01*
G01X1438785Y1399822D02*
X1436420Y1399796D01*
G01X1437751Y1399808D02*
X1439047Y1399822D01*
G01Y1396673D02*
X1440094Y1396684D01*
G01X1438785Y1396673D02*
X1436420Y1396646D01*
G01X1437751Y1396658D02*
X1439047Y1396673D01*
G01Y1393523D02*
X1440094Y1393534D01*
G01X1438785Y1393523D02*
X1436420Y1393497D01*
G01X1437751Y1393509D02*
X1439047Y1393523D01*
G01Y1390373D02*
X1440094Y1390385D01*
G01X1438785Y1390373D02*
X1436420Y1390347D01*
G01X1437751Y1390359D02*
X1439047Y1390373D01*
G01Y1387224D02*
X1440094Y1387235D01*
G01X1438785Y1387224D02*
X1436420Y1387198D01*
G01X1437751Y1387209D02*
X1439047Y1387224D01*
G01Y1384074D02*
X1440094Y1384086D01*
G01X1438785Y1384074D02*
X1436420Y1384048D01*
G01X1437751Y1384060D02*
X1439047Y1384074D01*
G01Y1380924D02*
X1440094Y1380936D01*
G01X1438785Y1380924D02*
X1436420Y1380898D01*
G01X1437751Y1380910D02*
X1439047Y1380924D01*
G01Y1377775D02*
X1440094Y1377786D01*
G01X1438785Y1377775D02*
X1436420Y1377749D01*
G01X1437751Y1377761D02*
X1439047Y1377775D01*
G01Y1374625D02*
X1440094Y1374637D01*
G01X1438785Y1374625D02*
X1436420Y1374599D01*
G01X1437751Y1374611D02*
X1439047Y1374625D01*
G01Y1371476D02*
X1440094Y1371487D01*
G01X1438785Y1371476D02*
X1436420Y1371450D01*
G01X1437751Y1371461D02*
X1439047Y1371476D01*
G01Y1368326D02*
X1440094Y1368338D01*
G01X1438785Y1368326D02*
X1436420Y1368300D01*
G01X1437751Y1368312D02*
X1439047Y1368326D01*
G01X1426512Y1369447D02*
X1429239Y1367872D01*
G01X1430449Y1363935D02*
X1426512Y1361966D01*
G01X1429239Y1367872D02*
X1426512Y1366297D01*
G01X1441235Y1368348D02*
Y1367396D01*
G01Y1374647D02*
Y1373695D01*
G01Y1371497D02*
Y1370546D01*
G01Y1377796D02*
Y1376845D01*
G01Y1384096D02*
Y1383144D01*
G01Y1380946D02*
Y1379995D01*
G01Y1387245D02*
Y1386294D01*
G01Y1393544D02*
Y1392593D01*
G01Y1390395D02*
Y1389444D01*
G01Y1396694D02*
Y1395743D01*
G01Y1402993D02*
Y1402042D01*
G01Y1399844D02*
Y1398892D01*
G01Y1406143D02*
Y1405192D01*
G01Y1412442D02*
Y1411491D01*
G01Y1409292D02*
Y1408341D01*
G01Y1415592D02*
Y1414640D01*
G01Y1418741D02*
Y1417790D01*
G01Y1425040D02*
Y1424089D01*
G01Y1421891D02*
Y1420940D01*
G01Y1428190D02*
Y1427239D01*
G01X1441007Y1368348D02*
Y1367396D01*
G01Y1374647D02*
Y1373695D01*
G01Y1371497D02*
Y1370546D01*
G01Y1377796D02*
Y1376845D01*
G01Y1384096D02*
Y1383144D01*
G01Y1380946D02*
Y1379995D01*
G01Y1387245D02*
Y1386294D01*
G01Y1393544D02*
Y1392593D01*
G01Y1390395D02*
Y1389444D01*
G01Y1396694D02*
Y1395743D01*
G01Y1402993D02*
Y1402042D01*
G01Y1399844D02*
Y1398892D01*
G01Y1406143D02*
Y1405192D01*
G01Y1412442D02*
Y1411491D01*
G01Y1409293D02*
Y1408341D01*
G01Y1415592D02*
Y1414640D01*
G01Y1418741D02*
Y1417790D01*
G01Y1425041D02*
Y1424089D01*
G01Y1421891D02*
Y1420940D01*
G01Y1428190D02*
Y1427239D01*
G01X1439047Y1368326D02*
Y1367418D01*
G01Y1374625D02*
Y1373717D01*
G01Y1371476D02*
Y1370567D01*
G01Y1377775D02*
Y1376867D01*
G01Y1384074D02*
Y1383166D01*
G01Y1380925D02*
Y1380016D01*
G01Y1387224D02*
Y1386315D01*
G01Y1393523D02*
Y1392615D01*
G01Y1390373D02*
Y1389465D01*
G01Y1396673D02*
Y1395764D01*
G01Y1402972D02*
Y1402063D01*
G01Y1399822D02*
Y1398914D01*
G01Y1406121D02*
Y1405213D01*
G01Y1412421D02*
Y1411512D01*
G01Y1409271D02*
Y1408363D01*
G01Y1415570D02*
Y1414662D01*
G01Y1418720D02*
Y1417811D01*
G01Y1425019D02*
Y1424111D01*
G01Y1421869D02*
Y1420961D01*
G01Y1428169D02*
Y1427260D01*
G01X1438785Y1368326D02*
Y1367418D01*
G01Y1374625D02*
Y1373717D01*
G01Y1371476D02*
Y1370567D01*
G01Y1377775D02*
Y1376867D01*
G01Y1384074D02*
Y1383166D01*
G01Y1380925D02*
Y1380016D01*
G01Y1387224D02*
Y1386315D01*
G01Y1393523D02*
Y1392615D01*
G01Y1390373D02*
Y1389465D01*
G01Y1396673D02*
Y1395764D01*
G01Y1402972D02*
Y1402064D01*
G01Y1399822D02*
Y1398914D01*
G01Y1406121D02*
Y1405213D01*
G01Y1412421D02*
Y1411512D01*
G01Y1409271D02*
Y1408363D01*
G01Y1415570D02*
Y1414662D01*
G01Y1418720D02*
Y1417812D01*
G01Y1425019D02*
Y1424111D01*
G01Y1421869D02*
Y1420961D01*
G01Y1428169D02*
Y1427260D01*
G01X1437751Y1368306D02*
Y1367438D01*
G01Y1374605D02*
Y1373737D01*
G01Y1371455D02*
Y1370588D01*
G01Y1377755D02*
Y1376887D01*
G01Y1384054D02*
Y1383186D01*
G01Y1380904D02*
Y1380036D01*
G01Y1387204D02*
Y1386336D01*
G01Y1393503D02*
Y1392635D01*
G01Y1390353D02*
Y1389485D01*
G01Y1396652D02*
Y1395784D01*
G01Y1402952D02*
Y1402084D01*
G01Y1399802D02*
Y1398934D01*
G01Y1406101D02*
Y1405233D01*
G01Y1412400D02*
Y1411533D01*
G01Y1409251D02*
Y1408383D01*
G01Y1415550D02*
Y1414682D01*
G01Y1421849D02*
Y1420981D01*
G01Y1418700D02*
Y1417832D01*
G01Y1424999D02*
Y1424131D01*
G01Y1428148D02*
Y1427281D01*
G01X1436420Y1368300D02*
Y1367444D01*
G01Y1374599D02*
Y1373743D01*
G01Y1371450D02*
Y1370594D01*
G01Y1377749D02*
Y1376893D01*
G01Y1384048D02*
Y1383192D01*
G01Y1380898D02*
Y1380042D01*
G01Y1387198D02*
Y1386342D01*
G01Y1393497D02*
Y1392641D01*
G01Y1390347D02*
Y1389491D01*
G01Y1396646D02*
Y1395790D01*
G01Y1402946D02*
Y1402090D01*
G01Y1399796D02*
Y1398940D01*
G01Y1406095D02*
Y1405239D01*
G01Y1412394D02*
Y1411538D01*
G01Y1409245D02*
Y1408389D01*
G01Y1415544D02*
Y1414688D01*
G01Y1421843D02*
Y1420987D01*
G01Y1418694D02*
Y1417838D01*
G01Y1424993D02*
Y1424137D01*
G01Y1428142D02*
Y1427286D01*
G01X1430449Y1507242D02*
Y1365903D01*
G01X1426512Y1694250D02*
Y1365903D01*
G01X1457732Y1429683D02*
X1457220D01*
G01X1457732Y1428896D02*
X1457220D01*
G01X1444212Y1428502D02*
X1443073D01*
G01X1469631Y1428305D02*
X1457535D01*
G01X1442772Y1428207D02*
X1442543D01*
G01X1470921Y1428049D02*
X1469507D01*
G01X1470921Y1427380D02*
X1469507D01*
G01X1442772Y1427222D02*
X1442543D01*
G01X1469631Y1427124D02*
X1457535D01*
G01X1444212Y1426927D02*
X1443073D01*
G01X1457732Y1426533D02*
X1457220D01*
G01X1457732Y1425746D02*
X1457220D01*
G01X1444212Y1425352D02*
X1443073D01*
G01X1469631Y1425155D02*
X1457535D01*
G01X1442772Y1425057D02*
X1442543D01*
G01X1470921Y1424900D02*
X1469507D01*
G01X1470921Y1424230D02*
X1469507D01*
G01X1442772Y1424073D02*
X1442543D01*
G01X1469631Y1423974D02*
X1457535D01*
G01X1444212Y1423777D02*
X1443073D01*
G01X1457732Y1423384D02*
X1457220D01*
G01X1457732Y1422596D02*
X1457220D01*
G01X1444212Y1422203D02*
X1443073D01*
G01X1469631Y1422006D02*
X1457535D01*
G01X1442772Y1421907D02*
X1442543D01*
G01X1470921Y1421750D02*
X1469507D01*
G01X1470921Y1421081D02*
X1469507D01*
G01X1442772Y1420923D02*
X1442543D01*
G01X1469631Y1420825D02*
X1457535D01*
G01X1444212Y1420628D02*
X1443073D01*
G01X1457732Y1420234D02*
X1457220D01*
G01X1457732Y1419447D02*
X1457220D01*
G01X1444212Y1419053D02*
X1443073D01*
G01X1469631Y1418856D02*
X1457535D01*
G01X1442772Y1418758D02*
X1442543D01*
G01X1470921Y1418600D02*
X1469507D01*
G01X1470921Y1417931D02*
X1469507D01*
G01X1442772Y1417774D02*
X1442543D01*
G01X1469631Y1417675D02*
X1457535D01*
G01X1444212Y1417478D02*
X1443073D01*
G01X1457732Y1417085D02*
X1457220D01*
G01X1457732Y1416297D02*
X1457220D01*
G01X1444212Y1415903D02*
X1443073D01*
G01X1469631Y1415707D02*
X1457535D01*
G01X1442772Y1415608D02*
X1442543D01*
G01X1470921Y1415451D02*
X1469507D01*
G01X1470921Y1414781D02*
X1469507D01*
G01X1442772Y1414624D02*
X1442543D01*
G01X1469631Y1414525D02*
X1457535D01*
G01X1444212Y1414329D02*
X1443073D01*
G01X1457732Y1413935D02*
X1457220D01*
G01X1457732Y1413148D02*
X1457220D01*
G01X1444212Y1412754D02*
X1443073D01*
G01X1469631Y1412557D02*
X1457535D01*
G01X1442772Y1412459D02*
X1442543D01*
G01X1470921Y1412301D02*
X1469507D01*
G01X1470921Y1411632D02*
X1469507D01*
G01X1442772Y1411474D02*
X1442543D01*
G01X1469631Y1411376D02*
X1457535D01*
G01X1444212Y1411179D02*
X1443073D01*
G01X1457732Y1410785D02*
X1457220D01*
G01X1457732Y1409998D02*
X1457220D01*
G01X1444212Y1409604D02*
X1443073D01*
G01X1469631Y1409407D02*
X1457535D01*
G01X1442772Y1409309D02*
X1442543D01*
G01X1470921Y1409151D02*
X1469507D01*
G01X1470921Y1408482D02*
X1469507D01*
G01X1442772Y1408325D02*
X1442543D01*
G01X1469631Y1408226D02*
X1457535D01*
G01X1444212Y1408029D02*
X1443073D01*
G01X1457732Y1407636D02*
X1457220D01*
G01X1457732Y1406848D02*
X1457220D01*
G01X1444212Y1406455D02*
X1443073D01*
G01X1469631Y1406258D02*
X1457535D01*
G01X1442772Y1406159D02*
X1442543D01*
G01X1470921Y1406002D02*
X1469507D01*
G01X1470921Y1405333D02*
X1469507D01*
G01X1442772Y1405175D02*
X1442543D01*
G01X1469631Y1405077D02*
X1457535D01*
G01X1444212Y1404880D02*
X1443073D01*
G01X1457732Y1404486D02*
X1457220D01*
G01X1457732Y1403699D02*
X1457220D01*
G01X1444212Y1403305D02*
X1443073D01*
G01X1469631Y1403108D02*
X1457535D01*
G01X1442772Y1403010D02*
X1442543D01*
G01X1470921Y1402852D02*
X1469507D01*
G01X1470921Y1402183D02*
X1469507D01*
G01X1442772Y1402025D02*
X1442543D01*
G01X1469631Y1401927D02*
X1457535D01*
G01X1444212Y1401730D02*
X1443073D01*
G01X1457732Y1401337D02*
X1457220D01*
G01X1457732Y1400549D02*
X1457220D01*
G01X1444212Y1400155D02*
X1443073D01*
G01X1469631Y1399959D02*
X1457535D01*
G01X1442772Y1399860D02*
X1442543D01*
G01X1470921Y1399703D02*
X1469507D01*
G01X1470921Y1399033D02*
X1469507D01*
G01X1442772Y1398876D02*
X1442543D01*
G01X1469631Y1398777D02*
X1457535D01*
G01X1444212Y1398581D02*
X1443073D01*
G01X1457732Y1398187D02*
X1457220D01*
G01X1457732Y1397400D02*
X1457220D01*
G01X1444212Y1397006D02*
X1443073D01*
G01X1469631Y1396809D02*
X1457535D01*
G01X1442772Y1396711D02*
X1442543D01*
G01X1470921Y1396553D02*
X1469507D01*
G01X1470921Y1395884D02*
X1469507D01*
G01X1442772Y1395726D02*
X1442543D01*
G01X1469631Y1395628D02*
X1457535D01*
G01X1444212Y1395431D02*
X1443073D01*
G01X1457732Y1395037D02*
X1457220D01*
G01X1457732Y1394250D02*
X1457220D01*
G01X1444212Y1393856D02*
X1443073D01*
G01X1469631Y1393659D02*
X1457535D01*
G01X1442772Y1393561D02*
X1442543D01*
G01X1470921Y1393403D02*
X1469507D01*
G01X1470921Y1392734D02*
X1469507D01*
G01X1442772Y1392577D02*
X1442543D01*
G01X1469631Y1392478D02*
X1457535D01*
G01X1444212Y1392281D02*
X1443073D01*
G01X1457732Y1391888D02*
X1457220D01*
G01X1457732Y1391100D02*
X1457220D01*
G01X1444212Y1390707D02*
X1443073D01*
G01X1469631Y1390510D02*
X1457535D01*
G01X1442772Y1390411D02*
X1442543D01*
G01X1470921Y1390254D02*
X1469507D01*
G01X1470921Y1389585D02*
X1469507D01*
G01X1442772Y1389427D02*
X1442543D01*
G01X1469631Y1389329D02*
X1457535D01*
G01X1444212Y1389132D02*
X1443073D01*
G01X1457732Y1388738D02*
X1457220D01*
G01X1457732Y1387951D02*
X1457220D01*
G01X1444212Y1387557D02*
X1443073D01*
G01X1469631Y1387360D02*
X1457535D01*
G01X1442772Y1387262D02*
X1442543D01*
G01X1470921Y1387104D02*
X1469507D01*
G01X1470921Y1386435D02*
X1469507D01*
G01X1442772Y1386277D02*
X1442543D01*
G01X1469631Y1386179D02*
X1457535D01*
G01X1444212Y1385982D02*
X1443073D01*
G01X1457732Y1385588D02*
X1457220D01*
G01X1457732Y1384801D02*
X1457220D01*
G01X1444212Y1384407D02*
X1443073D01*
G01X1469631Y1384211D02*
X1457535D01*
G01X1442772Y1384112D02*
X1442543D01*
G01X1470921Y1383955D02*
X1469507D01*
G01X1470921Y1383285D02*
X1469507D01*
G01X1442772Y1383128D02*
X1442543D01*
G01X1469631Y1383029D02*
X1457535D01*
G01X1444212Y1382833D02*
X1443073D01*
G01X1457732Y1382439D02*
X1457220D01*
G01X1457732Y1381651D02*
X1457220D01*
G01X1444212Y1381258D02*
X1443073D01*
G01X1469631Y1381061D02*
X1457535D01*
G01X1442772Y1380963D02*
X1442543D01*
G01X1470921Y1380805D02*
X1469507D01*
G01X1470921Y1380136D02*
X1469507D01*
G01X1442772Y1379978D02*
X1442543D01*
G01X1469631Y1379880D02*
X1457535D01*
G01X1444212Y1379683D02*
X1443073D01*
G01X1457732Y1379289D02*
X1457220D01*
G01X1457732Y1378502D02*
X1457220D01*
G01X1444212Y1378108D02*
X1443073D01*
G01X1469631Y1377911D02*
X1457535D01*
G01X1442772Y1377813D02*
X1442543D01*
G01X1470921Y1377655D02*
X1469507D01*
G01X1470921Y1376986D02*
X1469507D01*
G01X1442772Y1376829D02*
X1442543D01*
G01X1469631Y1376730D02*
X1457535D01*
G01X1444212Y1376533D02*
X1443073D01*
G01X1457732Y1376140D02*
X1457220D01*
G01X1457732Y1375352D02*
X1457220D01*
G01X1444212Y1374959D02*
X1443073D01*
G01X1469631Y1374762D02*
X1457535D01*
G01X1442772Y1374663D02*
X1442543D01*
G01X1470921Y1374506D02*
X1469507D01*
G01X1470921Y1373837D02*
X1469507D01*
G01X1442772Y1373679D02*
X1442543D01*
G01X1469631Y1373581D02*
X1457535D01*
G01X1444212Y1373384D02*
X1443073D01*
G01X1457732Y1372990D02*
X1457220D01*
G01X1457732Y1372203D02*
X1457220D01*
G01X1444212Y1371809D02*
X1443073D01*
G01X1469631Y1371612D02*
X1457535D01*
G01X1442772Y1371514D02*
X1442543D01*
G01X1470921Y1371356D02*
X1469507D01*
G01X1470921Y1370687D02*
X1469507D01*
G01X1442772Y1370529D02*
X1442543D01*
G01X1469631Y1370431D02*
X1457535D01*
G01X1444212Y1370234D02*
X1443073D01*
G01X1457732Y1369840D02*
X1457220D01*
G01X1457732Y1369053D02*
X1457220D01*
G01X1461157Y1368856D02*
X1471000D01*
G01X1444212Y1368659D02*
X1443073D01*
G01X1469631Y1368463D02*
X1457535D01*
G01X1442772Y1368364D02*
X1442543D01*
G01X1470921Y1368207D02*
X1469507D01*
G01X1470921Y1367537D02*
X1469507D01*
G01X1442772Y1367380D02*
X1442543D01*
G01X1469631Y1367281D02*
X1457535D01*
G01X1444212Y1367085D02*
X1443073D01*
G01X1474613Y1366966D02*
X1474975D01*
G01X1471000Y1366888D02*
X1461157D01*
G01X1473165Y1366701D02*
X1474929D01*
G01X1457732Y1366691D02*
X1457220D01*
G01X1475291Y1366435D02*
X1473165D01*
G01Y1369092D02*
X1475291Y1368384D01*
G01X1473889Y1368605D02*
X1475110Y1368207D01*
G01X1473708Y1368650D02*
X1473165Y1368827D01*
G01X1442772Y1427222D02*
X1443243Y1426927D01*
G01X1442543Y1427222D02*
X1442684Y1427135D01*
G01X1442772Y1424073D02*
X1443243Y1423777D01*
G01X1442543Y1424073D02*
X1442684Y1423985D01*
G01Y1427135D02*
X1443073Y1426927D01*
G01X1442684Y1423985D02*
X1443073Y1423777D01*
G01X1442684Y1420835D02*
X1443073Y1420628D01*
G01X1442684Y1417686D02*
X1443073Y1417478D01*
G01X1442684Y1414536D02*
X1443073Y1414329D01*
G01X1442684Y1411387D02*
X1443073Y1411179D01*
G01X1442684Y1408237D02*
X1443073Y1408029D01*
G01X1442684Y1405087D02*
X1443073Y1404880D01*
G01X1442684Y1401938D02*
X1443073Y1401730D01*
G01X1442684Y1398788D02*
X1443073Y1398581D01*
G01X1442684Y1395638D02*
X1443073Y1395431D01*
G01X1442684Y1392489D02*
X1443073Y1392281D01*
G01X1442684Y1389339D02*
X1443073Y1389132D01*
G01X1442684Y1386190D02*
X1443073Y1385982D01*
G01X1442684Y1383040D02*
X1443073Y1382833D01*
G01X1442772Y1420923D02*
X1443243Y1420628D01*
G01X1442543Y1420923D02*
X1442684Y1420835D01*
G01X1442772Y1417774D02*
X1443243Y1417478D01*
G01X1442543Y1417774D02*
X1442684Y1417686D01*
G01X1442772Y1414624D02*
X1443243Y1414329D01*
G01X1442543Y1414624D02*
X1442684Y1414536D01*
G01X1442772Y1411474D02*
X1443243Y1411179D01*
G01X1442543Y1411474D02*
X1442684Y1411387D01*
G01X1442772Y1408325D02*
X1443243Y1408029D01*
G01X1442543Y1408325D02*
X1442684Y1408237D01*
G01X1442772Y1405175D02*
X1443243Y1404880D01*
G01X1442543Y1405175D02*
X1442684Y1405087D01*
G01X1442772Y1402025D02*
X1443243Y1401730D01*
G01X1442543Y1402025D02*
X1442684Y1401938D01*
G01X1442772Y1398876D02*
X1443243Y1398581D01*
G01X1442543Y1398876D02*
X1442684Y1398788D01*
G01X1442772Y1395726D02*
X1443243Y1395431D01*
G01X1442543Y1395726D02*
X1442684Y1395638D01*
G01X1442772Y1392577D02*
X1443243Y1392281D01*
G01X1442543Y1392577D02*
X1442684Y1392489D01*
G01X1442772Y1389427D02*
X1443243Y1389132D01*
G01X1442543Y1389427D02*
X1442684Y1389339D01*
G01X1442772Y1386277D02*
X1443243Y1385982D01*
G01X1442543Y1386277D02*
X1442684Y1386190D01*
G01X1442772Y1383128D02*
X1443243Y1382833D01*
G01X1442543Y1383128D02*
X1442684Y1383040D01*
G01X1442772Y1379978D02*
X1443243Y1379683D01*
G01X1442543Y1379978D02*
X1442684Y1379890D01*
G01X1442772Y1376829D02*
X1443243Y1376533D01*
G01X1442543Y1376829D02*
X1442684Y1376741D01*
G01X1442772Y1373679D02*
X1443243Y1373384D01*
G01X1442543Y1373679D02*
X1442684Y1373591D01*
G01X1442772Y1370529D02*
X1443243Y1370234D01*
G01X1442543Y1370529D02*
X1442684Y1370442D01*
G01X1442772Y1367380D02*
X1443243Y1367085D01*
G01X1442543Y1367380D02*
X1442684Y1367292D01*
G01Y1379890D02*
X1443073Y1379683D01*
G01X1442684Y1376741D02*
X1443073Y1376533D01*
G01X1442684Y1373591D02*
X1443073Y1373384D01*
G01X1442684Y1370442D02*
X1443073Y1370234D01*
G01X1442684Y1367292D02*
X1443073Y1367085D01*
G01X1469636Y1428319D02*
X1469855Y1428049D01*
G01X1469636Y1425170D02*
X1469855Y1424900D01*
G01X1469636Y1422020D02*
X1469855Y1421750D01*
G01X1469636Y1418870D02*
X1469855Y1418600D01*
G01X1469636Y1415721D02*
X1469855Y1415451D01*
G01X1469636Y1412571D02*
X1469855Y1412301D01*
G01X1469636Y1409422D02*
X1469855Y1409151D01*
G01X1469278Y1428305D02*
X1469507Y1428049D01*
G01X1469278Y1425155D02*
X1469507Y1424900D01*
G01X1469278Y1422006D02*
X1469507Y1421750D01*
G01X1469278Y1418856D02*
X1469507Y1418600D01*
G01X1469278Y1415707D02*
X1469507Y1415451D01*
G01X1469278Y1412557D02*
X1469507Y1412301D01*
G01X1469278Y1409407D02*
X1469507Y1409151D01*
G01X1469278Y1406258D02*
X1469507Y1406002D01*
G01X1469278Y1403108D02*
X1469507Y1402852D01*
G01X1469278Y1399959D02*
X1469507Y1399703D01*
G01X1469278Y1396809D02*
X1469507Y1396553D01*
G01X1469278Y1393659D02*
X1469507Y1393403D01*
G01X1469278Y1390510D02*
X1469507Y1390254D01*
G01X1469278Y1387360D02*
X1469507Y1387104D01*
G01X1469278Y1384211D02*
X1469507Y1383955D01*
G01X1469278Y1381061D02*
X1469507Y1380805D01*
G01X1469278Y1377911D02*
X1469507Y1377655D01*
G01X1469278Y1374762D02*
X1469507Y1374506D01*
G01X1474975Y1366966D02*
X1475291Y1366701D01*
G01X1474929D02*
X1474613Y1366966D01*
G01X1475110Y1368207D02*
X1473889Y1367808D01*
G01X1473165Y1367587D02*
X1473708Y1367764D01*
G01X1475291Y1368029D02*
X1473165Y1367321D01*
G01X1469636Y1406272D02*
X1469855Y1406002D01*
G01X1469636Y1403122D02*
X1469855Y1402852D01*
G01X1469636Y1399973D02*
X1469855Y1399703D01*
G01X1469636Y1396823D02*
X1469855Y1396553D01*
G01X1469636Y1393673D02*
X1469855Y1393403D01*
G01X1469636Y1390524D02*
X1469855Y1390254D01*
G01X1469636Y1387374D02*
X1469855Y1387104D01*
G01X1469636Y1384225D02*
X1469855Y1383955D01*
G01X1469636Y1381075D02*
X1469855Y1380805D01*
G01X1469636Y1377925D02*
X1469855Y1377655D01*
G01X1469636Y1374776D02*
X1469855Y1374506D01*
G01X1469636Y1371626D02*
X1469855Y1371356D01*
G01X1469636Y1368477D02*
X1469855Y1368207D01*
G01X1469278Y1371612D02*
X1469507Y1371356D01*
G01X1469278Y1368463D02*
X1469507Y1368207D01*
G01X1443073Y1368659D02*
X1442684Y1368452D01*
G01X1443073Y1371809D02*
X1442684Y1371601D01*
G01X1443073Y1374959D02*
X1442684Y1374751D01*
G01X1443073Y1378108D02*
X1442684Y1377901D01*
G01X1443073Y1381258D02*
X1442684Y1381050D01*
G01X1443073Y1384407D02*
X1442684Y1384200D01*
G01X1443073Y1387557D02*
X1442684Y1387350D01*
G01X1443073Y1390707D02*
X1442684Y1390499D01*
G01X1443073Y1393856D02*
X1442684Y1393649D01*
G01X1443073Y1397006D02*
X1442684Y1396798D01*
G01X1443073Y1400155D02*
X1442684Y1399948D01*
G01X1443073Y1403305D02*
X1442684Y1403098D01*
G01X1443073Y1406455D02*
X1442684Y1406247D01*
G01X1443243Y1368659D02*
X1442772Y1368364D01*
G01X1442684Y1368452D02*
X1442543Y1368364D01*
G01X1443243Y1371809D02*
X1442772Y1371514D01*
G01X1442684Y1371601D02*
X1442543Y1371514D01*
G01X1443243Y1374959D02*
X1442772Y1374663D01*
G01X1442684Y1374751D02*
X1442543Y1374663D01*
G01X1443073Y1409604D02*
X1442684Y1409397D01*
G01X1443073Y1412754D02*
X1442684Y1412546D01*
G01X1443073Y1415903D02*
X1442684Y1415696D01*
G01X1443073Y1419053D02*
X1442684Y1418846D01*
G01X1443073Y1422203D02*
X1442684Y1421995D01*
G01X1443073Y1425352D02*
X1442684Y1425145D01*
G01X1443073Y1428502D02*
X1442684Y1428294D01*
G01X1443243Y1378108D02*
X1442772Y1377813D01*
G01X1442684Y1377901D02*
X1442543Y1377813D01*
G01X1443243Y1381258D02*
X1442772Y1380963D01*
G01X1442684Y1381050D02*
X1442543Y1380963D01*
G01X1443243Y1384407D02*
X1442772Y1384112D01*
G01X1442684Y1384200D02*
X1442543Y1384112D01*
G01X1443243Y1387557D02*
X1442772Y1387262D01*
G01X1442684Y1387350D02*
X1442543Y1387262D01*
G01X1443243Y1390707D02*
X1442772Y1390411D01*
G01X1442684Y1390499D02*
X1442543Y1390411D01*
G01X1443243Y1393856D02*
X1442772Y1393561D01*
G01X1442684Y1393649D02*
X1442543Y1393561D01*
G01X1443243Y1397006D02*
X1442772Y1396711D01*
G01X1442684Y1396798D02*
X1442543Y1396711D01*
G01X1443243Y1400155D02*
X1442772Y1399860D01*
G01X1442684Y1399948D02*
X1442543Y1399860D01*
G01X1443243Y1403305D02*
X1442772Y1403010D01*
G01X1442684Y1403098D02*
X1442543Y1403010D01*
G01X1443243Y1406455D02*
X1442772Y1406159D01*
G01X1442684Y1406247D02*
X1442543Y1406159D01*
G01X1443243Y1409604D02*
X1442772Y1409309D01*
G01X1442684Y1409397D02*
X1442543Y1409309D01*
G01X1443243Y1412754D02*
X1442772Y1412459D01*
G01X1442684Y1412546D02*
X1442543Y1412459D01*
G01X1443243Y1415903D02*
X1442772Y1415608D01*
G01X1442684Y1415696D02*
X1442543Y1415608D01*
G01X1443243Y1419053D02*
X1442772Y1418758D01*
G01X1442684Y1418846D02*
X1442543Y1418758D01*
G01X1443243Y1422203D02*
X1442772Y1421907D01*
G01X1442684Y1421995D02*
X1442543Y1421907D01*
G01X1443243Y1425352D02*
X1442772Y1425057D01*
G01X1442684Y1425145D02*
X1442543Y1425057D01*
G01X1443243Y1428502D02*
X1442772Y1428207D01*
G01X1442684Y1428294D02*
X1442543Y1428207D01*
G01X1469507Y1367537D02*
X1469278Y1367281D01*
G01X1469507Y1370687D02*
X1469278Y1370431D01*
G01X1469507Y1373837D02*
X1469278Y1373581D01*
G01X1469507Y1376986D02*
X1469278Y1376730D01*
G01X1469507Y1380136D02*
X1469278Y1379880D01*
G01X1469507Y1383285D02*
X1469278Y1383029D01*
G01X1469507Y1386435D02*
X1469278Y1386179D01*
G01X1469507Y1389585D02*
X1469278Y1389329D01*
G01X1469507Y1392734D02*
X1469278Y1392478D01*
G01X1469507Y1395884D02*
X1469278Y1395628D01*
G01X1469507Y1399033D02*
X1469278Y1398777D01*
G01X1469507Y1402183D02*
X1469278Y1401927D01*
G01X1469507Y1405333D02*
X1469278Y1405077D01*
G01X1469507Y1408482D02*
X1469278Y1408226D01*
G01X1469507Y1411632D02*
X1469278Y1411376D01*
G01X1469507Y1414781D02*
X1469278Y1414525D01*
G01X1469507Y1417931D02*
X1469278Y1417675D01*
G01X1469507Y1421081D02*
X1469278Y1420825D01*
G01X1469507Y1424230D02*
X1469278Y1423974D01*
G01X1469507Y1427380D02*
X1469278Y1427124D01*
G01X1469855Y1367537D02*
X1469636Y1367267D01*
G01X1469855Y1370687D02*
X1469636Y1370417D01*
G01X1469855Y1373837D02*
X1469636Y1373566D01*
G01X1469855Y1376986D02*
X1469636Y1376716D01*
G01X1469855Y1380136D02*
X1469636Y1379866D01*
G01X1469855Y1383285D02*
X1469636Y1383015D01*
G01X1469855Y1386435D02*
X1469636Y1386165D01*
G01X1469855Y1389585D02*
X1469636Y1389315D01*
G01X1469855Y1392734D02*
X1469636Y1392464D01*
G01X1469855Y1395884D02*
X1469636Y1395614D01*
G01X1469855Y1399033D02*
X1469636Y1398763D01*
G01X1469855Y1402183D02*
X1469636Y1401913D01*
G01X1469855Y1405333D02*
X1469636Y1405063D01*
G01X1469855Y1408482D02*
X1469636Y1408212D01*
G01X1469855Y1411632D02*
X1469636Y1411362D01*
G01X1469855Y1414781D02*
X1469636Y1414511D01*
G01X1469855Y1417931D02*
X1469636Y1417661D01*
G01X1469855Y1421081D02*
X1469636Y1420811D01*
G01X1469855Y1424230D02*
X1469636Y1423960D01*
G01X1469855Y1427380D02*
X1469636Y1427110D01*
G01X1475291Y1366701D02*
Y1366435D01*
G01Y1368384D02*
Y1368029D01*
G01X1473889Y1367808D02*
Y1368605D01*
G01X1473708Y1367764D02*
Y1368650D01*
G01X1473165Y1366435D02*
Y1366701D01*
G01Y1367321D02*
Y1367587D01*
G01Y1368827D02*
Y1369092D01*
G01X1471000Y1368856D02*
Y1366888D01*
G01X1470921Y1368207D02*
Y1367537D01*
G01Y1374506D02*
Y1373837D01*
G01Y1371356D02*
Y1370687D01*
G01Y1377655D02*
Y1376986D01*
G01Y1383955D02*
Y1383285D01*
G01Y1380805D02*
Y1380136D01*
G01Y1387104D02*
Y1386435D01*
G01Y1393403D02*
Y1392734D01*
G01Y1390254D02*
Y1389585D01*
G01Y1396553D02*
Y1395884D01*
G01Y1402852D02*
Y1402183D01*
G01Y1399703D02*
Y1399033D01*
G01Y1406002D02*
Y1405333D01*
G01Y1412301D02*
Y1411632D01*
G01Y1409151D02*
Y1408482D01*
G01Y1415451D02*
Y1414781D01*
G01Y1421750D02*
Y1421081D01*
G01Y1418600D02*
Y1417931D01*
G01Y1424900D02*
Y1424230D01*
G01Y1428049D02*
Y1427380D01*
G01X1470574Y1368207D02*
Y1367537D01*
G01Y1374506D02*
Y1373837D01*
G01Y1371356D02*
Y1370687D01*
G01Y1377655D02*
Y1376986D01*
G01Y1383955D02*
Y1383285D01*
G01Y1380805D02*
Y1380136D01*
G01Y1387104D02*
Y1386435D01*
G01Y1393403D02*
Y1392734D01*
G01Y1390254D02*
Y1389585D01*
G01Y1396553D02*
Y1395884D01*
G01Y1402852D02*
Y1402183D01*
G01Y1399703D02*
Y1399033D01*
G01Y1406002D02*
Y1405333D01*
G01Y1412301D02*
Y1411632D01*
G01Y1409151D02*
Y1408482D01*
G01Y1415451D02*
Y1414781D01*
G01Y1421750D02*
Y1421081D01*
G01Y1418600D02*
Y1417931D01*
G01Y1424900D02*
Y1424230D01*
G01Y1428049D02*
Y1427380D01*
G01X1469631Y1368463D02*
Y1367281D01*
G01Y1374762D02*
Y1373581D01*
G01Y1371612D02*
Y1370431D01*
G01Y1377911D02*
Y1376730D01*
G01Y1384211D02*
Y1383029D01*
G01Y1381061D02*
Y1379880D01*
G01Y1387360D02*
Y1386179D01*
G01Y1393659D02*
Y1392478D01*
G01Y1390510D02*
Y1389329D01*
G01Y1396809D02*
Y1395628D01*
G01Y1403108D02*
Y1401927D01*
G01Y1399959D02*
Y1398777D01*
G01Y1406258D02*
Y1405077D01*
G01Y1409407D02*
Y1408226D01*
G01Y1415707D02*
Y1414525D01*
G01Y1412557D02*
Y1411376D01*
G01Y1418856D02*
Y1417675D01*
G01Y1425155D02*
Y1423974D01*
G01Y1422006D02*
Y1420825D01*
G01Y1428305D02*
Y1427124D01*
G01X1469278Y1368463D02*
Y1367281D01*
G01Y1374762D02*
Y1373581D01*
G01Y1371612D02*
Y1370431D01*
G01Y1377911D02*
Y1376730D01*
G01Y1384211D02*
Y1383029D01*
G01Y1381061D02*
Y1379880D01*
G01Y1387360D02*
Y1386179D01*
G01Y1393659D02*
Y1392478D01*
G01Y1390510D02*
Y1389329D01*
G01Y1396809D02*
Y1395628D01*
G01Y1403108D02*
Y1401927D01*
G01Y1399959D02*
Y1398777D01*
G01Y1406258D02*
Y1405077D01*
G01Y1409407D02*
Y1408226D01*
G01Y1415707D02*
Y1414525D01*
G01Y1412557D02*
Y1411376D01*
G01Y1418856D02*
Y1417675D01*
G01Y1425155D02*
Y1423974D01*
G01Y1422006D02*
Y1420825D01*
G01Y1428305D02*
Y1427124D01*
G01X1467296Y1368463D02*
Y1367281D01*
G01Y1374762D02*
Y1373581D01*
G01Y1371612D02*
Y1370431D01*
G01Y1377911D02*
Y1376730D01*
G01Y1384211D02*
Y1383029D01*
G01Y1381061D02*
Y1379880D01*
G01Y1387360D02*
Y1386179D01*
G01Y1393659D02*
Y1392478D01*
G01Y1390510D02*
Y1389329D01*
G01Y1396809D02*
Y1395628D01*
G01Y1403108D02*
Y1401927D01*
G01Y1399959D02*
Y1398777D01*
G01Y1406258D02*
Y1405077D01*
G01Y1409407D02*
Y1408226D01*
G01Y1415707D02*
Y1414525D01*
G01Y1412557D02*
Y1411376D01*
G01Y1418856D02*
Y1417675D01*
G01Y1425155D02*
Y1423974D01*
G01Y1422006D02*
Y1420825D01*
G01Y1428305D02*
Y1427124D01*
G01X1467186Y1368463D02*
Y1367281D01*
G01Y1374762D02*
Y1373581D01*
G01Y1371612D02*
Y1370431D01*
G01Y1377911D02*
Y1376730D01*
G01Y1384211D02*
Y1383029D01*
G01Y1381061D02*
Y1379880D01*
G01Y1387360D02*
Y1386179D01*
G01Y1393659D02*
Y1392478D01*
G01Y1390510D02*
Y1389329D01*
G01Y1396809D02*
Y1395628D01*
G01Y1403108D02*
Y1401927D01*
G01Y1399959D02*
Y1398777D01*
G01Y1406258D02*
Y1405077D01*
G01Y1409407D02*
Y1408226D01*
G01Y1415707D02*
Y1414525D01*
G01Y1412557D02*
Y1411376D01*
G01Y1418856D02*
Y1417675D01*
G01Y1425155D02*
Y1423974D01*
G01Y1422006D02*
Y1420825D01*
G01Y1428305D02*
Y1427124D01*
G01X1461157Y1366888D02*
Y1368856D01*
G01X1458405Y1368463D02*
Y1367281D01*
G01Y1374762D02*
Y1373581D01*
G01Y1371612D02*
Y1370431D01*
G01Y1377911D02*
Y1376730D01*
G01Y1384211D02*
Y1383029D01*
G01Y1381061D02*
Y1379880D01*
G01Y1387360D02*
Y1386179D01*
G01Y1393659D02*
Y1392478D01*
G01Y1390510D02*
Y1389329D01*
G01Y1396809D02*
Y1395628D01*
G01Y1403108D02*
Y1401927D01*
G01Y1399959D02*
Y1398777D01*
G01Y1406258D02*
Y1405077D01*
G01Y1409407D02*
Y1408226D01*
G01Y1415707D02*
Y1414525D01*
G01Y1412557D02*
Y1411376D01*
G01Y1418856D02*
Y1417675D01*
G01Y1425155D02*
Y1423974D01*
G01Y1422006D02*
Y1420825D01*
G01Y1428305D02*
Y1427124D01*
G01X1458295Y1368463D02*
Y1367281D01*
G01Y1374762D02*
Y1373581D01*
G01Y1371612D02*
Y1370431D01*
G01Y1377911D02*
Y1376730D01*
G01Y1384211D02*
Y1383029D01*
G01Y1381061D02*
Y1379880D01*
G01Y1387360D02*
Y1386179D01*
G01Y1393659D02*
Y1392478D01*
G01Y1390510D02*
Y1389329D01*
G01Y1396809D02*
Y1395628D01*
G01Y1403108D02*
Y1401927D01*
G01Y1399959D02*
Y1398777D01*
G01Y1406258D02*
Y1405077D01*
G01Y1409407D02*
Y1408226D01*
G01Y1415707D02*
Y1414525D01*
G01Y1412557D02*
Y1411376D01*
G01Y1418856D02*
Y1417675D01*
G01Y1425155D02*
Y1423974D01*
G01Y1422006D02*
Y1420825D01*
G01Y1428305D02*
Y1427124D01*
G01X1457929Y1368463D02*
Y1367281D01*
G01Y1374762D02*
Y1373581D01*
G01Y1371612D02*
Y1370431D01*
G01Y1377911D02*
Y1376730D01*
G01Y1384211D02*
Y1383029D01*
G01Y1381061D02*
Y1379880D01*
G01Y1387360D02*
Y1386179D01*
G01Y1393659D02*
Y1392478D01*
G01Y1390510D02*
Y1389329D01*
G01Y1396809D02*
Y1395628D01*
G01Y1403108D02*
Y1401927D01*
G01Y1399959D02*
Y1398777D01*
G01Y1406258D02*
Y1405077D01*
G01Y1409407D02*
Y1408226D01*
G01Y1415707D02*
Y1414525D01*
G01Y1412557D02*
Y1411376D01*
G01Y1418856D02*
Y1417675D01*
G01Y1425155D02*
Y1423974D01*
G01Y1422006D02*
Y1420825D01*
G01Y1428305D02*
Y1427124D01*
G01X1457732Y1367281D02*
Y1366691D01*
G01Y1369053D02*
Y1368463D01*
G01Y1373581D02*
Y1372990D01*
G01Y1370431D02*
Y1369840D01*
G01Y1372203D02*
Y1371612D01*
G01Y1376730D02*
Y1376140D01*
G01Y1378502D02*
Y1377911D01*
G01Y1375352D02*
Y1374762D01*
G01Y1383029D02*
Y1382439D01*
G01Y1379880D02*
Y1379289D01*
G01Y1381651D02*
Y1381061D01*
G01Y1386179D02*
Y1385588D01*
G01Y1387951D02*
Y1387360D01*
G01Y1384801D02*
Y1384211D01*
G01Y1392478D02*
Y1391888D01*
G01Y1389329D02*
Y1388738D01*
G01Y1391100D02*
Y1390510D01*
G01Y1395628D02*
Y1395037D01*
G01Y1397400D02*
Y1396809D01*
G01Y1394250D02*
Y1393659D01*
G01Y1401927D02*
Y1401337D01*
G01Y1398777D02*
Y1398187D01*
G01Y1400549D02*
Y1399959D01*
G01Y1405077D02*
Y1404486D01*
G01Y1406848D02*
Y1406258D01*
G01Y1403699D02*
Y1403108D01*
G01Y1411376D02*
Y1410785D01*
G01Y1408226D02*
Y1407636D01*
G01Y1409998D02*
Y1409407D01*
G01Y1414525D02*
Y1413935D01*
G01Y1416297D02*
Y1415707D01*
G01Y1413148D02*
Y1412557D01*
G01Y1420825D02*
Y1420234D01*
G01Y1417675D02*
Y1417085D01*
G01Y1419447D02*
Y1418856D01*
G01Y1423974D02*
Y1423384D01*
G01Y1425746D02*
Y1425155D01*
G01Y1422596D02*
Y1422006D01*
G01Y1430274D02*
Y1429683D01*
G01Y1427124D02*
Y1426533D01*
G01Y1428896D02*
Y1428305D01*
G01X1457535Y1367281D02*
Y1366691D01*
G01Y1369053D02*
Y1368463D01*
G01Y1373581D02*
Y1372990D01*
G01Y1370431D02*
Y1369840D01*
G01Y1372203D02*
Y1371612D01*
G01Y1376730D02*
Y1376140D01*
G01Y1378502D02*
Y1377911D01*
G01Y1375352D02*
Y1374762D01*
G01Y1383029D02*
Y1382439D01*
G01Y1379880D02*
Y1379289D01*
G01Y1381651D02*
Y1381061D01*
G01Y1386179D02*
Y1385588D01*
G01Y1387951D02*
Y1387360D01*
G01Y1384801D02*
Y1384211D01*
G01Y1392478D02*
Y1391888D01*
G01Y1389329D02*
Y1388738D01*
G01Y1391100D02*
Y1390510D01*
G01Y1395628D02*
Y1395037D01*
G01Y1397400D02*
Y1396809D01*
G01Y1394250D02*
Y1393659D01*
G01Y1401927D02*
Y1401337D01*
G01Y1398777D02*
Y1398187D01*
G01Y1400549D02*
Y1399959D01*
G01Y1405077D02*
Y1404486D01*
G01Y1406848D02*
Y1406258D01*
G01Y1403699D02*
Y1403108D01*
G01Y1411376D02*
Y1410785D01*
G01Y1408226D02*
Y1407636D01*
G01Y1409998D02*
Y1409407D01*
G01Y1414525D02*
Y1413935D01*
G01Y1416297D02*
Y1415707D01*
G01Y1413148D02*
Y1412557D01*
G01Y1420825D02*
Y1420234D01*
G01Y1417675D02*
Y1417085D01*
G01Y1419447D02*
Y1418856D01*
G01Y1423974D02*
Y1423384D01*
G01Y1425746D02*
Y1425155D01*
G01Y1422596D02*
Y1422006D01*
G01Y1430274D02*
Y1429683D01*
G01Y1427124D02*
Y1426533D01*
G01Y1428896D02*
Y1428305D01*
G01X1449937Y1507242D02*
Y1363935D01*
G01X1444212Y1368659D02*
Y1367085D01*
G01Y1374959D02*
Y1373384D01*
G01Y1371809D02*
Y1370234D01*
G01Y1378108D02*
Y1376533D01*
G01Y1384407D02*
Y1382833D01*
G01Y1381258D02*
Y1379683D01*
G01Y1387557D02*
Y1385982D01*
G01Y1390707D02*
Y1389132D01*
G01Y1397006D02*
Y1395431D01*
G01Y1393856D02*
Y1392281D01*
G01Y1400155D02*
Y1398581D01*
G01Y1406455D02*
Y1404880D01*
G01Y1403305D02*
Y1401730D01*
G01Y1409604D02*
Y1408029D01*
G01Y1415903D02*
Y1414329D01*
G01Y1412754D02*
Y1411179D01*
G01Y1419053D02*
Y1417478D01*
G01Y1425352D02*
Y1423777D01*
G01Y1422203D02*
Y1420628D01*
G01Y1428502D02*
Y1426927D01*
G01X1442684Y1368452D02*
Y1367292D01*
G01Y1374751D02*
Y1373591D01*
G01Y1371601D02*
Y1370442D01*
G01Y1377901D02*
Y1376741D01*
G01Y1384200D02*
Y1383040D01*
G01Y1381050D02*
Y1379890D01*
G01Y1387350D02*
Y1386190D01*
G01Y1393649D02*
Y1392489D01*
G01Y1390499D02*
Y1389339D01*
G01Y1396798D02*
Y1395638D01*
G01Y1403098D02*
Y1401938D01*
G01Y1399948D02*
Y1398788D01*
G01Y1406247D02*
Y1405087D01*
G01Y1409397D02*
Y1408237D01*
G01Y1415696D02*
Y1414536D01*
G01Y1412546D02*
Y1411387D01*
G01Y1418846D02*
Y1417686D01*
G01Y1425145D02*
Y1423985D01*
G01Y1421995D02*
Y1420835D01*
G01Y1428294D02*
Y1427135D01*
G01X1441235Y1431340D02*
X1441007D01*
G01X1439047Y1431318D02*
X1438785D01*
G01X1439047Y1430410D02*
X1438785D01*
G01X1441235Y1430388D02*
X1441007D01*
G01X1440094Y1431330D02*
X1438785Y1431318D01*
G01X1441235Y1431340D02*
X1440094Y1431330D01*
G01X1437751Y1431304D02*
X1436420Y1431292D01*
G01X1442543Y1431356D02*
X1441007Y1431340D01*
G01X1442543Y1431356D02*
X1439047Y1431318D01*
G01X1441235Y1431340D02*
X1442772Y1431356D01*
G01X1439047Y1431318D02*
X1440094Y1431330D01*
G01X1438785Y1431318D02*
X1436420Y1431292D01*
G01X1437751Y1431304D02*
X1439047Y1431318D01*
G01Y1430410D02*
X1442543Y1430372D01*
G01X1437751Y1430424D02*
X1441007Y1430388D01*
G01X1438785Y1430410D02*
X1436420Y1430436D01*
G01X1441235Y1430388D02*
X1442772Y1430372D01*
G01X1441235Y1430388D02*
X1438785Y1430410D01*
G01X1437751Y1430424D02*
X1436420Y1430436D01*
G01X1441235Y1431340D02*
Y1430388D01*
G01X1441007Y1431340D02*
Y1430388D01*
G01X1439047Y1431318D02*
Y1430410D01*
G01X1438785Y1431318D02*
Y1430410D01*
G01X1437751Y1431298D02*
Y1430430D01*
G01X1436420Y1431292D02*
Y1430436D01*
G01X1440094Y1500621D02*
X1438785Y1500610D01*
G01X1441235Y1500631D02*
X1440094Y1500621D01*
G01X1437751Y1500595D02*
X1436420Y1500583D01*
G01X1442543Y1500648D02*
X1441007Y1500631D01*
G01X1442543Y1500648D02*
X1439047Y1500610D01*
G01X1441235Y1500631D02*
X1442772Y1500648D01*
G01X1439047Y1500610D02*
X1440094Y1500621D01*
G01X1438785Y1500610D02*
X1436420Y1500583D01*
G01X1437751Y1500595D02*
X1439047Y1500610D01*
G01Y1499701D02*
X1442543Y1499663D01*
G01X1437751Y1499716D02*
X1441007Y1499680D01*
G01X1439047Y1496552D02*
X1442543Y1496514D01*
G01X1437751Y1496566D02*
X1441007Y1496530D01*
G01X1439047Y1493402D02*
X1442543Y1493364D01*
G01X1437751Y1493416D02*
X1441007Y1493381D01*
G01X1439047Y1490252D02*
X1442543Y1490214D01*
G01X1437751Y1490267D02*
X1441007Y1490231D01*
G01X1439047Y1487103D02*
X1442543Y1487065D01*
G01X1437751Y1487117D02*
X1441007Y1487081D01*
G01X1439047Y1483953D02*
X1442543Y1483915D01*
G01X1437751Y1483968D02*
X1441007Y1483932D01*
G01X1439047Y1480804D02*
X1442543Y1480766D01*
G01X1437751Y1480818D02*
X1441007Y1480782D01*
G01X1439047Y1477654D02*
X1442543Y1477616D01*
G01X1437751Y1477668D02*
X1441007Y1477633D01*
G01X1439047Y1474504D02*
X1442543Y1474466D01*
G01X1437751Y1474519D02*
X1441007Y1474483D01*
G01X1439047Y1471355D02*
X1442543Y1471317D01*
G01X1437751Y1471369D02*
X1441007Y1471333D01*
G01X1439047Y1468205D02*
X1442543Y1468167D01*
G01X1437751Y1468220D02*
X1441007Y1468184D01*
G01X1439047Y1465056D02*
X1442543Y1465018D01*
G01X1437751Y1465070D02*
X1441007Y1465034D01*
G01X1439047Y1461906D02*
X1442543Y1461868D01*
G01X1437751Y1461920D02*
X1441007Y1461884D01*
G01X1439047Y1458756D02*
X1442543Y1458718D01*
G01X1437751Y1458771D02*
X1441007Y1458735D01*
G01X1439047Y1455607D02*
X1442543Y1455569D01*
G01X1437751Y1455621D02*
X1441007Y1455585D01*
G01X1439047Y1452457D02*
X1442543Y1452419D01*
G01X1437751Y1452472D02*
X1441007Y1452436D01*
G01X1439047Y1449308D02*
X1442543Y1449270D01*
G01X1437751Y1449322D02*
X1441007Y1449286D01*
G01X1439047Y1446158D02*
X1442543Y1446120D01*
G01X1437751Y1446172D02*
X1441007Y1446136D01*
G01X1439047Y1443008D02*
X1442543Y1442970D01*
G01X1437751Y1443023D02*
X1441007Y1442987D01*
G01X1439047Y1439859D02*
X1442543Y1439821D01*
G01X1437751Y1439873D02*
X1441007Y1439837D01*
G01X1439047Y1436709D02*
X1442543Y1436671D01*
G01X1437751Y1436723D02*
X1441007Y1436688D01*
G01X1438785Y1499701D02*
X1436420Y1499727D01*
G01X1438785Y1496552D02*
X1436420Y1496578D01*
G01X1438785Y1493402D02*
X1436420Y1493428D01*
G01X1438785Y1490253D02*
X1436420Y1490279D01*
G01X1438785Y1487103D02*
X1436420Y1487129D01*
G01X1438785Y1483953D02*
X1436420Y1483979D01*
G01X1438785Y1480804D02*
X1436420Y1480830D01*
G01X1438785Y1477654D02*
X1436420Y1477680D01*
G01X1438785Y1474504D02*
X1436420Y1474531D01*
G01X1438785Y1471355D02*
X1436420Y1471381D01*
G01X1438785Y1468205D02*
X1436420Y1468231D01*
G01X1438785Y1465056D02*
X1436420Y1465082D01*
G01X1438785Y1461906D02*
X1436420Y1461932D01*
G01X1438785Y1458756D02*
X1436420Y1458783D01*
G01X1438785Y1455607D02*
X1436420Y1455633D01*
G01X1438785Y1452457D02*
X1436420Y1452483D01*
G01X1438785Y1449308D02*
X1436420Y1449334D01*
G01X1438785Y1446158D02*
X1436420Y1446184D01*
G01X1438785Y1443008D02*
X1436420Y1443034D01*
G01X1438785Y1439859D02*
X1436420Y1439885D01*
G01X1438785Y1436709D02*
X1436420Y1436735D01*
G01X1441235Y1499680D02*
X1442772Y1499663D01*
G01X1441235Y1496530D02*
X1442772Y1496514D01*
G01X1441235Y1493381D02*
X1442772Y1493364D01*
G01X1441235Y1490231D02*
X1442772Y1490214D01*
G01X1441235Y1487081D02*
X1442772Y1487065D01*
G01X1441235Y1483932D02*
X1442772Y1483915D01*
G01X1441235Y1480782D02*
X1442772Y1480766D01*
G01X1441235Y1477633D02*
X1442772Y1477616D01*
G01X1441235Y1474483D02*
X1442772Y1474466D01*
G01X1441235Y1471333D02*
X1442772Y1471317D01*
G01X1441235Y1468184D02*
X1442772Y1468167D01*
G01X1441235Y1465034D02*
X1442772Y1465018D01*
G01X1441235Y1461884D02*
X1442772Y1461868D01*
G01X1441235Y1458735D02*
X1442772Y1458718D01*
G01X1441235Y1455585D02*
X1442772Y1455569D01*
G01X1441235Y1452436D02*
X1442772Y1452419D01*
G01X1441235Y1449286D02*
X1442772Y1449270D01*
G01X1441235Y1446136D02*
X1442772Y1446120D01*
G01X1441235Y1442987D02*
X1442772Y1442970D01*
G01X1441235Y1439837D02*
X1442772Y1439821D01*
G01X1441235Y1436688D02*
X1442772Y1436671D01*
G01X1441235Y1499680D02*
X1438785Y1499701D01*
G01X1437751Y1499716D02*
X1436420Y1499727D01*
G01X1441235Y1496530D02*
X1438785Y1496552D01*
G01X1437751Y1496566D02*
X1436420Y1496578D01*
G01X1441235Y1493381D02*
X1438785Y1493402D01*
G01X1437751Y1493416D02*
X1436420Y1493428D01*
G01X1441235Y1490231D02*
X1438785Y1490253D01*
G01X1437751Y1490267D02*
X1436420Y1490279D01*
G01X1441235Y1487081D02*
X1438785Y1487103D01*
G01X1437751Y1487117D02*
X1436420Y1487129D01*
G01X1441235Y1483932D02*
X1438785Y1483953D01*
G01X1437751Y1483968D02*
X1436420Y1483979D01*
G01X1441235Y1480782D02*
X1438785Y1480804D01*
G01X1437751Y1480818D02*
X1436420Y1480830D01*
G01X1441235Y1477633D02*
X1438785Y1477654D01*
G01X1437751Y1477668D02*
X1436420Y1477680D01*
G01X1441235Y1474483D02*
X1438785Y1474504D01*
G01X1437751Y1474519D02*
X1436420Y1474531D01*
G01X1441235Y1471333D02*
X1438785Y1471355D01*
G01X1437751Y1471369D02*
X1436420Y1471381D01*
G01X1441235Y1468184D02*
X1438785Y1468205D01*
G01X1437751Y1468220D02*
X1436420Y1468231D01*
G01X1441235Y1465034D02*
X1438785Y1465056D01*
G01X1437751Y1465070D02*
X1436420Y1465082D01*
G01X1441235Y1461884D02*
X1438785Y1461906D01*
G01X1437751Y1461920D02*
X1436420Y1461932D01*
G01X1441235Y1458735D02*
X1438785Y1458756D01*
G01X1437751Y1458771D02*
X1436420Y1458783D01*
G01X1441235Y1455585D02*
X1438785Y1455607D01*
G01X1437751Y1455621D02*
X1436420Y1455633D01*
G01X1441235Y1452436D02*
X1438785Y1452457D01*
G01X1437751Y1452472D02*
X1436420Y1452483D01*
G01X1441235Y1449286D02*
X1438785Y1449308D01*
G01X1437751Y1449322D02*
X1436420Y1449334D01*
G01X1441235Y1446136D02*
X1438785Y1446158D01*
G01X1437751Y1446172D02*
X1436420Y1446184D01*
G01X1441235Y1442987D02*
X1438785Y1443008D01*
G01X1437751Y1443023D02*
X1436420Y1443034D01*
G01X1441235Y1439837D02*
X1438785Y1439859D01*
G01X1437751Y1439873D02*
X1436420Y1439885D01*
G01X1441235Y1436688D02*
X1438785Y1436709D01*
G01X1437751Y1436723D02*
X1436420Y1436735D01*
G01X1441235Y1433538D02*
X1438785Y1433560D01*
G01X1437751Y1433574D02*
X1436420Y1433586D01*
G01X1441007Y1500631D02*
X1441235D01*
G01X1439047Y1500610D02*
X1438785D01*
G01X1439047Y1499701D02*
X1438785D01*
G01X1441235Y1499680D02*
X1441007D01*
G01X1441235Y1497481D02*
X1441007D01*
G01X1439047Y1497460D02*
X1438785D01*
G01X1439047Y1496552D02*
X1438785D01*
G01X1441235Y1496530D02*
X1441007D01*
G01X1441235Y1494332D02*
X1441007D01*
G01X1439047Y1494310D02*
X1438785D01*
G01X1439047Y1493402D02*
X1438785D01*
G01X1441235Y1493381D02*
X1441007D01*
G01X1441235Y1491182D02*
X1441007D01*
G01X1439047Y1491161D02*
X1438785D01*
G01X1439047Y1490253D02*
X1438785D01*
G01X1441235Y1490231D02*
X1441007D01*
G01X1441235Y1488033D02*
X1441007D01*
G01X1439047Y1488011D02*
X1438785D01*
G01X1439047Y1487103D02*
X1438785D01*
G01X1441235Y1487081D02*
X1441007D01*
G01X1441235Y1484883D02*
X1441007D01*
G01X1439047Y1484861D02*
X1438785D01*
G01X1439047Y1483953D02*
X1438785D01*
G01X1441235Y1483932D02*
X1441007D01*
G01X1441235Y1481733D02*
X1441007D01*
G01X1439047Y1481712D02*
X1438785D01*
G01X1439047Y1480804D02*
X1438785D01*
G01X1441235Y1480782D02*
X1441007D01*
G01X1441235Y1478584D02*
X1441007D01*
G01X1439047Y1478562D02*
X1438785D01*
G01X1439047Y1477654D02*
X1438785D01*
G01X1441235Y1477633D02*
X1441007D01*
G01X1441235Y1475434D02*
X1441007D01*
G01X1439047Y1475413D02*
X1438785D01*
G01X1439047Y1474504D02*
X1438785D01*
G01X1441235Y1474483D02*
X1441007D01*
G01X1441235Y1472285D02*
X1441007D01*
G01X1439047Y1472263D02*
X1438785D01*
G01X1439047Y1471355D02*
X1438785D01*
G01X1441235Y1471333D02*
X1441007D01*
G01X1441235Y1469135D02*
X1441007D01*
G01X1439047Y1469113D02*
X1438785D01*
G01X1439047Y1468205D02*
X1438785D01*
G01X1441235Y1468184D02*
X1441007D01*
G01X1441235Y1465985D02*
X1441007D01*
G01X1439047Y1465964D02*
X1438785D01*
G01X1439047Y1465056D02*
X1438785D01*
G01X1441235Y1465034D02*
X1441007D01*
G01X1441235Y1462836D02*
X1441007D01*
G01X1439047Y1462814D02*
X1438785D01*
G01X1439047Y1461906D02*
X1438785D01*
G01X1441235Y1461884D02*
X1441007D01*
G01X1441235Y1459686D02*
X1441007D01*
G01X1439047Y1459665D02*
X1438785D01*
G01X1439047Y1458756D02*
X1438785D01*
G01X1441235Y1458735D02*
X1441007D01*
G01X1441235Y1456537D02*
X1441007D01*
G01X1439047Y1456515D02*
X1438785D01*
G01X1439047Y1455607D02*
X1438785D01*
G01X1441235Y1455585D02*
X1441007D01*
G01X1441235Y1453387D02*
X1441007D01*
G01X1439047Y1453365D02*
X1438785D01*
G01X1439047Y1452457D02*
X1438785D01*
G01X1441235Y1452436D02*
X1441007D01*
G01X1441235Y1450237D02*
X1441007D01*
G01X1439047Y1450216D02*
X1438785D01*
G01X1439047Y1449308D02*
X1438785D01*
G01X1441235Y1449286D02*
X1441007D01*
G01X1441235Y1447088D02*
X1441007D01*
G01X1439047Y1447066D02*
X1438785D01*
G01X1439047Y1446158D02*
X1438785D01*
G01X1441235Y1446136D02*
X1441007D01*
G01X1441235Y1443938D02*
X1441007D01*
G01X1439047Y1443917D02*
X1438785D01*
G01X1439047Y1443008D02*
X1438785D01*
G01X1441235Y1442987D02*
X1441007D01*
G01X1441235Y1440789D02*
X1441007D01*
G01X1439047Y1440767D02*
X1438785D01*
G01X1439047Y1439859D02*
X1438785D01*
G01X1441235Y1439837D02*
X1441007D01*
G01X1441235Y1437639D02*
X1441007D01*
G01X1439047Y1437617D02*
X1438785D01*
G01X1439047Y1436709D02*
X1438785D01*
G01X1441235Y1436688D02*
X1441007D01*
G01X1441235Y1434489D02*
X1441007D01*
G01X1439047Y1434468D02*
X1438785D01*
G01X1439047Y1433560D02*
X1438785D01*
G01X1441235Y1433538D02*
X1441007D01*
G01X1440094Y1497471D02*
X1438785Y1497460D01*
G01X1441235Y1497481D02*
X1440094Y1497471D01*
G01Y1494322D02*
X1438785Y1494310D01*
G01X1441235Y1494332D02*
X1440094Y1494322D01*
G01Y1491172D02*
X1438785Y1491161D01*
G01X1441235Y1491182D02*
X1440094Y1491172D01*
G01Y1488023D02*
X1438785Y1488011D01*
G01X1441235Y1488033D02*
X1440094Y1488023D01*
G01Y1484873D02*
X1438785Y1484861D01*
G01X1441235Y1484883D02*
X1440094Y1484873D01*
G01Y1481723D02*
X1438785Y1481712D01*
G01X1441235Y1481733D02*
X1440094Y1481723D01*
G01Y1478574D02*
X1438785Y1478562D01*
G01X1441235Y1478584D02*
X1440094Y1478574D01*
G01Y1475424D02*
X1438785Y1475413D01*
G01X1441235Y1475434D02*
X1440094Y1475424D01*
G01Y1472275D02*
X1438785Y1472263D01*
G01X1441235Y1472285D02*
X1440094Y1472275D01*
G01Y1469125D02*
X1438785Y1469113D01*
G01X1441235Y1469135D02*
X1440094Y1469125D01*
G01Y1465975D02*
X1438785Y1465964D01*
G01X1441235Y1465985D02*
X1440094Y1465975D01*
G01Y1462826D02*
X1438785Y1462814D01*
G01X1441235Y1462836D02*
X1440094Y1462826D01*
G01Y1459676D02*
X1438785Y1459665D01*
G01X1441235Y1459686D02*
X1440094Y1459676D01*
G01Y1456527D02*
X1438785Y1456515D01*
G01X1441235Y1456537D02*
X1440094Y1456527D01*
G01Y1453377D02*
X1438785Y1453365D01*
G01X1441235Y1453387D02*
X1440094Y1453377D01*
G01Y1450227D02*
X1438785Y1450216D01*
G01X1441235Y1450237D02*
X1440094Y1450227D01*
G01X1438785Y1447066D02*
X1440094Y1447078D01*
G01X1441235Y1447088D02*
X1440094Y1447078D01*
G01Y1443928D02*
X1438785Y1443917D01*
G01X1441235Y1443938D02*
X1440094Y1443928D01*
G01Y1440779D02*
X1438785Y1440767D01*
G01X1441235Y1440789D02*
X1440094Y1440779D01*
G01Y1437629D02*
X1438785Y1437617D01*
G01X1441235Y1437639D02*
X1440094Y1437629D01*
G01Y1434479D02*
X1438785Y1434468D01*
G01X1441235Y1434489D02*
X1440094Y1434479D01*
G01X1437751Y1497446D02*
X1436420Y1497434D01*
G01X1437751Y1494296D02*
X1436420Y1494284D01*
G01X1437751Y1491146D02*
X1436420Y1491135D01*
G01X1437751Y1487997D02*
X1436420Y1487985D01*
G01X1437751Y1484847D02*
X1436420Y1484835D01*
G01X1437751Y1481698D02*
X1436420Y1481686D01*
G01X1437751Y1478548D02*
X1436420Y1478536D01*
G01X1437751Y1475398D02*
X1436420Y1475387D01*
G01X1437751Y1472249D02*
X1436420Y1472237D01*
G01X1437751Y1469099D02*
X1436420Y1469087D01*
G01X1437751Y1465950D02*
X1436420Y1465938D01*
G01X1437751Y1462800D02*
X1436420Y1462788D01*
G01X1437751Y1459650D02*
X1436420Y1459639D01*
G01X1437751Y1456501D02*
X1436420Y1456489D01*
G01X1437751Y1453351D02*
X1436420Y1453339D01*
G01X1437751Y1450202D02*
X1436420Y1450190D01*
G01X1437751Y1447052D02*
X1436420Y1447040D01*
G01X1437751Y1443902D02*
X1436420Y1443891D01*
G01X1437751Y1440753D02*
X1436420Y1440741D01*
G01X1437751Y1437603D02*
X1436420Y1437591D01*
G01X1437751Y1434453D02*
X1436420Y1434442D01*
G01X1442543Y1497498D02*
X1441007Y1497481D01*
G01X1442543Y1497498D02*
X1439047Y1497460D01*
G01X1441235Y1497481D02*
X1442772Y1497498D01*
G01X1442543Y1494348D02*
X1441007Y1494332D01*
G01X1442543Y1494348D02*
X1439047Y1494310D01*
G01X1441235Y1494332D02*
X1442772Y1494348D01*
G01X1442543Y1491199D02*
X1441007Y1491182D01*
G01X1442543Y1491199D02*
X1439047Y1491161D01*
G01X1441235Y1491182D02*
X1442772Y1491199D01*
G01X1442543Y1488049D02*
X1441007Y1488033D01*
G01X1442543Y1488049D02*
X1439047Y1488011D01*
G01X1441235Y1488033D02*
X1442772Y1488049D01*
G01X1442543Y1484900D02*
X1441007Y1484883D01*
G01X1442543Y1484900D02*
X1439047Y1484862D01*
G01X1441235Y1484883D02*
X1442772Y1484900D01*
G01X1442543Y1481750D02*
X1441007Y1481733D01*
G01X1442543Y1481750D02*
X1439047Y1481712D01*
G01X1441235Y1481733D02*
X1442772Y1481750D01*
G01X1442543Y1478600D02*
X1441007Y1478584D01*
G01X1442543Y1478600D02*
X1439047Y1478562D01*
G01X1441235Y1478584D02*
X1442772Y1478600D01*
G01X1442543Y1475451D02*
X1441007Y1475434D01*
G01X1442543Y1475451D02*
X1439047Y1475413D01*
G01X1441235Y1475434D02*
X1442772Y1475451D01*
G01X1442543Y1472301D02*
X1441007Y1472285D01*
G01X1442543Y1472301D02*
X1439047Y1472263D01*
G01X1441235Y1472285D02*
X1442772Y1472301D01*
G01X1442543Y1469151D02*
X1441007Y1469135D01*
G01X1442543Y1469151D02*
X1439047Y1469114D01*
G01X1441235Y1469135D02*
X1442772Y1469151D01*
G01X1442543Y1466002D02*
X1441007Y1465985D01*
G01X1442543Y1466002D02*
X1439047Y1465964D01*
G01X1441235Y1465985D02*
X1442772Y1466002D01*
G01X1442543Y1462852D02*
X1441007Y1462836D01*
G01X1442543Y1462852D02*
X1439047Y1462814D01*
G01X1441235Y1462836D02*
X1442772Y1462852D01*
G01X1442543Y1459703D02*
X1441007Y1459686D01*
G01X1442543Y1459703D02*
X1439047Y1459665D01*
G01X1441235Y1459686D02*
X1442772Y1459703D01*
G01X1442543Y1456553D02*
X1441007Y1456537D01*
G01X1442543Y1456553D02*
X1439047Y1456515D01*
G01X1441235Y1456537D02*
X1442772Y1456553D01*
G01X1442543Y1453403D02*
X1441007Y1453387D01*
G01X1442543Y1453403D02*
X1439047Y1453365D01*
G01X1441235Y1453387D02*
X1442772Y1453403D01*
G01X1442543Y1450254D02*
X1441007Y1450237D01*
G01X1442543Y1450254D02*
X1439047Y1450216D01*
G01X1441235Y1450237D02*
X1442772Y1450254D01*
G01X1442543Y1447104D02*
X1441007Y1447088D01*
G01X1442543Y1447104D02*
X1439047Y1447066D01*
G01X1441235Y1447088D02*
X1442772Y1447104D01*
G01X1442543Y1443955D02*
X1441007Y1443938D01*
G01X1442543Y1443955D02*
X1439047Y1443917D01*
G01X1441235Y1443938D02*
X1442772Y1443955D01*
G01X1442543Y1440805D02*
X1441007Y1440789D01*
G01X1442543Y1440805D02*
X1439047Y1440767D01*
G01X1441235Y1440789D02*
X1442772Y1440805D01*
G01X1442543Y1437655D02*
X1441007Y1437639D01*
G01X1442543Y1437655D02*
X1439047Y1437617D01*
G01X1441235Y1437639D02*
X1442772Y1437655D01*
G01X1442543Y1434506D02*
X1441007Y1434489D01*
G01X1442543Y1434506D02*
X1439047Y1434468D01*
G01X1441235Y1434489D02*
X1442772Y1434506D01*
G01X1439047Y1497460D02*
X1440094Y1497471D01*
G01X1438785Y1497460D02*
X1436420Y1497434D01*
G01X1437751Y1497446D02*
X1439047Y1497460D01*
G01Y1494310D02*
X1440094Y1494322D01*
G01X1438785Y1494310D02*
X1436420Y1494284D01*
G01X1437751Y1494296D02*
X1439047Y1494310D01*
G01Y1491161D02*
X1440094Y1491172D01*
G01X1438785Y1491161D02*
X1436420Y1491135D01*
G01X1437751Y1491146D02*
X1439047Y1491161D01*
G01Y1488011D02*
X1440094Y1488023D01*
G01X1438785Y1488011D02*
X1436420Y1487985D01*
G01X1437751Y1487997D02*
X1439047Y1488011D01*
G01Y1484861D02*
X1440094Y1484873D01*
G01X1438785Y1484861D02*
X1436420Y1484835D01*
G01X1437751Y1484847D02*
X1439047Y1484861D01*
G01Y1481712D02*
X1440094Y1481723D01*
G01X1438785Y1481712D02*
X1436420Y1481686D01*
G01X1437751Y1481698D02*
X1439047Y1481712D01*
G01Y1478562D02*
X1440094Y1478574D01*
G01X1438785Y1478562D02*
X1436420Y1478536D01*
G01X1437751Y1478548D02*
X1439047Y1478562D01*
G01Y1475413D02*
X1440094Y1475424D01*
G01X1438785Y1475413D02*
X1436420Y1475387D01*
G01X1437751Y1475398D02*
X1439047Y1475413D01*
G01Y1472263D02*
X1440094Y1472275D01*
G01X1438785Y1472263D02*
X1436420Y1472237D01*
G01X1437751Y1472249D02*
X1439047Y1472263D01*
G01Y1469113D02*
X1440094Y1469125D01*
G01X1438785Y1469113D02*
X1436420Y1469087D01*
G01X1437751Y1469099D02*
X1439047Y1469113D01*
G01Y1465964D02*
X1440094Y1465975D01*
G01X1438785Y1465964D02*
X1436420Y1465938D01*
G01X1437751Y1465950D02*
X1439047Y1465964D01*
G01Y1462814D02*
X1440094Y1462826D01*
G01X1438785Y1462814D02*
X1436420Y1462788D01*
G01X1437751Y1462800D02*
X1439047Y1462814D01*
G01Y1459665D02*
X1440094Y1459676D01*
G01X1438785Y1459665D02*
X1436420Y1459639D01*
G01X1437751Y1459650D02*
X1439047Y1459665D01*
G01Y1456515D02*
X1440094Y1456527D01*
G01X1438785Y1456515D02*
X1436420Y1456489D01*
G01X1437751Y1456501D02*
X1439047Y1456515D01*
G01Y1453365D02*
X1440094Y1453377D01*
G01X1438785Y1453365D02*
X1436420Y1453339D01*
G01X1437751Y1453351D02*
X1439047Y1453365D01*
G01Y1450216D02*
X1440094Y1450227D01*
G01X1438785Y1450216D02*
X1436420Y1450190D01*
G01X1437751Y1450202D02*
X1439047Y1450216D01*
G01Y1447066D02*
X1440094Y1447078D01*
G01X1438785Y1447066D02*
X1436420Y1447040D01*
G01X1437751Y1447052D02*
X1439047Y1447066D01*
G01Y1443917D02*
X1440094Y1443928D01*
G01X1438785Y1443917D02*
X1436420Y1443891D01*
G01X1437751Y1443902D02*
X1439047Y1443917D01*
G01Y1440767D02*
X1440094Y1440779D01*
G01X1438785Y1440767D02*
X1436420Y1440741D01*
G01X1437751Y1440753D02*
X1439047Y1440767D01*
G01Y1437617D02*
X1440094Y1437629D01*
G01X1438785Y1437617D02*
X1436420Y1437591D01*
G01X1437751Y1437603D02*
X1439047Y1437617D01*
G01Y1434468D02*
X1440094Y1434479D01*
G01X1438785Y1434468D02*
X1436420Y1434442D01*
G01X1437751Y1434453D02*
X1439047Y1434468D01*
G01Y1433560D02*
X1442543Y1433522D01*
G01X1437751Y1433574D02*
X1441007Y1433538D01*
G01X1438785Y1433560D02*
X1436420Y1433586D01*
G01X1441235Y1433538D02*
X1442772Y1433522D01*
G01X1441235Y1434489D02*
Y1433538D01*
G01Y1437639D02*
Y1436688D01*
G01Y1443938D02*
Y1442987D01*
G01Y1440789D02*
Y1439837D01*
G01Y1447088D02*
Y1446136D01*
G01Y1453387D02*
Y1452436D01*
G01Y1450237D02*
Y1449286D01*
G01Y1456537D02*
Y1455585D01*
G01Y1462836D02*
Y1461884D01*
G01Y1459686D02*
Y1458735D01*
G01Y1465985D02*
Y1465034D01*
G01Y1472285D02*
Y1471333D01*
G01Y1469135D02*
Y1468184D01*
G01Y1475434D02*
Y1474483D01*
G01Y1481733D02*
Y1480782D01*
G01Y1478584D02*
Y1477633D01*
G01Y1484883D02*
Y1483932D01*
G01Y1491182D02*
Y1490231D01*
G01Y1488033D02*
Y1487081D01*
G01Y1494332D02*
Y1493381D01*
G01Y1500631D02*
Y1499680D01*
G01Y1497481D02*
Y1496530D01*
G01X1441007Y1434489D02*
Y1433538D01*
G01Y1437639D02*
Y1436688D01*
G01Y1443938D02*
Y1442987D01*
G01Y1440789D02*
Y1439837D01*
G01Y1447088D02*
Y1446136D01*
G01Y1453387D02*
Y1452436D01*
G01Y1450237D02*
Y1449286D01*
G01Y1456537D02*
Y1455585D01*
G01Y1462836D02*
Y1461884D01*
G01Y1459686D02*
Y1458735D01*
G01Y1465985D02*
Y1465034D01*
G01Y1472285D02*
Y1471333D01*
G01Y1469135D02*
Y1468184D01*
G01Y1475434D02*
Y1474483D01*
G01Y1481733D02*
Y1480782D01*
G01Y1478584D02*
Y1477633D01*
G01Y1484883D02*
Y1483932D01*
G01Y1491182D02*
Y1490231D01*
G01Y1488033D02*
Y1487081D01*
G01Y1494332D02*
Y1493381D01*
G01Y1500631D02*
Y1499680D01*
G01Y1497481D02*
Y1496530D01*
G01X1439047Y1434468D02*
Y1433560D01*
G01Y1437617D02*
Y1436709D01*
G01Y1443917D02*
Y1443008D01*
G01Y1440767D02*
Y1439859D01*
G01Y1447066D02*
Y1446158D01*
G01Y1453365D02*
Y1452457D01*
G01Y1450216D02*
Y1449308D01*
G01Y1456515D02*
Y1455607D01*
G01Y1462814D02*
Y1461906D01*
G01Y1459665D02*
Y1458756D01*
G01Y1465964D02*
Y1465056D01*
G01Y1472263D02*
Y1471355D01*
G01Y1469114D02*
Y1468205D01*
G01Y1475413D02*
Y1474504D01*
G01Y1481712D02*
Y1480804D01*
G01Y1478562D02*
Y1477654D01*
G01Y1484862D02*
Y1483953D01*
G01Y1491161D02*
Y1490252D01*
G01Y1488011D02*
Y1487103D01*
G01Y1494310D02*
Y1493402D01*
G01Y1500610D02*
Y1499701D01*
G01Y1497460D02*
Y1496552D01*
G01X1438785Y1434468D02*
Y1433560D01*
G01Y1437617D02*
Y1436709D01*
G01Y1443917D02*
Y1443008D01*
G01Y1440767D02*
Y1439859D01*
G01Y1447066D02*
Y1446158D01*
G01Y1453365D02*
Y1452457D01*
G01Y1450216D02*
Y1449308D01*
G01Y1456515D02*
Y1455607D01*
G01Y1462814D02*
Y1461906D01*
G01Y1459665D02*
Y1458756D01*
G01Y1465964D02*
Y1465056D01*
G01Y1472263D02*
Y1471355D01*
G01Y1469114D02*
Y1468205D01*
G01Y1475413D02*
Y1474504D01*
G01Y1481712D02*
Y1480804D01*
G01Y1478562D02*
Y1477654D01*
G01Y1484862D02*
Y1483953D01*
G01Y1491161D02*
Y1490253D01*
G01Y1488011D02*
Y1487103D01*
G01Y1494310D02*
Y1493402D01*
G01Y1500610D02*
Y1499701D01*
G01Y1497460D02*
Y1496552D01*
G01X1437751Y1434448D02*
Y1433580D01*
G01Y1437597D02*
Y1436729D01*
G01Y1443896D02*
Y1443029D01*
G01Y1440747D02*
Y1439879D01*
G01Y1447046D02*
Y1446178D01*
G01Y1453345D02*
Y1452477D01*
G01Y1450196D02*
Y1449328D01*
G01Y1456495D02*
Y1455627D01*
G01Y1462794D02*
Y1461926D01*
G01Y1459644D02*
Y1458777D01*
G01Y1465944D02*
Y1465076D01*
G01Y1472243D02*
Y1471375D01*
G01Y1469093D02*
Y1468225D01*
G01Y1475392D02*
Y1474525D01*
G01Y1481692D02*
Y1480824D01*
G01Y1478542D02*
Y1477674D01*
G01Y1484841D02*
Y1483973D01*
G01Y1491141D02*
Y1490273D01*
G01Y1487991D02*
Y1487123D01*
G01Y1494290D02*
Y1493422D01*
G01Y1500589D02*
Y1499721D01*
G01Y1497440D02*
Y1496572D01*
G01X1436420Y1434442D02*
Y1433586D01*
G01Y1437591D02*
Y1436735D01*
G01Y1443891D02*
Y1443034D01*
G01Y1440741D02*
Y1439885D01*
G01Y1447040D02*
Y1446184D01*
G01Y1453339D02*
Y1452483D01*
G01Y1450190D02*
Y1449334D01*
G01Y1456489D02*
Y1455633D01*
G01Y1462788D02*
Y1461932D01*
G01Y1459639D02*
Y1458783D01*
G01Y1465938D02*
Y1465082D01*
G01Y1472237D02*
Y1471381D01*
G01Y1469087D02*
Y1468231D01*
G01Y1475387D02*
Y1474531D01*
G01Y1481686D02*
Y1480830D01*
G01Y1478536D02*
Y1477680D01*
G01Y1484835D02*
Y1483979D01*
G01Y1491135D02*
Y1490279D01*
G01Y1487985D02*
Y1487129D01*
G01Y1494284D02*
Y1493428D01*
G01Y1500583D02*
Y1499727D01*
G01Y1497434D02*
Y1496578D01*
G01X1457732Y1432045D02*
X1457220D01*
G01X1444212Y1431651D02*
X1443073D01*
G01X1469631Y1431455D02*
X1457535D01*
G01X1442772Y1431356D02*
X1442543D01*
G01X1470921Y1431199D02*
X1469507D01*
G01X1470921Y1430529D02*
X1469507D01*
G01X1442772Y1430372D02*
X1442543D01*
G01X1469631Y1430274D02*
X1457535D01*
G01X1444212Y1430077D02*
X1443073D01*
G01X1442772Y1430372D02*
X1443243Y1430077D01*
G01X1442543Y1430372D02*
X1442684Y1430284D01*
G01D02*
X1443073Y1430077D01*
G01X1469636Y1431469D02*
X1469855Y1431199D01*
G01X1469278Y1431455D02*
X1469507Y1431199D01*
G01X1443073Y1431651D02*
X1442684Y1431444D01*
G01X1443243Y1431651D02*
X1442772Y1431356D01*
G01X1442684Y1431444D02*
X1442543Y1431356D01*
G01X1469507Y1430529D02*
X1469278Y1430274D01*
G01X1469855Y1430529D02*
X1469636Y1430259D01*
G01X1470921Y1431199D02*
Y1430529D01*
G01X1470574Y1431199D02*
Y1430529D01*
G01X1469631Y1431455D02*
Y1430274D01*
G01X1469278Y1431455D02*
Y1430274D01*
G01X1467296Y1431455D02*
Y1430274D01*
G01X1467186Y1431455D02*
Y1430274D01*
G01X1458405Y1431455D02*
Y1430274D01*
G01X1458295Y1431455D02*
Y1430274D01*
G01X1457929Y1431455D02*
Y1430274D01*
G01X1457732Y1432045D02*
Y1431455D01*
G01X1457535Y1432045D02*
Y1431455D01*
G01X1444212Y1431651D02*
Y1430077D01*
G01X1442684Y1431444D02*
Y1430284D01*
G01X1444212Y1502518D02*
X1443073D01*
G01X1457732Y1502124D02*
X1457220D01*
G01X1457732Y1501337D02*
X1457220D01*
G01X1444212Y1500943D02*
X1443073D01*
G01X1469631Y1500746D02*
X1457535D01*
G01X1442772Y1500648D02*
X1442543D01*
G01X1470921Y1500490D02*
X1469507D01*
G01X1470921Y1499821D02*
X1469507D01*
G01X1442772Y1499663D02*
X1442543D01*
G01X1469631Y1499565D02*
X1457535D01*
G01X1444212Y1499368D02*
X1443073D01*
G01X1457732Y1498974D02*
X1457220D01*
G01X1457732Y1498187D02*
X1457220D01*
G01X1444212Y1497793D02*
X1443073D01*
G01X1469631Y1497596D02*
X1457535D01*
G01X1442772Y1497498D02*
X1442543D01*
G01X1470921Y1497340D02*
X1469507D01*
G01X1470921Y1496671D02*
X1469507D01*
G01X1442772Y1496514D02*
X1442543D01*
G01X1469631Y1496415D02*
X1457535D01*
G01X1444212Y1496218D02*
X1443073D01*
G01X1457732Y1495825D02*
X1457220D01*
G01X1457732Y1495037D02*
X1457220D01*
G01X1444212Y1494644D02*
X1443073D01*
G01X1469631Y1494447D02*
X1457535D01*
G01X1442772Y1494348D02*
X1442543D01*
G01X1470921Y1494191D02*
X1469507D01*
G01X1470921Y1493522D02*
X1469507D01*
G01X1442772Y1493364D02*
X1442543D01*
G01X1469631Y1493266D02*
X1457535D01*
G01X1444212Y1493069D02*
X1443073D01*
G01X1457732Y1492675D02*
X1457220D01*
G01X1457732Y1491888D02*
X1457220D01*
G01X1444212Y1491494D02*
X1443073D01*
G01X1469631Y1491297D02*
X1457535D01*
G01X1442772Y1491199D02*
X1442543D01*
G01X1470921Y1491041D02*
X1469507D01*
G01X1470921Y1490372D02*
X1469507D01*
G01X1442772Y1490214D02*
X1442543D01*
G01X1469631Y1490116D02*
X1457535D01*
G01X1444212Y1489919D02*
X1443073D01*
G01X1457732Y1489525D02*
X1457220D01*
G01X1457732Y1488738D02*
X1457220D01*
G01X1444212Y1488344D02*
X1443073D01*
G01X1469631Y1488148D02*
X1457535D01*
G01X1442772Y1488049D02*
X1442543D01*
G01X1470921Y1487892D02*
X1469507D01*
G01X1470921Y1487222D02*
X1469507D01*
G01X1442772Y1487065D02*
X1442543D01*
G01X1469631Y1486966D02*
X1457535D01*
G01X1444212Y1486770D02*
X1443073D01*
G01X1457732Y1486376D02*
X1457220D01*
G01X1457732Y1485588D02*
X1457220D01*
G01X1444212Y1485195D02*
X1443073D01*
G01X1469631Y1484998D02*
X1457535D01*
G01X1442772Y1484900D02*
X1442543D01*
G01X1470921Y1484742D02*
X1469507D01*
G01X1470921Y1484073D02*
X1469507D01*
G01X1442772Y1483915D02*
X1442543D01*
G01X1469631Y1483817D02*
X1457535D01*
G01X1444212Y1483620D02*
X1443073D01*
G01X1457732Y1483226D02*
X1457220D01*
G01X1457732Y1482439D02*
X1457220D01*
G01X1444212Y1482045D02*
X1443073D01*
G01X1469631Y1481848D02*
X1457535D01*
G01X1442772Y1481750D02*
X1442543D01*
G01X1470921Y1481592D02*
X1469507D01*
G01X1470921Y1480923D02*
X1469507D01*
G01X1442772Y1480766D02*
X1442543D01*
G01X1469631Y1480667D02*
X1457535D01*
G01X1444212Y1480470D02*
X1443073D01*
G01X1457732Y1480077D02*
X1457220D01*
G01X1457732Y1479289D02*
X1457220D01*
G01X1444212Y1478896D02*
X1443073D01*
G01X1469631Y1478699D02*
X1457535D01*
G01X1442772Y1478600D02*
X1442543D01*
G01X1470921Y1478443D02*
X1469507D01*
G01X1470921Y1477774D02*
X1469507D01*
G01X1442772Y1477616D02*
X1442543D01*
G01X1469631Y1477518D02*
X1457535D01*
G01X1444212Y1477321D02*
X1443073D01*
G01X1457732Y1476927D02*
X1457220D01*
G01X1457732Y1476140D02*
X1457220D01*
G01X1444212Y1475746D02*
X1443073D01*
G01X1469631Y1475549D02*
X1457535D01*
G01X1442772Y1475451D02*
X1442543D01*
G01X1470921Y1475293D02*
X1469507D01*
G01X1470921Y1474624D02*
X1469507D01*
G01X1442772Y1474466D02*
X1442543D01*
G01X1469631Y1474368D02*
X1457535D01*
G01X1444212Y1474171D02*
X1443073D01*
G01X1457732Y1473777D02*
X1457220D01*
G01X1457732Y1472990D02*
X1457220D01*
G01X1444212Y1472596D02*
X1443073D01*
G01X1469631Y1472400D02*
X1457535D01*
G01X1442772Y1472301D02*
X1442543D01*
G01X1470921Y1472144D02*
X1469507D01*
G01X1470921Y1471474D02*
X1469507D01*
G01X1442772Y1471317D02*
X1442543D01*
G01X1469631Y1471218D02*
X1457535D01*
G01X1444212Y1471022D02*
X1443073D01*
G01X1457732Y1470628D02*
X1457220D01*
G01X1457732Y1469840D02*
X1457220D01*
G01X1444212Y1469447D02*
X1443073D01*
G01X1469631Y1469250D02*
X1457535D01*
G01X1442772Y1469151D02*
X1442543D01*
G01X1470921Y1468994D02*
X1469507D01*
G01X1470921Y1468325D02*
X1469507D01*
G01X1442772Y1468167D02*
X1442543D01*
G01X1469631Y1468069D02*
X1457535D01*
G01X1444212Y1467872D02*
X1443073D01*
G01X1457732Y1467478D02*
X1457220D01*
G01X1457732Y1466691D02*
X1457220D01*
G01X1444212Y1466297D02*
X1443073D01*
G01X1469631Y1466100D02*
X1457535D01*
G01X1442772Y1466002D02*
X1442543D01*
G01X1470921Y1465844D02*
X1469507D01*
G01X1470921Y1465175D02*
X1469507D01*
G01X1442772Y1465018D02*
X1442543D01*
G01X1469631Y1464919D02*
X1457535D01*
G01X1444212Y1464722D02*
X1443073D01*
G01X1457732Y1464329D02*
X1457220D01*
G01X1457732Y1463541D02*
X1457220D01*
G01X1444212Y1463148D02*
X1443073D01*
G01X1469631Y1462951D02*
X1457535D01*
G01X1442772Y1462852D02*
X1442543D01*
G01X1470921Y1462695D02*
X1469507D01*
G01X1470921Y1462025D02*
X1469507D01*
G01X1442772Y1461868D02*
X1442543D01*
G01X1469631Y1461770D02*
X1457535D01*
G01X1444212Y1461573D02*
X1443073D01*
G01X1457732Y1461179D02*
X1457220D01*
G01X1457732Y1460392D02*
X1457220D01*
G01X1444212Y1459998D02*
X1443073D01*
G01X1469631Y1459801D02*
X1457535D01*
G01X1442772Y1459703D02*
X1442543D01*
G01X1470921Y1459545D02*
X1469507D01*
G01X1470921Y1458876D02*
X1469507D01*
G01X1442772Y1458718D02*
X1442543D01*
G01X1469631Y1458620D02*
X1457535D01*
G01X1444212Y1458423D02*
X1443073D01*
G01X1457732Y1458029D02*
X1457220D01*
G01X1457732Y1457242D02*
X1457220D01*
G01X1444212Y1456848D02*
X1443073D01*
G01X1469631Y1456651D02*
X1457535D01*
G01X1442772Y1456553D02*
X1442543D01*
G01X1470921Y1456396D02*
X1469507D01*
G01X1470921Y1455726D02*
X1469507D01*
G01X1442772Y1455569D02*
X1442543D01*
G01X1469631Y1455470D02*
X1457535D01*
G01X1444212Y1455274D02*
X1443073D01*
G01X1457732Y1454880D02*
X1457220D01*
G01X1457732Y1454092D02*
X1457220D01*
G01X1444212Y1453699D02*
X1443073D01*
G01X1469631Y1453502D02*
X1457535D01*
G01X1442772Y1453403D02*
X1442543D01*
G01X1470921Y1453246D02*
X1469507D01*
G01X1470921Y1452577D02*
X1469507D01*
G01X1442772Y1452419D02*
X1442543D01*
G01X1469631Y1452321D02*
X1457535D01*
G01X1444212Y1452124D02*
X1443073D01*
G01X1457732Y1451730D02*
X1457220D01*
G01X1457732Y1450943D02*
X1457220D01*
G01X1444212Y1450549D02*
X1443073D01*
G01X1469631Y1450352D02*
X1457535D01*
G01X1442772Y1450254D02*
X1442543D01*
G01X1470921Y1450096D02*
X1469507D01*
G01X1470921Y1449427D02*
X1469507D01*
G01X1442772Y1449270D02*
X1442543D01*
G01X1469631Y1449171D02*
X1457535D01*
G01X1444212Y1448974D02*
X1443073D01*
G01X1457732Y1448581D02*
X1457220D01*
G01X1457732Y1447793D02*
X1457220D01*
G01X1444212Y1447400D02*
X1443073D01*
G01X1469631Y1447203D02*
X1457535D01*
G01X1442772Y1447104D02*
X1442543D01*
G01X1470921Y1446947D02*
X1469507D01*
G01X1470921Y1446277D02*
X1469507D01*
G01X1442772Y1446120D02*
X1442543D01*
G01X1469631Y1446022D02*
X1457535D01*
G01X1444212Y1445825D02*
X1443073D01*
G01X1457732Y1445431D02*
X1457220D01*
G01X1457732Y1444644D02*
X1457220D01*
G01X1444212Y1444250D02*
X1443073D01*
G01X1469631Y1444053D02*
X1457535D01*
G01X1442772Y1443955D02*
X1442543D01*
G01X1470921Y1443797D02*
X1469507D01*
G01X1470921Y1443128D02*
X1469507D01*
G01X1442772Y1442970D02*
X1442543D01*
G01X1469631Y1442872D02*
X1457535D01*
G01X1444212Y1442675D02*
X1443073D01*
G01X1457732Y1442281D02*
X1457220D01*
G01X1457732Y1441494D02*
X1457220D01*
G01X1444212Y1441100D02*
X1443073D01*
G01X1469631Y1440903D02*
X1457535D01*
G01X1442772Y1440805D02*
X1442543D01*
G01X1470921Y1440648D02*
X1469507D01*
G01X1470921Y1439978D02*
X1469507D01*
G01X1442772Y1439821D02*
X1442543D01*
G01X1469631Y1439722D02*
X1457535D01*
G01X1444212Y1439525D02*
X1443073D01*
G01X1457732Y1439132D02*
X1457220D01*
G01X1457732Y1438344D02*
X1457220D01*
G01X1444212Y1437951D02*
X1443073D01*
G01X1469631Y1437754D02*
X1457535D01*
G01X1442772Y1437655D02*
X1442543D01*
G01X1470921Y1437498D02*
X1469507D01*
G01X1470921Y1436829D02*
X1469507D01*
G01X1442772Y1436671D02*
X1442543D01*
G01X1469631Y1436573D02*
X1457535D01*
G01X1444212Y1436376D02*
X1443073D01*
G01X1457732Y1435982D02*
X1457220D01*
G01X1457732Y1435195D02*
X1457220D01*
G01X1444212Y1434801D02*
X1443073D01*
G01X1469631Y1434604D02*
X1457535D01*
G01X1442772Y1434506D02*
X1442543D01*
G01X1470921Y1434348D02*
X1469507D01*
G01X1470921Y1433679D02*
X1469507D01*
G01X1442772Y1433522D02*
X1442543D01*
G01X1469631Y1433423D02*
X1457535D01*
G01X1444212Y1433226D02*
X1443073D01*
G01X1457732Y1432833D02*
X1457220D01*
G01X1442684Y1502725D02*
X1443073Y1502518D01*
G01X1442684Y1499575D02*
X1443073Y1499368D01*
G01X1442684Y1496426D02*
X1443073Y1496218D01*
G01X1442684Y1493276D02*
X1443073Y1493069D01*
G01X1442684Y1490127D02*
X1443073Y1489919D01*
G01X1442684Y1486977D02*
X1443073Y1486770D01*
G01X1442684Y1483827D02*
X1443073Y1483620D01*
G01X1442684Y1480678D02*
X1443073Y1480470D01*
G01X1442684Y1477528D02*
X1443073Y1477321D01*
G01X1442684Y1474379D02*
X1443073Y1474171D01*
G01X1442684Y1471229D02*
X1443073Y1471022D01*
G01X1442684Y1468079D02*
X1443073Y1467872D01*
G01X1442772Y1502813D02*
X1443243Y1502518D01*
G01X1442543Y1502813D02*
X1442684Y1502725D01*
G01X1442772Y1499663D02*
X1443243Y1499368D01*
G01X1442543Y1499663D02*
X1442684Y1499575D01*
G01X1442772Y1496514D02*
X1443243Y1496218D01*
G01X1442543Y1496514D02*
X1442684Y1496426D01*
G01X1442772Y1493364D02*
X1443243Y1493069D01*
G01X1442543Y1493364D02*
X1442684Y1493276D01*
G01X1442772Y1490214D02*
X1443243Y1489919D01*
G01X1442543Y1490214D02*
X1442684Y1490127D01*
G01X1442772Y1487065D02*
X1443243Y1486770D01*
G01X1442543Y1487065D02*
X1442684Y1486977D01*
G01X1442772Y1483915D02*
X1443243Y1483620D01*
G01X1442543Y1483915D02*
X1442684Y1483827D01*
G01X1442772Y1480766D02*
X1443243Y1480470D01*
G01X1442543Y1480766D02*
X1442684Y1480678D01*
G01X1442772Y1477616D02*
X1443243Y1477321D01*
G01X1442543Y1477616D02*
X1442684Y1477528D01*
G01X1442772Y1474466D02*
X1443243Y1474171D01*
G01X1442543Y1474466D02*
X1442684Y1474379D01*
G01X1442772Y1471317D02*
X1443243Y1471022D01*
G01X1442543Y1471317D02*
X1442684Y1471229D01*
G01X1442772Y1468167D02*
X1443243Y1467872D01*
G01X1442543Y1468167D02*
X1442684Y1468079D01*
G01X1442772Y1465018D02*
X1443243Y1464722D01*
G01X1442543Y1465018D02*
X1442684Y1464930D01*
G01X1442772Y1461868D02*
X1443243Y1461573D01*
G01X1442543Y1461868D02*
X1442684Y1461780D01*
G01X1442772Y1458718D02*
X1443243Y1458423D01*
G01X1442543Y1458718D02*
X1442684Y1458631D01*
G01X1442772Y1455569D02*
X1443243Y1455274D01*
G01X1442543Y1455569D02*
X1442684Y1455481D01*
G01X1442772Y1452419D02*
X1443243Y1452124D01*
G01X1442543Y1452419D02*
X1442684Y1452331D01*
G01X1442772Y1449270D02*
X1443243Y1448974D01*
G01X1442543Y1449270D02*
X1442684Y1449182D01*
G01X1442772Y1446120D02*
X1443243Y1445825D01*
G01X1442543Y1446120D02*
X1442684Y1446032D01*
G01X1442772Y1442970D02*
X1443243Y1442675D01*
G01X1442543Y1442970D02*
X1442684Y1442883D01*
G01X1442772Y1439821D02*
X1443243Y1439525D01*
G01X1442543Y1439821D02*
X1442684Y1439733D01*
G01X1442772Y1436671D02*
X1443243Y1436376D01*
G01X1442543Y1436671D02*
X1442684Y1436583D01*
G01X1442772Y1433522D02*
X1443243Y1433226D01*
G01X1442543Y1433522D02*
X1442684Y1433434D01*
G01Y1464930D02*
X1443073Y1464722D01*
G01X1442684Y1461780D02*
X1443073Y1461573D01*
G01X1442684Y1458631D02*
X1443073Y1458423D01*
G01X1442684Y1455481D02*
X1443073Y1455274D01*
G01X1442684Y1452331D02*
X1443073Y1452124D01*
G01X1442684Y1449182D02*
X1443073Y1448974D01*
G01X1442684Y1446032D02*
X1443073Y1445825D01*
G01X1442684Y1442883D02*
X1443073Y1442675D01*
G01X1442684Y1439733D02*
X1443073Y1439525D01*
G01X1442684Y1436583D02*
X1443073Y1436376D01*
G01X1442684Y1433434D02*
X1443073Y1433226D01*
G01X1469278Y1500746D02*
X1469507Y1500490D01*
G01X1469278Y1497596D02*
X1469507Y1497340D01*
G01X1469278Y1494447D02*
X1469507Y1494191D01*
G01X1469278Y1491297D02*
X1469507Y1491041D01*
G01X1469636Y1500760D02*
X1469855Y1500490D01*
G01X1469636Y1497610D02*
X1469855Y1497340D01*
G01X1469636Y1494461D02*
X1469855Y1494191D01*
G01X1469636Y1491311D02*
X1469855Y1491041D01*
G01X1469636Y1488162D02*
X1469855Y1487892D01*
G01X1469636Y1485012D02*
X1469855Y1484742D01*
G01X1469636Y1481862D02*
X1469855Y1481592D01*
G01X1469636Y1478713D02*
X1469855Y1478443D01*
G01X1469636Y1475563D02*
X1469855Y1475293D01*
G01X1469636Y1472414D02*
X1469855Y1472144D01*
G01X1469636Y1469264D02*
X1469855Y1468994D01*
G01X1469636Y1466114D02*
X1469855Y1465844D01*
G01X1469636Y1462965D02*
X1469855Y1462695D01*
G01X1469636Y1459815D02*
X1469855Y1459545D01*
G01X1469636Y1456666D02*
X1469855Y1456396D01*
G01X1469636Y1453516D02*
X1469855Y1453246D01*
G01X1469636Y1450366D02*
X1469855Y1450096D01*
G01X1469636Y1447217D02*
X1469855Y1446947D01*
G01X1469636Y1444067D02*
X1469855Y1443797D01*
G01X1469636Y1440918D02*
X1469855Y1440648D01*
G01X1469636Y1437768D02*
X1469855Y1437498D01*
G01X1469636Y1434618D02*
X1469855Y1434348D01*
G01X1469278Y1488148D02*
X1469507Y1487892D01*
G01X1469278Y1484998D02*
X1469507Y1484742D01*
G01X1469278Y1481848D02*
X1469507Y1481592D01*
G01X1469278Y1478699D02*
X1469507Y1478443D01*
G01X1469278Y1475549D02*
X1469507Y1475293D01*
G01X1469278Y1472400D02*
X1469507Y1472144D01*
G01X1469278Y1469250D02*
X1469507Y1468994D01*
G01X1469278Y1466100D02*
X1469507Y1465844D01*
G01X1469278Y1462951D02*
X1469507Y1462695D01*
G01X1469278Y1459801D02*
X1469507Y1459545D01*
G01X1469278Y1456651D02*
X1469507Y1456396D01*
G01X1469278Y1453502D02*
X1469507Y1453246D01*
G01X1469278Y1450352D02*
X1469507Y1450096D01*
G01X1469278Y1447203D02*
X1469507Y1446947D01*
G01X1469278Y1444053D02*
X1469507Y1443797D01*
G01X1469278Y1440903D02*
X1469507Y1440648D01*
G01X1469278Y1437754D02*
X1469507Y1437498D01*
G01X1469278Y1434604D02*
X1469507Y1434348D01*
G01X1443073Y1434801D02*
X1442684Y1434594D01*
G01X1443073Y1437951D02*
X1442684Y1437743D01*
G01X1443073Y1441100D02*
X1442684Y1440893D01*
G01X1443073Y1444250D02*
X1442684Y1444042D01*
G01X1443073Y1447400D02*
X1442684Y1447192D01*
G01X1443073Y1450549D02*
X1442684Y1450342D01*
G01X1443073Y1453699D02*
X1442684Y1453491D01*
G01X1443073Y1456848D02*
X1442684Y1456641D01*
G01X1443073Y1459998D02*
X1442684Y1459790D01*
G01X1443073Y1463148D02*
X1442684Y1462940D01*
G01X1443073Y1466297D02*
X1442684Y1466090D01*
G01X1443073Y1469447D02*
X1442684Y1469239D01*
G01X1443073Y1472596D02*
X1442684Y1472389D01*
G01X1443073Y1475746D02*
X1442684Y1475539D01*
G01X1443073Y1478896D02*
X1442684Y1478688D01*
G01X1443073Y1482045D02*
X1442684Y1481838D01*
G01X1443073Y1485195D02*
X1442684Y1484987D01*
G01X1443073Y1488344D02*
X1442684Y1488137D01*
G01X1443073Y1491494D02*
X1442684Y1491287D01*
G01X1443073Y1494644D02*
X1442684Y1494436D01*
G01X1443243Y1434801D02*
X1442772Y1434506D01*
G01X1442684Y1434594D02*
X1442543Y1434506D01*
G01X1443243Y1437951D02*
X1442772Y1437655D01*
G01X1442684Y1437743D02*
X1442543Y1437655D01*
G01X1443243Y1441100D02*
X1442772Y1440805D01*
G01X1442684Y1440893D02*
X1442543Y1440805D01*
G01X1443243Y1444250D02*
X1442772Y1443955D01*
G01X1442684Y1444042D02*
X1442543Y1443955D01*
G01X1443243Y1447400D02*
X1442772Y1447104D01*
G01X1442684Y1447192D02*
X1442543Y1447104D01*
G01X1443243Y1450549D02*
X1442772Y1450254D01*
G01X1442684Y1450342D02*
X1442543Y1450254D01*
G01X1443243Y1453699D02*
X1442772Y1453403D01*
G01X1442684Y1453491D02*
X1442543Y1453403D01*
G01X1443243Y1456848D02*
X1442772Y1456553D01*
G01X1442684Y1456641D02*
X1442543Y1456553D01*
G01X1443243Y1459998D02*
X1442772Y1459703D01*
G01X1442684Y1459790D02*
X1442543Y1459703D01*
G01X1443243Y1463148D02*
X1442772Y1462852D01*
G01X1442684Y1462940D02*
X1442543Y1462852D01*
G01X1443243Y1466297D02*
X1442772Y1466002D01*
G01X1442684Y1466090D02*
X1442543Y1466002D01*
G01X1443073Y1497793D02*
X1442684Y1497586D01*
G01X1443073Y1500943D02*
X1442684Y1500735D01*
G01X1443243Y1469447D02*
X1442772Y1469151D01*
G01X1442684Y1469239D02*
X1442543Y1469151D01*
G01X1443243Y1472596D02*
X1442772Y1472301D01*
G01X1442684Y1472389D02*
X1442543Y1472301D01*
G01X1443243Y1475746D02*
X1442772Y1475451D01*
G01X1442684Y1475539D02*
X1442543Y1475451D01*
G01X1443243Y1478896D02*
X1442772Y1478600D01*
G01X1442684Y1478688D02*
X1442543Y1478600D01*
G01X1443243Y1482045D02*
X1442772Y1481750D01*
G01X1442684Y1481838D02*
X1442543Y1481750D01*
G01X1443243Y1485195D02*
X1442772Y1484900D01*
G01X1442684Y1484987D02*
X1442543Y1484900D01*
G01X1443243Y1488344D02*
X1442772Y1488049D01*
G01X1442684Y1488137D02*
X1442543Y1488049D01*
G01X1443243Y1491494D02*
X1442772Y1491199D01*
G01X1442684Y1491287D02*
X1442543Y1491199D01*
G01X1443243Y1494644D02*
X1442772Y1494348D01*
G01X1442684Y1494436D02*
X1442543Y1494348D01*
G01X1443243Y1497793D02*
X1442772Y1497498D01*
G01X1442684Y1497586D02*
X1442543Y1497498D01*
G01X1443243Y1500943D02*
X1442772Y1500648D01*
G01X1442684Y1500735D02*
X1442543Y1500648D01*
G01X1469507Y1433679D02*
X1469278Y1433423D01*
G01X1469507Y1436829D02*
X1469278Y1436573D01*
G01X1469507Y1439978D02*
X1469278Y1439722D01*
G01X1469507Y1443128D02*
X1469278Y1442872D01*
G01X1469507Y1446277D02*
X1469278Y1446022D01*
G01X1469507Y1449427D02*
X1469278Y1449171D01*
G01X1469507Y1452577D02*
X1469278Y1452321D01*
G01X1469507Y1455726D02*
X1469278Y1455470D01*
G01X1469507Y1458876D02*
X1469278Y1458620D01*
G01X1469507Y1462025D02*
X1469278Y1461770D01*
G01X1469507Y1465175D02*
X1469278Y1464919D01*
G01X1469507Y1468325D02*
X1469278Y1468069D01*
G01X1469507Y1471474D02*
X1469278Y1471218D01*
G01X1469507Y1474624D02*
X1469278Y1474368D01*
G01X1469507Y1477774D02*
X1469278Y1477518D01*
G01X1469507Y1480923D02*
X1469278Y1480667D01*
G01X1469507Y1484073D02*
X1469278Y1483817D01*
G01X1469507Y1487222D02*
X1469278Y1486966D01*
G01X1469507Y1490372D02*
X1469278Y1490116D01*
G01X1469507Y1493522D02*
X1469278Y1493266D01*
G01X1469507Y1496671D02*
X1469278Y1496415D01*
G01X1469855Y1433679D02*
X1469636Y1433409D01*
G01X1469855Y1436829D02*
X1469636Y1436559D01*
G01X1469855Y1439978D02*
X1469636Y1439708D01*
G01X1469855Y1443128D02*
X1469636Y1442858D01*
G01X1469855Y1446277D02*
X1469636Y1446007D01*
G01X1469855Y1449427D02*
X1469636Y1449157D01*
G01X1469855Y1452577D02*
X1469636Y1452307D01*
G01X1469855Y1455726D02*
X1469636Y1455456D01*
G01X1469855Y1458876D02*
X1469636Y1458606D01*
G01X1469855Y1462025D02*
X1469636Y1461755D01*
G01X1469855Y1465175D02*
X1469636Y1464905D01*
G01X1469855Y1468325D02*
X1469636Y1468055D01*
G01X1469855Y1471474D02*
X1469636Y1471204D01*
G01X1469855Y1474624D02*
X1469636Y1474354D01*
G01X1469855Y1477774D02*
X1469636Y1477503D01*
G01X1469855Y1480923D02*
X1469636Y1480653D01*
G01X1469855Y1484073D02*
X1469636Y1483803D01*
G01X1469855Y1487222D02*
X1469636Y1486952D01*
G01X1470921Y1434348D02*
Y1433679D01*
G01Y1437498D02*
Y1436829D01*
G01Y1443797D02*
Y1443128D01*
G01Y1440648D02*
Y1439978D01*
G01Y1446947D02*
Y1446277D01*
G01Y1453246D02*
Y1452577D01*
G01Y1450096D02*
Y1449427D01*
G01Y1456396D02*
Y1455726D01*
G01Y1462695D02*
Y1462025D01*
G01Y1459545D02*
Y1458876D01*
G01Y1465844D02*
Y1465175D01*
G01Y1472144D02*
Y1471474D01*
G01Y1468994D02*
Y1468325D01*
G01Y1475293D02*
Y1474624D01*
G01Y1481592D02*
Y1480923D01*
G01Y1478443D02*
Y1477774D01*
G01Y1484742D02*
Y1484073D01*
G01Y1491041D02*
Y1490372D01*
G01Y1487892D02*
Y1487222D01*
G01Y1494191D02*
Y1493522D01*
G01Y1500490D02*
Y1499821D01*
G01Y1497340D02*
Y1496671D01*
G01X1470574Y1434348D02*
Y1433679D01*
G01Y1437498D02*
Y1436829D01*
G01Y1443797D02*
Y1443128D01*
G01Y1440648D02*
Y1439978D01*
G01Y1446947D02*
Y1446277D01*
G01Y1453246D02*
Y1452577D01*
G01Y1450096D02*
Y1449427D01*
G01Y1456396D02*
Y1455726D01*
G01Y1462695D02*
Y1462025D01*
G01Y1459545D02*
Y1458876D01*
G01Y1465844D02*
Y1465175D01*
G01Y1472144D02*
Y1471474D01*
G01Y1468994D02*
Y1468325D01*
G01Y1475293D02*
Y1474624D01*
G01Y1481592D02*
Y1480923D01*
G01Y1478443D02*
Y1477774D01*
G01Y1484742D02*
Y1484073D01*
G01Y1491041D02*
Y1490372D01*
G01Y1487892D02*
Y1487222D01*
G01Y1494191D02*
Y1493522D01*
G01Y1500490D02*
Y1499821D01*
G01Y1497340D02*
Y1496671D01*
G01X1469631Y1434604D02*
Y1433423D01*
G01Y1437754D02*
Y1436573D01*
G01Y1444053D02*
Y1442872D01*
G01Y1440903D02*
Y1439722D01*
G01Y1447203D02*
Y1446022D01*
G01Y1453502D02*
Y1452321D01*
G01Y1450352D02*
Y1449171D01*
G01Y1456651D02*
Y1455470D01*
G01Y1462951D02*
Y1461770D01*
G01Y1459801D02*
Y1458620D01*
G01Y1466100D02*
Y1464919D01*
G01Y1472400D02*
Y1471218D01*
G01Y1469250D02*
Y1468069D01*
G01Y1475549D02*
Y1474368D01*
G01Y1481848D02*
Y1480667D01*
G01Y1478699D02*
Y1477518D01*
G01Y1484998D02*
Y1483817D01*
G01Y1491297D02*
Y1490116D01*
G01Y1488148D02*
Y1486966D01*
G01Y1494447D02*
Y1493266D01*
G01Y1500746D02*
Y1499565D01*
G01Y1497596D02*
Y1496415D01*
G01X1469278Y1434604D02*
Y1433423D01*
G01Y1437754D02*
Y1436573D01*
G01Y1444053D02*
Y1442872D01*
G01Y1440903D02*
Y1439722D01*
G01Y1447203D02*
Y1446022D01*
G01Y1453502D02*
Y1452321D01*
G01Y1450352D02*
Y1449171D01*
G01Y1456651D02*
Y1455470D01*
G01Y1462951D02*
Y1461770D01*
G01Y1459801D02*
Y1458620D01*
G01Y1466100D02*
Y1464919D01*
G01Y1472400D02*
Y1471218D01*
G01Y1469250D02*
Y1468069D01*
G01Y1475549D02*
Y1474368D01*
G01Y1481848D02*
Y1480667D01*
G01Y1478699D02*
Y1477518D01*
G01Y1484998D02*
Y1483817D01*
G01Y1491297D02*
Y1490116D01*
G01Y1488148D02*
Y1486966D01*
G01Y1494447D02*
Y1493266D01*
G01Y1500746D02*
Y1499565D01*
G01Y1497596D02*
Y1496415D01*
G01X1467296Y1434604D02*
Y1433423D01*
G01Y1437754D02*
Y1436573D01*
G01Y1444053D02*
Y1442872D01*
G01Y1440903D02*
Y1439722D01*
G01Y1447203D02*
Y1446022D01*
G01Y1453502D02*
Y1452321D01*
G01Y1450352D02*
Y1449171D01*
G01Y1456651D02*
Y1455470D01*
G01Y1462951D02*
Y1461770D01*
G01Y1459801D02*
Y1458620D01*
G01Y1466100D02*
Y1464919D01*
G01Y1472400D02*
Y1471218D01*
G01Y1469250D02*
Y1468069D01*
G01Y1475549D02*
Y1474368D01*
G01Y1481848D02*
Y1480667D01*
G01Y1478699D02*
Y1477518D01*
G01Y1484998D02*
Y1483817D01*
G01Y1491297D02*
Y1490116D01*
G01Y1488148D02*
Y1486966D01*
G01Y1494447D02*
Y1493266D01*
G01Y1500746D02*
Y1499565D01*
G01Y1497596D02*
Y1496415D01*
G01X1467186Y1434604D02*
Y1433423D01*
G01Y1437754D02*
Y1436573D01*
G01Y1444053D02*
Y1442872D01*
G01Y1440903D02*
Y1439722D01*
G01Y1447203D02*
Y1446022D01*
G01Y1453502D02*
Y1452321D01*
G01Y1450352D02*
Y1449171D01*
G01Y1456651D02*
Y1455470D01*
G01Y1462951D02*
Y1461770D01*
G01Y1459801D02*
Y1458620D01*
G01Y1466100D02*
Y1464919D01*
G01Y1472400D02*
Y1471218D01*
G01Y1469250D02*
Y1468069D01*
G01Y1475549D02*
Y1474368D01*
G01Y1481848D02*
Y1480667D01*
G01Y1478699D02*
Y1477518D01*
G01Y1484998D02*
Y1483817D01*
G01Y1491297D02*
Y1490116D01*
G01Y1488148D02*
Y1486966D01*
G01Y1494447D02*
Y1493266D01*
G01Y1500746D02*
Y1499565D01*
G01Y1497596D02*
Y1496415D01*
G01X1458405Y1434604D02*
Y1433423D01*
G01Y1437754D02*
Y1436573D01*
G01Y1444053D02*
Y1442872D01*
G01Y1440903D02*
Y1439722D01*
G01Y1447203D02*
Y1446022D01*
G01Y1453502D02*
Y1452321D01*
G01Y1450352D02*
Y1449171D01*
G01Y1456651D02*
Y1455470D01*
G01Y1462951D02*
Y1461770D01*
G01Y1459801D02*
Y1458620D01*
G01Y1466100D02*
Y1464919D01*
G01Y1472400D02*
Y1471218D01*
G01Y1469250D02*
Y1468069D01*
G01Y1475549D02*
Y1474368D01*
G01Y1481848D02*
Y1480667D01*
G01Y1478699D02*
Y1477518D01*
G01Y1484998D02*
Y1483817D01*
G01Y1491297D02*
Y1490116D01*
G01Y1488148D02*
Y1486966D01*
G01Y1494447D02*
Y1493266D01*
G01Y1500746D02*
Y1499565D01*
G01Y1497596D02*
Y1496415D01*
G01X1458295Y1434604D02*
Y1433423D01*
G01Y1437754D02*
Y1436573D01*
G01Y1444053D02*
Y1442872D01*
G01Y1440903D02*
Y1439722D01*
G01Y1447203D02*
Y1446022D01*
G01Y1453502D02*
Y1452321D01*
G01Y1450352D02*
Y1449171D01*
G01Y1456651D02*
Y1455470D01*
G01Y1462951D02*
Y1461770D01*
G01Y1459801D02*
Y1458620D01*
G01Y1466100D02*
Y1464919D01*
G01Y1472400D02*
Y1471218D01*
G01Y1469250D02*
Y1468069D01*
G01Y1475549D02*
Y1474368D01*
G01Y1481848D02*
Y1480667D01*
G01Y1478699D02*
Y1477518D01*
G01Y1484998D02*
Y1483817D01*
G01Y1491297D02*
Y1490116D01*
G01Y1488148D02*
Y1486966D01*
G01Y1494447D02*
Y1493266D01*
G01Y1500746D02*
Y1499565D01*
G01Y1497596D02*
Y1496415D01*
G01X1457929Y1434604D02*
Y1433423D01*
G01Y1437754D02*
Y1436573D01*
G01Y1444053D02*
Y1442872D01*
G01Y1440903D02*
Y1439722D01*
G01Y1447203D02*
Y1446022D01*
G01Y1453502D02*
Y1452321D01*
G01Y1450352D02*
Y1449171D01*
G01Y1456651D02*
Y1455470D01*
G01Y1462951D02*
Y1461770D01*
G01Y1459801D02*
Y1458620D01*
G01Y1466100D02*
Y1464919D01*
G01Y1472400D02*
Y1471218D01*
G01Y1469250D02*
Y1468069D01*
G01Y1475549D02*
Y1474368D01*
G01Y1481848D02*
Y1480667D01*
G01Y1478699D02*
Y1477518D01*
G01Y1484998D02*
Y1483817D01*
G01Y1491297D02*
Y1490116D01*
G01Y1488148D02*
Y1486966D01*
G01Y1494447D02*
Y1493266D01*
G01Y1500746D02*
Y1499565D01*
G01Y1497596D02*
Y1496415D01*
G01X1457732Y1433423D02*
Y1432833D01*
G01Y1435195D02*
Y1434604D01*
G01Y1439722D02*
Y1439132D01*
G01Y1436573D02*
Y1435982D01*
G01Y1438344D02*
Y1437754D01*
G01Y1442872D02*
Y1442281D01*
G01Y1444644D02*
Y1444053D01*
G01Y1441494D02*
Y1440903D01*
G01Y1449171D02*
Y1448581D01*
G01Y1446022D02*
Y1445431D01*
G01Y1447793D02*
Y1447203D01*
G01Y1452321D02*
Y1451730D01*
G01Y1454092D02*
Y1453502D01*
G01Y1450943D02*
Y1450352D01*
G01Y1458620D02*
Y1458029D01*
G01Y1455470D02*
Y1454880D01*
G01Y1457242D02*
Y1456651D01*
G01Y1461770D02*
Y1461179D01*
G01Y1463541D02*
Y1462951D01*
G01Y1460392D02*
Y1459801D01*
G01Y1468069D02*
Y1467478D01*
G01Y1464919D02*
Y1464329D01*
G01Y1466691D02*
Y1466100D01*
G01Y1471218D02*
Y1470628D01*
G01Y1472990D02*
Y1472400D01*
G01Y1469840D02*
Y1469250D01*
G01Y1477518D02*
Y1476927D01*
G01Y1474368D02*
Y1473777D01*
G01Y1476140D02*
Y1475549D01*
G01Y1480667D02*
Y1480077D01*
G01Y1482439D02*
Y1481848D01*
G01Y1479289D02*
Y1478699D01*
G01Y1486966D02*
Y1486376D01*
G01Y1483817D02*
Y1483226D01*
G01Y1485588D02*
Y1484998D01*
G01Y1490116D02*
Y1489525D01*
G01Y1491888D02*
Y1491297D01*
G01Y1488738D02*
Y1488148D01*
G01Y1496415D02*
Y1495825D01*
G01Y1493266D02*
Y1492675D01*
G01Y1495037D02*
Y1494447D01*
G01Y1499565D02*
Y1498974D01*
G01Y1501337D02*
Y1500746D01*
G01Y1498187D02*
Y1497596D01*
G01Y1502714D02*
Y1502124D01*
G01X1457535Y1433423D02*
Y1432833D01*
G01Y1435195D02*
Y1434604D01*
G01Y1439722D02*
Y1439132D01*
G01Y1436573D02*
Y1435982D01*
G01Y1438344D02*
Y1437754D01*
G01Y1442872D02*
Y1442281D01*
G01Y1444644D02*
Y1444053D01*
G01Y1441494D02*
Y1440903D01*
G01Y1449171D02*
Y1448581D01*
G01Y1446022D02*
Y1445431D01*
G01Y1447793D02*
Y1447203D01*
G01Y1452321D02*
Y1451730D01*
G01Y1454092D02*
Y1453502D01*
G01Y1450943D02*
Y1450352D01*
G01Y1458620D02*
Y1458029D01*
G01Y1455470D02*
Y1454880D01*
G01Y1457242D02*
Y1456651D01*
G01Y1461770D02*
Y1461179D01*
G01Y1463541D02*
Y1462951D01*
G01Y1460392D02*
Y1459801D01*
G01Y1468069D02*
Y1467478D01*
G01Y1464919D02*
Y1464329D01*
G01Y1466691D02*
Y1466100D01*
G01Y1471218D02*
Y1470628D01*
G01Y1472990D02*
Y1472400D01*
G01Y1469840D02*
Y1469250D01*
G01Y1477518D02*
Y1476927D01*
G01Y1474368D02*
Y1473777D01*
G01Y1476140D02*
Y1475549D01*
G01Y1480667D02*
Y1480077D01*
G01Y1482439D02*
Y1481848D01*
G01Y1479289D02*
Y1478699D01*
G01Y1486966D02*
Y1486376D01*
G01Y1483817D02*
Y1483226D01*
G01Y1485588D02*
Y1484998D01*
G01Y1490116D02*
Y1489525D01*
G01Y1491888D02*
Y1491297D01*
G01Y1488738D02*
Y1488148D01*
G01Y1496415D02*
Y1495825D01*
G01Y1493266D02*
Y1492675D01*
G01Y1495037D02*
Y1494447D01*
G01Y1499565D02*
Y1498974D01*
G01Y1501337D02*
Y1500746D01*
G01Y1498187D02*
Y1497596D01*
G01Y1502714D02*
Y1502124D01*
G01X1444212Y1434801D02*
Y1433226D01*
G01Y1437951D02*
Y1436376D01*
G01Y1444250D02*
Y1442675D01*
G01Y1441100D02*
Y1439525D01*
G01Y1447400D02*
Y1445825D01*
G01Y1453699D02*
Y1452124D01*
G01Y1450549D02*
Y1448974D01*
G01Y1456848D02*
Y1455274D01*
G01Y1463148D02*
Y1461573D01*
G01Y1459998D02*
Y1458423D01*
G01Y1466297D02*
Y1464722D01*
G01Y1472596D02*
Y1471022D01*
G01Y1469447D02*
Y1467872D01*
G01Y1475746D02*
Y1474171D01*
G01Y1482045D02*
Y1480470D01*
G01Y1478896D02*
Y1477321D01*
G01Y1485195D02*
Y1483620D01*
G01Y1491494D02*
Y1489919D01*
G01Y1488344D02*
Y1486770D01*
G01Y1494644D02*
Y1493069D01*
G01Y1500943D02*
Y1499368D01*
G01Y1497793D02*
Y1496218D01*
G01Y1504092D02*
Y1502518D01*
G01X1442684Y1434594D02*
Y1433434D01*
G01Y1437743D02*
Y1436583D01*
G01Y1444042D02*
Y1442883D01*
G01Y1440893D02*
Y1439733D01*
G01Y1447192D02*
Y1446032D01*
G01Y1453491D02*
Y1452331D01*
G01Y1450342D02*
Y1449182D01*
G01Y1456641D02*
Y1455481D01*
G01Y1462940D02*
Y1461780D01*
G01Y1459790D02*
Y1458631D01*
G01Y1466090D02*
Y1464930D01*
G01Y1472389D02*
Y1471229D01*
G01Y1469239D02*
Y1468079D01*
G01Y1475539D02*
Y1474379D01*
G01Y1481838D02*
Y1480678D01*
G01Y1478688D02*
Y1477528D01*
G01Y1484987D02*
Y1483827D01*
G01Y1491287D02*
Y1490127D01*
G01Y1488137D02*
Y1486977D01*
G01Y1494436D02*
Y1493276D01*
G01Y1500735D02*
Y1499575D01*
G01Y1497586D02*
Y1496426D01*
G01X1469507Y1499821D02*
X1469278Y1499565D01*
G01X1469507Y1502970D02*
X1469278Y1502714D01*
G01X1469855Y1490372D02*
X1469636Y1490102D01*
G01X1469855Y1493522D02*
X1469636Y1493252D01*
G01X1469855Y1496671D02*
X1469636Y1496401D01*
G01X1469855Y1499821D02*
X1469636Y1499551D01*
G01X1469855Y1502970D02*
X1469636Y1502700D01*
G01X1440094Y1503771D02*
X1438785Y1503759D01*
G01X1441235Y1503781D02*
X1440094Y1503771D01*
G01X1437751Y1503745D02*
X1436420Y1503733D01*
G01X1442543Y1503797D02*
X1441007Y1503781D01*
G01X1442543Y1503797D02*
X1439047Y1503759D01*
G01X1441235Y1503781D02*
X1442772Y1503797D01*
G01X1439047Y1503759D02*
X1440094Y1503771D01*
G01X1438785Y1503759D02*
X1436420Y1503733D01*
G01X1437751Y1503745D02*
X1439047Y1503759D01*
G01Y1502851D02*
X1442543Y1502813D01*
G01X1437751Y1502865D02*
X1441007Y1502829D01*
G01X1438785Y1502851D02*
X1436420Y1502877D01*
G01X1441235Y1502829D02*
X1442772Y1502813D01*
G01X1441235Y1502829D02*
X1438785Y1502851D01*
G01X1437751Y1502865D02*
X1436420Y1502877D01*
G01X1441235Y1503781D02*
X1441007D01*
G01X1439047Y1503759D02*
X1438785D01*
G01X1439047Y1502851D02*
X1438785D01*
G01X1441235Y1502829D02*
X1441007D01*
G01X1441235Y1503781D02*
Y1502829D01*
G01X1441007Y1503781D02*
Y1502829D01*
G01X1439047Y1503759D02*
Y1502851D01*
G01X1438785Y1503759D02*
Y1502851D01*
G01X1437751Y1503739D02*
Y1502871D01*
G01X1436420Y1503733D02*
Y1502877D01*
G01X1439047Y1575292D02*
X1442543Y1575254D01*
G01X1437751Y1575306D02*
X1441007Y1575270D01*
G01X1439047Y1572142D02*
X1442543Y1572104D01*
G01X1437751Y1572157D02*
X1441007Y1572121D01*
G01X1439047Y1568993D02*
X1442543Y1568955D01*
G01X1437751Y1569007D02*
X1441007Y1568971D01*
G01X1439047Y1565843D02*
X1442543Y1565805D01*
G01X1437751Y1565857D02*
X1441007Y1565821D01*
G01X1439047Y1562693D02*
X1442543Y1562655D01*
G01X1437751Y1562708D02*
X1441007Y1562672D01*
G01X1439047Y1559544D02*
X1442543Y1559506D01*
G01X1437751Y1559558D02*
X1441007Y1559522D01*
G01X1439047Y1556394D02*
X1442543Y1556356D01*
G01X1437751Y1556409D02*
X1441007Y1556373D01*
G01X1439047Y1553245D02*
X1442543Y1553207D01*
G01X1437751Y1553259D02*
X1441007Y1553223D01*
G01X1439047Y1550095D02*
X1442543Y1550057D01*
G01X1437751Y1550109D02*
X1441007Y1550073D01*
G01X1439047Y1546945D02*
X1442543Y1546907D01*
G01X1437751Y1546960D02*
X1441007Y1546924D01*
G01X1439047Y1543796D02*
X1442543Y1543758D01*
G01X1437751Y1543810D02*
X1441007Y1543774D01*
G01X1439047Y1540646D02*
X1442543Y1540608D01*
G01X1437751Y1540660D02*
X1441007Y1540625D01*
G01X1439047Y1537497D02*
X1442543Y1537459D01*
G01X1437751Y1537511D02*
X1441007Y1537475D01*
G01X1439047Y1534347D02*
X1442543Y1534309D01*
G01X1437751Y1534361D02*
X1441007Y1534325D01*
G01X1439047Y1531197D02*
X1442543Y1531159D01*
G01X1437751Y1531212D02*
X1441007Y1531176D01*
G01X1439047Y1528048D02*
X1442543Y1528010D01*
G01X1437751Y1528062D02*
X1441007Y1528026D01*
G01X1439047Y1524898D02*
X1442543Y1524860D01*
G01X1437751Y1524912D02*
X1441007Y1524877D01*
G01X1439047Y1521749D02*
X1442543Y1521711D01*
G01X1437751Y1521763D02*
X1441007Y1521727D01*
G01X1439047Y1518599D02*
X1442543Y1518561D01*
G01X1437751Y1518613D02*
X1441007Y1518577D01*
G01X1438785Y1575292D02*
X1436420Y1575318D01*
G01X1438785Y1572142D02*
X1436420Y1572168D01*
G01X1438785Y1568993D02*
X1436420Y1569019D01*
G01X1438785Y1565843D02*
X1436420Y1565869D01*
G01X1438785Y1562693D02*
X1436420Y1562720D01*
G01X1438785Y1559544D02*
X1436420Y1559570D01*
G01X1438785Y1556394D02*
X1436420Y1556420D01*
G01X1438785Y1553245D02*
X1436420Y1553271D01*
G01X1438785Y1550095D02*
X1436420Y1550121D01*
G01X1438785Y1546945D02*
X1436420Y1546971D01*
G01X1438785Y1543796D02*
X1436420Y1543822D01*
G01X1438785Y1540646D02*
X1436420Y1540672D01*
G01X1438785Y1537497D02*
X1436420Y1537523D01*
G01X1438785Y1534347D02*
X1436420Y1534373D01*
G01X1438785Y1531197D02*
X1436420Y1531223D01*
G01X1438785Y1528048D02*
X1436420Y1528074D01*
G01X1438785Y1524898D02*
X1436420Y1524924D01*
G01X1438785Y1521749D02*
X1436420Y1521775D01*
G01X1438785Y1518599D02*
X1436420Y1518625D01*
G01X1441235Y1575270D02*
X1442772Y1575254D01*
G01X1441235Y1572121D02*
X1442772Y1572104D01*
G01X1441235Y1568971D02*
X1442772Y1568955D01*
G01X1441235Y1565821D02*
X1442772Y1565805D01*
G01X1441235Y1562672D02*
X1442772Y1562655D01*
G01X1441235Y1559522D02*
X1442772Y1559506D01*
G01X1441235Y1556373D02*
X1442772Y1556356D01*
G01X1441235Y1553223D02*
X1442772Y1553207D01*
G01X1441235Y1550073D02*
X1442772Y1550057D01*
G01X1441235Y1546924D02*
X1442772Y1546907D01*
G01X1441235Y1543774D02*
X1442772Y1543758D01*
G01X1441235Y1540625D02*
X1442772Y1540608D01*
G01X1441235Y1537475D02*
X1442772Y1537459D01*
G01X1441235Y1534325D02*
X1442772Y1534309D01*
G01X1441235Y1531176D02*
X1442772Y1531159D01*
G01X1441235Y1528026D02*
X1442772Y1528010D01*
G01X1441235Y1524877D02*
X1442772Y1524860D01*
G01X1441235Y1521727D02*
X1442772Y1521711D01*
G01X1441235Y1518577D02*
X1442772Y1518561D01*
G01X1441235Y1575270D02*
X1438785Y1575292D01*
G01X1437751Y1575306D02*
X1436420Y1575318D01*
G01X1441235Y1572121D02*
X1438785Y1572142D01*
G01X1437751Y1572157D02*
X1436420Y1572168D01*
G01X1441235Y1568971D02*
X1438785Y1568993D01*
G01X1437751Y1569007D02*
X1436420Y1569019D01*
G01X1441235Y1565821D02*
X1438785Y1565843D01*
G01X1437751Y1565857D02*
X1436420Y1565869D01*
G01X1441235Y1562672D02*
X1438785Y1562693D01*
G01X1437751Y1562708D02*
X1436420Y1562720D01*
G01X1441235Y1559522D02*
X1438785Y1559544D01*
G01X1437751Y1559558D02*
X1436420Y1559570D01*
G01X1441235Y1556373D02*
X1438785Y1556394D01*
G01X1437751Y1556409D02*
X1436420Y1556420D01*
G01X1441235Y1553223D02*
X1438785Y1553245D01*
G01X1437751Y1553259D02*
X1436420Y1553271D01*
G01X1441235Y1550073D02*
X1438785Y1550095D01*
G01X1437751Y1550109D02*
X1436420Y1550121D01*
G01X1441235Y1546924D02*
X1438785Y1546945D01*
G01X1437751Y1546960D02*
X1436420Y1546971D01*
G01X1441235Y1543774D02*
X1438785Y1543796D01*
G01X1437751Y1543810D02*
X1436420Y1543822D01*
G01X1441235Y1540625D02*
X1438785Y1540646D01*
G01X1437751Y1540660D02*
X1436420Y1540672D01*
G01X1441235Y1537475D02*
X1438785Y1537497D01*
G01X1437751Y1537511D02*
X1436420Y1537523D01*
G01X1441235Y1534325D02*
X1438785Y1534347D01*
G01X1437751Y1534361D02*
X1436420Y1534373D01*
G01X1441235Y1531176D02*
X1438785Y1531197D01*
G01X1437751Y1531212D02*
X1436420Y1531223D01*
G01X1441235Y1528026D02*
X1438785Y1528048D01*
G01X1437751Y1528062D02*
X1436420Y1528074D01*
G01X1441235Y1524877D02*
X1438785Y1524898D01*
G01X1437751Y1524912D02*
X1436420Y1524924D01*
G01X1441235Y1521727D02*
X1438785Y1521749D01*
G01X1437751Y1521763D02*
X1436420Y1521775D01*
G01X1441235Y1518577D02*
X1438785Y1518599D01*
G01X1437751Y1518613D02*
X1436420Y1518625D01*
G01X1439047Y1575292D02*
X1438785D01*
G01X1441235Y1575270D02*
X1441007D01*
G01X1441235Y1573072D02*
X1441007D01*
G01X1439047Y1573050D02*
X1438785D01*
G01X1439047Y1572142D02*
X1438785D01*
G01X1441235Y1572121D02*
X1441007D01*
G01X1441235Y1569922D02*
X1441007D01*
G01X1439047Y1569901D02*
X1438785D01*
G01X1439047Y1568993D02*
X1438785D01*
G01X1441235Y1568971D02*
X1441007D01*
G01X1441235Y1566773D02*
X1441007D01*
G01X1439047Y1566751D02*
X1438785D01*
G01X1439047Y1565843D02*
X1438785D01*
G01X1441235Y1565821D02*
X1441007D01*
G01X1441235Y1563623D02*
X1441007D01*
G01X1439047Y1563602D02*
X1438785D01*
G01X1439047Y1562693D02*
X1438785D01*
G01X1441235Y1562672D02*
X1441007D01*
G01X1441235Y1560474D02*
X1441007D01*
G01X1439047Y1560452D02*
X1438785D01*
G01X1439047Y1559544D02*
X1438785D01*
G01X1441235Y1559522D02*
X1441007D01*
G01X1441235Y1557324D02*
X1441007D01*
G01X1439047Y1557302D02*
X1438785D01*
G01X1439047Y1556394D02*
X1438785D01*
G01X1441235Y1556373D02*
X1441007D01*
G01X1441235Y1554174D02*
X1441007D01*
G01X1439047Y1554153D02*
X1438785D01*
G01X1439047Y1553245D02*
X1438785D01*
G01X1441235Y1553223D02*
X1441007D01*
G01X1441235Y1551025D02*
X1441007D01*
G01X1439047Y1551003D02*
X1438785D01*
G01X1439047Y1550095D02*
X1438785D01*
G01X1441235Y1550073D02*
X1441007D01*
G01X1441235Y1547875D02*
X1441007D01*
G01X1439047Y1547854D02*
X1438785D01*
G01X1439047Y1546945D02*
X1438785D01*
G01X1441235Y1546924D02*
X1441007D01*
G01X1441235Y1544726D02*
X1441007D01*
G01X1439047Y1544704D02*
X1438785D01*
G01X1439047Y1543796D02*
X1438785D01*
G01X1441235Y1543774D02*
X1441007D01*
G01X1441235Y1541576D02*
X1441007D01*
G01X1439047Y1541554D02*
X1438785D01*
G01X1439047Y1540646D02*
X1438785D01*
G01X1441235Y1540625D02*
X1441007D01*
G01X1441235Y1538426D02*
X1441007D01*
G01X1439047Y1538405D02*
X1438785D01*
G01X1439047Y1537497D02*
X1438785D01*
G01X1441235Y1537475D02*
X1441007D01*
G01X1441235Y1535277D02*
X1441007D01*
G01X1439047Y1535255D02*
X1438785D01*
G01X1439047Y1534347D02*
X1438785D01*
G01X1441235Y1534325D02*
X1441007D01*
G01X1441235Y1532127D02*
X1441007D01*
G01X1439047Y1532106D02*
X1438785D01*
G01X1439047Y1531197D02*
X1438785D01*
G01X1441235Y1531176D02*
X1441007D01*
G01X1441235Y1528978D02*
X1441007D01*
G01X1439047Y1528956D02*
X1438785D01*
G01X1439047Y1528048D02*
X1438785D01*
G01X1441235Y1528026D02*
X1441007D01*
G01X1441235Y1525828D02*
X1441007D01*
G01X1439047Y1525806D02*
X1438785D01*
G01X1439047Y1524898D02*
X1438785D01*
G01X1441235Y1524877D02*
X1441007D01*
G01X1441235Y1522678D02*
X1441007D01*
G01X1439047Y1522657D02*
X1438785D01*
G01X1439047Y1521749D02*
X1438785D01*
G01X1441235Y1521727D02*
X1441007D01*
G01X1441235Y1519529D02*
X1441007D01*
G01X1439047Y1519507D02*
X1438785D01*
G01X1439047Y1518599D02*
X1438785D01*
G01X1441235Y1518577D02*
X1441007D01*
G01X1449937Y1515116D02*
X1430449D01*
G01Y1507242D02*
X1449937D01*
G01X1440094Y1573062D02*
X1438785Y1573050D01*
G01X1441235Y1573072D02*
X1440094Y1573062D01*
G01Y1569912D02*
X1438785Y1569901D01*
G01X1441235Y1569922D02*
X1440094Y1569912D01*
G01Y1566763D02*
X1438785Y1566751D01*
G01X1441235Y1566773D02*
X1440094Y1566763D01*
G01Y1563613D02*
X1438785Y1563602D01*
G01X1441235Y1563623D02*
X1440094Y1563613D01*
G01Y1560464D02*
X1438785Y1560452D01*
G01X1441235Y1560474D02*
X1440094Y1560464D01*
G01Y1557314D02*
X1438785Y1557302D01*
G01X1441235Y1557324D02*
X1440094Y1557314D01*
G01Y1554164D02*
X1438785Y1554153D01*
G01X1441235Y1554174D02*
X1440094Y1554164D01*
G01Y1551015D02*
X1438785Y1551003D01*
G01X1441235Y1551025D02*
X1440094Y1551015D01*
G01Y1547865D02*
X1438785Y1547854D01*
G01X1441235Y1547875D02*
X1440094Y1547865D01*
G01Y1544716D02*
X1438785Y1544704D01*
G01X1441235Y1544726D02*
X1440094Y1544716D01*
G01Y1541566D02*
X1438785Y1541554D01*
G01X1441235Y1541576D02*
X1440094Y1541566D01*
G01X1438785Y1538405D02*
X1440094Y1538416D01*
G01X1441235Y1538426D02*
X1440094Y1538416D01*
G01Y1535267D02*
X1438785Y1535255D01*
G01X1441235Y1535277D02*
X1440094Y1535267D01*
G01Y1532117D02*
X1438785Y1532106D01*
G01X1441235Y1532127D02*
X1440094Y1532117D01*
G01Y1528968D02*
X1438785Y1528956D01*
G01X1441235Y1528978D02*
X1440094Y1528968D01*
G01Y1525818D02*
X1438785Y1525806D01*
G01X1441235Y1525828D02*
X1440094Y1525818D01*
G01Y1522668D02*
X1438785Y1522657D01*
G01X1441235Y1522678D02*
X1440094Y1522668D01*
G01Y1519519D02*
X1438785Y1519507D01*
G01X1441235Y1519529D02*
X1440094Y1519519D01*
G01X1437751Y1573036D02*
X1436420Y1573024D01*
G01X1437751Y1569887D02*
X1436420Y1569875D01*
G01X1437751Y1566737D02*
X1436420Y1566725D01*
G01X1437751Y1563587D02*
X1436420Y1563576D01*
G01X1437751Y1560438D02*
X1436420Y1560426D01*
G01X1437751Y1557288D02*
X1436420Y1557276D01*
G01X1437751Y1554139D02*
X1436420Y1554127D01*
G01X1437751Y1550989D02*
X1436420Y1550977D01*
G01X1437751Y1547839D02*
X1436420Y1547828D01*
G01X1437751Y1544690D02*
X1436420Y1544678D01*
G01X1437751Y1541540D02*
X1436420Y1541528D01*
G01X1437751Y1538391D02*
X1436420Y1538379D01*
G01X1437751Y1535241D02*
X1436420Y1535229D01*
G01X1437751Y1532091D02*
X1436420Y1532079D01*
G01X1437751Y1528942D02*
X1436420Y1528930D01*
G01X1437751Y1525792D02*
X1436420Y1525780D01*
G01X1437751Y1522642D02*
X1436420Y1522631D01*
G01X1437751Y1519493D02*
X1436420Y1519481D01*
G01X1442543Y1573088D02*
X1441007Y1573072D01*
G01X1442543Y1573088D02*
X1439047Y1573051D01*
G01X1441235Y1573072D02*
X1442772Y1573088D01*
G01X1442543Y1569939D02*
X1441007Y1569922D01*
G01X1442543Y1569939D02*
X1439047Y1569901D01*
G01X1441235Y1569922D02*
X1442772Y1569939D01*
G01X1442543Y1566789D02*
X1441007Y1566773D01*
G01X1442543Y1566789D02*
X1439047Y1566751D01*
G01X1441235Y1566773D02*
X1442772Y1566789D01*
G01X1442543Y1563640D02*
X1441007Y1563623D01*
G01X1442543Y1563640D02*
X1439047Y1563602D01*
G01X1441235Y1563623D02*
X1442772Y1563640D01*
G01X1442543Y1560490D02*
X1441007Y1560474D01*
G01X1442543Y1560490D02*
X1439047Y1560452D01*
G01X1441235Y1560474D02*
X1442772Y1560490D01*
G01X1442543Y1557340D02*
X1441007Y1557324D01*
G01X1442543Y1557340D02*
X1439047Y1557302D01*
G01X1441235Y1557324D02*
X1442772Y1557340D01*
G01X1442543Y1554191D02*
X1441007Y1554174D01*
G01X1442543Y1554191D02*
X1439047Y1554153D01*
G01X1441235Y1554174D02*
X1442772Y1554191D01*
G01X1442543Y1551041D02*
X1441007Y1551025D01*
G01X1442543Y1551041D02*
X1439047Y1551003D01*
G01X1441235Y1551025D02*
X1442772Y1551041D01*
G01X1442543Y1547892D02*
X1441007Y1547875D01*
G01X1442543Y1547892D02*
X1439047Y1547854D01*
G01X1441235Y1547875D02*
X1442772Y1547892D01*
G01X1442543Y1544742D02*
X1441007Y1544726D01*
G01X1442543Y1544742D02*
X1439047Y1544704D01*
G01X1441235Y1544726D02*
X1442772Y1544742D01*
G01X1442543Y1541592D02*
X1441007Y1541576D01*
G01X1442543Y1541592D02*
X1439047Y1541554D01*
G01X1441235Y1541576D02*
X1442772Y1541592D01*
G01X1442543Y1538443D02*
X1441007Y1538426D01*
G01X1442543Y1538443D02*
X1439047Y1538405D01*
G01X1441235Y1538426D02*
X1442772Y1538443D01*
G01X1442543Y1535293D02*
X1441007Y1535277D01*
G01X1442543Y1535293D02*
X1439047Y1535255D01*
G01X1441235Y1535277D02*
X1442772Y1535293D01*
G01X1442543Y1532144D02*
X1441007Y1532127D01*
G01X1442543Y1532144D02*
X1439047Y1532106D01*
G01X1441235Y1532127D02*
X1442772Y1532144D01*
G01X1442543Y1528994D02*
X1441007Y1528978D01*
G01X1442543Y1528994D02*
X1439047Y1528956D01*
G01X1441235Y1528978D02*
X1442772Y1528994D01*
G01X1442543Y1525844D02*
X1441007Y1525828D01*
G01X1442543Y1525844D02*
X1439047Y1525806D01*
G01X1441235Y1525828D02*
X1442772Y1525844D01*
G01X1442543Y1522695D02*
X1441007Y1522678D01*
G01X1442543Y1522695D02*
X1439047Y1522657D01*
G01X1441235Y1522678D02*
X1442772Y1522695D01*
G01X1442543Y1519545D02*
X1441007Y1519529D01*
G01X1442543Y1519545D02*
X1439047Y1519507D01*
G01X1441235Y1519529D02*
X1442772Y1519545D01*
G01X1439047Y1573050D02*
X1440094Y1573062D01*
G01X1438785Y1573050D02*
X1436420Y1573024D01*
G01X1437751Y1573036D02*
X1439047Y1573050D01*
G01Y1569901D02*
X1440094Y1569912D01*
G01X1438785Y1569901D02*
X1436420Y1569875D01*
G01X1437751Y1569887D02*
X1439047Y1569901D01*
G01Y1566751D02*
X1440094Y1566763D01*
G01X1438785Y1566751D02*
X1436420Y1566725D01*
G01X1437751Y1566737D02*
X1439047Y1566751D01*
G01Y1563602D02*
X1440094Y1563613D01*
G01X1438785Y1563602D02*
X1436420Y1563576D01*
G01X1437751Y1563587D02*
X1439047Y1563602D01*
G01Y1560452D02*
X1440094Y1560464D01*
G01X1438785Y1560452D02*
X1436420Y1560426D01*
G01X1437751Y1560438D02*
X1439047Y1560452D01*
G01Y1557302D02*
X1440094Y1557314D01*
G01X1438785Y1557302D02*
X1436420Y1557276D01*
G01X1437751Y1557288D02*
X1439047Y1557302D01*
G01Y1554153D02*
X1440094Y1554164D01*
G01X1438785Y1554153D02*
X1436420Y1554127D01*
G01X1437751Y1554139D02*
X1439047Y1554153D01*
G01Y1551003D02*
X1440094Y1551015D01*
G01X1438785Y1551003D02*
X1436420Y1550977D01*
G01X1437751Y1550989D02*
X1439047Y1551003D01*
G01Y1547854D02*
X1440094Y1547865D01*
G01X1438785Y1547854D02*
X1436420Y1547828D01*
G01X1437751Y1547839D02*
X1439047Y1547854D01*
G01Y1544704D02*
X1440094Y1544716D01*
G01X1438785Y1544704D02*
X1436420Y1544678D01*
G01X1437751Y1544690D02*
X1439047Y1544704D01*
G01Y1541554D02*
X1440094Y1541566D01*
G01X1438785Y1541554D02*
X1436420Y1541528D01*
G01X1437751Y1541540D02*
X1439047Y1541554D01*
G01Y1538405D02*
X1440094Y1538416D01*
G01X1438785Y1538405D02*
X1436420Y1538379D01*
G01X1437751Y1538391D02*
X1439047Y1538405D01*
G01Y1535255D02*
X1440094Y1535267D01*
G01X1438785Y1535255D02*
X1436420Y1535229D01*
G01X1437751Y1535241D02*
X1439047Y1535255D01*
G01Y1532106D02*
X1440094Y1532117D01*
G01X1438785Y1532106D02*
X1436420Y1532079D01*
G01X1437751Y1532091D02*
X1439047Y1532106D01*
G01Y1528956D02*
X1440094Y1528968D01*
G01X1438785Y1528956D02*
X1436420Y1528930D01*
G01X1437751Y1528942D02*
X1439047Y1528956D01*
G01Y1525806D02*
X1440094Y1525818D01*
G01X1438785Y1525806D02*
X1436420Y1525780D01*
G01X1437751Y1525792D02*
X1439047Y1525806D01*
G01Y1522657D02*
X1440094Y1522668D01*
G01X1438785Y1522657D02*
X1436420Y1522631D01*
G01X1437751Y1522642D02*
X1439047Y1522657D01*
G01Y1519507D02*
X1440094Y1519519D01*
G01X1438785Y1519507D02*
X1436420Y1519481D01*
G01X1437751Y1519493D02*
X1439047Y1519507D01*
G01X1426512Y1509211D02*
X1430449Y1507242D01*
G01Y1515116D02*
X1426512Y1513148D01*
G01X1441235Y1519529D02*
Y1518577D01*
G01Y1522678D02*
Y1521727D01*
G01Y1528977D02*
Y1528026D01*
G01Y1525828D02*
Y1524877D01*
G01Y1532127D02*
Y1531176D01*
G01Y1538426D02*
Y1537475D01*
G01Y1535277D02*
Y1534325D01*
G01Y1541576D02*
Y1540625D01*
G01Y1547875D02*
Y1546924D01*
G01Y1544726D02*
Y1543774D01*
G01Y1551025D02*
Y1550073D01*
G01Y1557324D02*
Y1556373D01*
G01Y1554174D02*
Y1553223D01*
G01Y1560474D02*
Y1559522D01*
G01Y1566773D02*
Y1565821D01*
G01Y1563623D02*
Y1562672D01*
G01Y1569922D02*
Y1568971D01*
G01Y1576222D02*
Y1575270D01*
G01Y1573072D02*
Y1572121D01*
G01X1441007Y1519529D02*
Y1518577D01*
G01Y1522678D02*
Y1521727D01*
G01Y1528978D02*
Y1528026D01*
G01Y1525828D02*
Y1524877D01*
G01Y1532127D02*
Y1531176D01*
G01Y1538426D02*
Y1537475D01*
G01Y1535277D02*
Y1534325D01*
G01Y1541576D02*
Y1540625D01*
G01Y1547875D02*
Y1546924D01*
G01Y1544726D02*
Y1543774D01*
G01Y1551025D02*
Y1550073D01*
G01Y1557324D02*
Y1556373D01*
G01Y1554174D02*
Y1553223D01*
G01Y1560474D02*
Y1559522D01*
G01Y1566773D02*
Y1565821D01*
G01Y1563623D02*
Y1562672D01*
G01Y1569922D02*
Y1568971D01*
G01Y1576222D02*
Y1575270D01*
G01Y1573072D02*
Y1572121D01*
G01X1439047Y1519507D02*
Y1518599D01*
G01Y1522657D02*
Y1521749D01*
G01Y1528956D02*
Y1528048D01*
G01Y1525806D02*
Y1524898D01*
G01Y1532106D02*
Y1531197D01*
G01Y1538405D02*
Y1537497D01*
G01Y1535255D02*
Y1534347D01*
G01Y1541554D02*
Y1540646D01*
G01Y1547854D02*
Y1546945D01*
G01Y1544704D02*
Y1543796D01*
G01Y1551003D02*
Y1550095D01*
G01Y1557302D02*
Y1556394D01*
G01Y1554153D02*
Y1553245D01*
G01Y1560452D02*
Y1559544D01*
G01Y1566751D02*
Y1565843D01*
G01Y1563602D02*
Y1562693D01*
G01Y1569901D02*
Y1568993D01*
G01Y1576200D02*
Y1575292D01*
G01Y1573051D02*
Y1572142D01*
G01X1438785Y1519507D02*
Y1518599D01*
G01Y1522657D02*
Y1521749D01*
G01Y1528956D02*
Y1528048D01*
G01Y1525806D02*
Y1524898D01*
G01Y1532106D02*
Y1531197D01*
G01Y1538405D02*
Y1537497D01*
G01Y1535255D02*
Y1534347D01*
G01Y1541554D02*
Y1540646D01*
G01Y1547854D02*
Y1546945D01*
G01Y1544704D02*
Y1543796D01*
G01Y1551003D02*
Y1550095D01*
G01Y1557302D02*
Y1556394D01*
G01Y1554153D02*
Y1553245D01*
G01Y1560452D02*
Y1559544D01*
G01Y1566751D02*
Y1565843D01*
G01Y1563602D02*
Y1562693D01*
G01Y1569901D02*
Y1568993D01*
G01Y1576200D02*
Y1575292D01*
G01Y1573051D02*
Y1572142D01*
G01X1437751Y1519487D02*
Y1518619D01*
G01Y1522637D02*
Y1521769D01*
G01Y1528936D02*
Y1528068D01*
G01Y1525786D02*
Y1524918D01*
G01Y1532085D02*
Y1531218D01*
G01Y1538385D02*
Y1537517D01*
G01Y1535235D02*
Y1534367D01*
G01Y1541534D02*
Y1540666D01*
G01Y1547833D02*
Y1546966D01*
G01Y1544684D02*
Y1543816D01*
G01Y1550983D02*
Y1550115D01*
G01Y1557282D02*
Y1556414D01*
G01Y1554133D02*
Y1553265D01*
G01Y1560432D02*
Y1559564D01*
G01Y1566731D02*
Y1565863D01*
G01Y1563581D02*
Y1562714D01*
G01Y1569881D02*
Y1569013D01*
G01Y1576180D02*
Y1575312D01*
G01Y1573030D02*
Y1572162D01*
G01X1436420Y1519481D02*
Y1518625D01*
G01Y1522631D02*
Y1521775D01*
G01Y1528930D02*
Y1528074D01*
G01Y1525780D02*
Y1524924D01*
G01Y1532079D02*
Y1531223D01*
G01Y1538379D02*
Y1537523D01*
G01Y1535229D02*
Y1534373D01*
G01Y1541528D02*
Y1540672D01*
G01Y1547828D02*
Y1546971D01*
G01Y1544678D02*
Y1543822D01*
G01Y1550977D02*
Y1550121D01*
G01Y1557276D02*
Y1556420D01*
G01Y1554127D02*
Y1553271D01*
G01Y1560426D02*
Y1559570D01*
G01Y1566725D02*
Y1565869D01*
G01Y1563576D02*
Y1562720D01*
G01Y1569875D02*
Y1569019D01*
G01Y1576174D02*
Y1575318D01*
G01Y1573024D02*
Y1572168D01*
G01X1430449Y1694250D02*
Y1515116D01*
G01X1457732Y1504486D02*
X1457220D01*
G01X1444212Y1504092D02*
X1443073D01*
G01X1469631Y1503896D02*
X1457535D01*
G01X1442772Y1503797D02*
X1442543D01*
G01X1470921Y1503640D02*
X1469507D01*
G01X1470921Y1502970D02*
X1469507D01*
G01X1442772Y1502813D02*
X1442543D01*
G01X1469631Y1502714D02*
X1457535D01*
G01X1469278Y1503896D02*
X1469507Y1503640D01*
G01X1469636Y1503910D02*
X1469855Y1503640D01*
G01X1443073Y1504092D02*
X1442684Y1503885D01*
G01X1443243Y1504092D02*
X1442772Y1503797D01*
G01X1442684Y1503885D02*
X1442543Y1503797D01*
G01X1470921Y1503640D02*
Y1502970D01*
G01X1470574Y1503640D02*
Y1502970D01*
G01X1469631Y1503896D02*
Y1502714D01*
G01X1469278Y1503896D02*
Y1502714D01*
G01X1467296Y1503896D02*
Y1502714D01*
G01X1467186Y1503896D02*
Y1502714D01*
G01X1458405Y1503896D02*
Y1502714D01*
G01X1458295Y1503896D02*
Y1502714D01*
G01X1457929Y1503896D02*
Y1502714D01*
G01X1457732Y1504486D02*
Y1503896D01*
G01X1457535Y1504486D02*
Y1503896D01*
G01X1442684Y1503885D02*
Y1502725D01*
G01X1457220Y1504880D02*
X1459189Y1506848D01*
G01X1474543D02*
G03Y1515510I0J4331D01*
G01X1470921Y1575411D02*
X1469507D01*
G01X1442772Y1575254D02*
X1442543D01*
G01X1469631Y1575155D02*
X1457535D01*
G01X1444212Y1574959D02*
X1443073D01*
G01X1457732Y1574565D02*
X1457220D01*
G01X1457732Y1573777D02*
X1457220D01*
G01X1444212Y1573384D02*
X1443073D01*
G01X1469631Y1573187D02*
X1457535D01*
G01X1442772Y1573088D02*
X1442543D01*
G01X1470921Y1572931D02*
X1469507D01*
G01X1470921Y1572262D02*
X1469507D01*
G01X1442772Y1572104D02*
X1442543D01*
G01X1469631Y1572006D02*
X1457535D01*
G01X1444212Y1571809D02*
X1443073D01*
G01X1457732Y1571415D02*
X1457220D01*
G01X1457732Y1570628D02*
X1457220D01*
G01X1444212Y1570234D02*
X1443073D01*
G01X1469631Y1570037D02*
X1457535D01*
G01X1442772Y1569939D02*
X1442543D01*
G01X1470921Y1569781D02*
X1469507D01*
G01X1470921Y1569112D02*
X1469507D01*
G01X1442772Y1568955D02*
X1442543D01*
G01X1469631Y1568856D02*
X1457535D01*
G01X1444212Y1568659D02*
X1443073D01*
G01X1457732Y1568266D02*
X1457220D01*
G01X1457732Y1567478D02*
X1457220D01*
G01X1444212Y1567085D02*
X1443073D01*
G01X1469631Y1566888D02*
X1457535D01*
G01X1442772Y1566789D02*
X1442543D01*
G01X1470921Y1566632D02*
X1469507D01*
G01X1470921Y1565963D02*
X1469507D01*
G01X1442772Y1565805D02*
X1442543D01*
G01X1469631Y1565707D02*
X1457535D01*
G01X1444212Y1565510D02*
X1443073D01*
G01X1457732Y1565116D02*
X1457220D01*
G01X1457732Y1564329D02*
X1457220D01*
G01X1444212Y1563935D02*
X1443073D01*
G01X1469631Y1563738D02*
X1457535D01*
G01X1442772Y1563640D02*
X1442543D01*
G01X1470921Y1563482D02*
X1469507D01*
G01X1470921Y1562813D02*
X1469507D01*
G01X1442772Y1562655D02*
X1442543D01*
G01X1469631Y1562557D02*
X1457535D01*
G01X1444212Y1562360D02*
X1443073D01*
G01X1457732Y1561966D02*
X1457220D01*
G01X1457732Y1561179D02*
X1457220D01*
G01X1444212Y1560785D02*
X1443073D01*
G01X1469631Y1560588D02*
X1457535D01*
G01X1442772Y1560490D02*
X1442543D01*
G01X1470921Y1560333D02*
X1469507D01*
G01X1470921Y1559663D02*
X1469507D01*
G01X1442772Y1559506D02*
X1442543D01*
G01X1469631Y1559407D02*
X1457535D01*
G01X1444212Y1559211D02*
X1443073D01*
G01X1457732Y1558817D02*
X1457220D01*
G01X1457732Y1558029D02*
X1457220D01*
G01X1444212Y1557636D02*
X1443073D01*
G01X1469631Y1557439D02*
X1457535D01*
G01X1442772Y1557340D02*
X1442543D01*
G01X1470921Y1557183D02*
X1469507D01*
G01X1470921Y1556514D02*
X1469507D01*
G01X1442772Y1556356D02*
X1442543D01*
G01X1469631Y1556258D02*
X1457535D01*
G01X1444212Y1556061D02*
X1443073D01*
G01X1457732Y1555667D02*
X1457220D01*
G01X1457732Y1554880D02*
X1457220D01*
G01X1444212Y1554486D02*
X1443073D01*
G01X1469631Y1554289D02*
X1457535D01*
G01X1442772Y1554191D02*
X1442543D01*
G01X1470921Y1554033D02*
X1469507D01*
G01X1470921Y1553364D02*
X1469507D01*
G01X1442772Y1553207D02*
X1442543D01*
G01X1469631Y1553108D02*
X1457535D01*
G01X1444212Y1552911D02*
X1443073D01*
G01X1457732Y1552518D02*
X1457220D01*
G01X1457732Y1551730D02*
X1457220D01*
G01X1444212Y1551337D02*
X1443073D01*
G01X1469631Y1551140D02*
X1457535D01*
G01X1442772Y1551041D02*
X1442543D01*
G01X1470921Y1550884D02*
X1469507D01*
G01X1470921Y1550214D02*
X1469507D01*
G01X1442772Y1550057D02*
X1442543D01*
G01X1469631Y1549959D02*
X1457535D01*
G01X1444212Y1549762D02*
X1443073D01*
G01X1457732Y1549368D02*
X1457220D01*
G01X1457732Y1548581D02*
X1457220D01*
G01X1444212Y1548187D02*
X1443073D01*
G01X1469631Y1547990D02*
X1457535D01*
G01X1442772Y1547892D02*
X1442543D01*
G01X1470921Y1547734D02*
X1469507D01*
G01X1470921Y1547065D02*
X1469507D01*
G01X1442772Y1546907D02*
X1442543D01*
G01X1469631Y1546809D02*
X1457535D01*
G01X1444212Y1546612D02*
X1443073D01*
G01X1457732Y1546218D02*
X1457220D01*
G01X1457732Y1545431D02*
X1457220D01*
G01X1444212Y1545037D02*
X1443073D01*
G01X1469631Y1544840D02*
X1457535D01*
G01X1442772Y1544742D02*
X1442543D01*
G01X1470921Y1544585D02*
X1469507D01*
G01X1470921Y1543915D02*
X1469507D01*
G01X1442772Y1543758D02*
X1442543D01*
G01X1469631Y1543659D02*
X1457535D01*
G01X1444212Y1543463D02*
X1443073D01*
G01X1457732Y1543069D02*
X1457220D01*
G01X1457732Y1542281D02*
X1457220D01*
G01X1444212Y1541888D02*
X1443073D01*
G01X1469631Y1541691D02*
X1457535D01*
G01X1442772Y1541592D02*
X1442543D01*
G01X1470921Y1541435D02*
X1469507D01*
G01X1470921Y1540766D02*
X1469507D01*
G01X1442772Y1540608D02*
X1442543D01*
G01X1469631Y1540510D02*
X1457535D01*
G01X1444212Y1540313D02*
X1443073D01*
G01X1457732Y1539919D02*
X1457220D01*
G01X1457732Y1539132D02*
X1457220D01*
G01X1444212Y1538738D02*
X1443073D01*
G01X1469631Y1538541D02*
X1457535D01*
G01X1442772Y1538443D02*
X1442543D01*
G01X1470921Y1538285D02*
X1469507D01*
G01X1470921Y1537616D02*
X1469507D01*
G01X1442772Y1537459D02*
X1442543D01*
G01X1469631Y1537360D02*
X1457535D01*
G01X1444212Y1537163D02*
X1443073D01*
G01X1457732Y1536770D02*
X1457220D01*
G01X1457732Y1535982D02*
X1457220D01*
G01X1444212Y1535588D02*
X1443073D01*
G01X1469631Y1535392D02*
X1457535D01*
G01X1442772Y1535293D02*
X1442543D01*
G01X1470921Y1535136D02*
X1469507D01*
G01X1470921Y1534466D02*
X1469507D01*
G01X1442772Y1534309D02*
X1442543D01*
G01X1469631Y1534211D02*
X1457535D01*
G01X1444212Y1534014D02*
X1443073D01*
G01X1457732Y1533620D02*
X1457220D01*
G01X1457732Y1532833D02*
X1457220D01*
G01X1444212Y1532439D02*
X1443073D01*
G01X1469631Y1532242D02*
X1457535D01*
G01X1442772Y1532144D02*
X1442543D01*
G01X1470921Y1531986D02*
X1469507D01*
G01X1470921Y1531317D02*
X1469507D01*
G01X1442772Y1531159D02*
X1442543D01*
G01X1469631Y1531061D02*
X1457535D01*
G01X1444212Y1530864D02*
X1443073D01*
G01X1457732Y1530470D02*
X1457220D01*
G01X1457732Y1529683D02*
X1457220D01*
G01X1444212Y1529289D02*
X1443073D01*
G01X1469631Y1529092D02*
X1457535D01*
G01X1442772Y1528994D02*
X1442543D01*
G01X1470921Y1528837D02*
X1469507D01*
G01X1470921Y1528167D02*
X1469507D01*
G01X1442772Y1528010D02*
X1442543D01*
G01X1469631Y1527911D02*
X1457535D01*
G01X1444212Y1527714D02*
X1443073D01*
G01X1457732Y1527321D02*
X1457220D01*
G01X1457732Y1526533D02*
X1457220D01*
G01X1444212Y1526140D02*
X1443073D01*
G01X1469631Y1525943D02*
X1457535D01*
G01X1442772Y1525844D02*
X1442543D01*
G01X1470921Y1525687D02*
X1469507D01*
G01X1470921Y1525018D02*
X1469507D01*
G01X1442772Y1524860D02*
X1442543D01*
G01X1469631Y1524762D02*
X1457535D01*
G01X1444212Y1524565D02*
X1443073D01*
G01X1457732Y1524171D02*
X1457220D01*
G01X1457732Y1523384D02*
X1457220D01*
G01X1444212Y1522990D02*
X1443073D01*
G01X1469631Y1522793D02*
X1457535D01*
G01X1442772Y1522695D02*
X1442543D01*
G01X1470921Y1522537D02*
X1469507D01*
G01X1470921Y1521868D02*
X1469507D01*
G01X1442772Y1521711D02*
X1442543D01*
G01X1469631Y1521612D02*
X1457535D01*
G01X1444212Y1521415D02*
X1443073D01*
G01X1457732Y1521022D02*
X1457220D01*
G01X1457732Y1520234D02*
X1457220D01*
G01X1444212Y1519840D02*
X1443073D01*
G01X1469631Y1519644D02*
X1457535D01*
G01X1442772Y1519545D02*
X1442543D01*
G01X1470921Y1519388D02*
X1469507D01*
G01X1470921Y1518718D02*
X1469507D01*
G01X1442772Y1518561D02*
X1442543D01*
G01X1469631Y1518463D02*
X1457535D01*
G01X1444212Y1518266D02*
X1443073D01*
G01X1457732Y1517872D02*
X1457220D01*
G01X1474543Y1515510D02*
X1459189D01*
G01X1474937Y1515116D02*
X1457220D01*
G01X1474937Y1507242D02*
X1457220D01*
G01X1459189Y1506848D02*
X1474543D01*
G01X1442684Y1575166D02*
X1443073Y1574959D01*
G01X1442684Y1572016D02*
X1443073Y1571809D01*
G01X1442684Y1568867D02*
X1443073Y1568659D01*
G01X1442684Y1565717D02*
X1443073Y1565510D01*
G01X1442684Y1562568D02*
X1443073Y1562360D01*
G01X1442684Y1559418D02*
X1443073Y1559211D01*
G01X1442684Y1556268D02*
X1443073Y1556061D01*
G01X1442772Y1575254D02*
X1443243Y1574959D01*
G01X1442543Y1575254D02*
X1442684Y1575166D01*
G01X1442772Y1572104D02*
X1443243Y1571809D01*
G01X1442543Y1572104D02*
X1442684Y1572016D01*
G01X1442772Y1568955D02*
X1443243Y1568659D01*
G01X1442543Y1568955D02*
X1442684Y1568867D01*
G01X1442772Y1565805D02*
X1443243Y1565510D01*
G01X1442543Y1565805D02*
X1442684Y1565717D01*
G01X1442772Y1562655D02*
X1443243Y1562360D01*
G01X1442543Y1562655D02*
X1442684Y1562568D01*
G01X1442772Y1559506D02*
X1443243Y1559211D01*
G01X1442543Y1559506D02*
X1442684Y1559418D01*
G01X1442772Y1556356D02*
X1443243Y1556061D01*
G01X1442543Y1556356D02*
X1442684Y1556268D01*
G01X1442772Y1553207D02*
X1443243Y1552911D01*
G01X1442543Y1553207D02*
X1442684Y1553119D01*
G01X1442772Y1550057D02*
X1443243Y1549762D01*
G01X1442543Y1550057D02*
X1442684Y1549969D01*
G01X1442772Y1546907D02*
X1443243Y1546612D01*
G01X1442543Y1546907D02*
X1442684Y1546820D01*
G01X1442772Y1543758D02*
X1443243Y1543463D01*
G01X1442543Y1543758D02*
X1442684Y1543670D01*
G01X1442772Y1540608D02*
X1443243Y1540313D01*
G01X1442543Y1540608D02*
X1442684Y1540520D01*
G01X1442772Y1537459D02*
X1443243Y1537163D01*
G01X1442543Y1537459D02*
X1442684Y1537371D01*
G01X1442772Y1534309D02*
X1443243Y1534014D01*
G01X1442543Y1534309D02*
X1442684Y1534221D01*
G01X1442772Y1531159D02*
X1443243Y1530864D01*
G01X1442543Y1531159D02*
X1442684Y1531072D01*
G01X1442772Y1528010D02*
X1443243Y1527714D01*
G01X1442543Y1528010D02*
X1442684Y1527922D01*
G01X1442772Y1524860D02*
X1443243Y1524565D01*
G01X1442543Y1524860D02*
X1442684Y1524772D01*
G01X1442772Y1521711D02*
X1443243Y1521415D01*
G01X1442543Y1521711D02*
X1442684Y1521623D01*
G01X1442772Y1518561D02*
X1443243Y1518266D01*
G01X1442543Y1518561D02*
X1442684Y1518473D01*
G01Y1553119D02*
X1443073Y1552911D01*
G01X1442684Y1549969D02*
X1443073Y1549762D01*
G01X1442684Y1546820D02*
X1443073Y1546612D01*
G01X1442684Y1543670D02*
X1443073Y1543463D01*
G01X1442684Y1540520D02*
X1443073Y1540313D01*
G01X1442684Y1537371D02*
X1443073Y1537163D01*
G01X1442684Y1534221D02*
X1443073Y1534014D01*
G01X1442684Y1531072D02*
X1443073Y1530864D01*
G01X1442684Y1527922D02*
X1443073Y1527714D01*
G01X1442684Y1524772D02*
X1443073Y1524565D01*
G01X1442684Y1521623D02*
X1443073Y1521415D01*
G01X1442684Y1518473D02*
X1443073Y1518266D01*
G01X1469636Y1573201D02*
X1469855Y1572931D01*
G01X1469636Y1570051D02*
X1469855Y1569781D01*
G01X1469636Y1566902D02*
X1469855Y1566632D01*
G01X1469636Y1563752D02*
X1469855Y1563482D01*
G01X1469636Y1560603D02*
X1469855Y1560333D01*
G01X1469636Y1557453D02*
X1469855Y1557183D01*
G01X1469636Y1554303D02*
X1469855Y1554033D01*
G01X1469636Y1551154D02*
X1469855Y1550884D01*
G01X1469636Y1548004D02*
X1469855Y1547734D01*
G01X1469636Y1544855D02*
X1469855Y1544585D01*
G01X1469636Y1541705D02*
X1469855Y1541435D01*
G01X1469636Y1538555D02*
X1469855Y1538285D01*
G01X1469636Y1535406D02*
X1469855Y1535136D01*
G01X1469636Y1532256D02*
X1469855Y1531986D01*
G01X1469636Y1529107D02*
X1469855Y1528837D01*
G01X1469278Y1573187D02*
X1469507Y1572931D01*
G01X1469278Y1570037D02*
X1469507Y1569781D01*
G01X1469278Y1566888D02*
X1469507Y1566632D01*
G01X1469278Y1563738D02*
X1469507Y1563482D01*
G01X1469278Y1560588D02*
X1469507Y1560333D01*
G01X1469278Y1557439D02*
X1469507Y1557183D01*
G01X1469278Y1554289D02*
X1469507Y1554033D01*
G01X1469278Y1551140D02*
X1469507Y1550884D01*
G01X1469278Y1547990D02*
X1469507Y1547734D01*
G01X1469278Y1544840D02*
X1469507Y1544585D01*
G01X1469278Y1541691D02*
X1469507Y1541435D01*
G01X1469278Y1538541D02*
X1469507Y1538285D01*
G01X1469278Y1535392D02*
X1469507Y1535136D01*
G01X1469278Y1532242D02*
X1469507Y1531986D01*
G01X1469278Y1529092D02*
X1469507Y1528837D01*
G01X1469278Y1525943D02*
X1469507Y1525687D01*
G01X1469278Y1522793D02*
X1469507Y1522537D01*
G01X1469278Y1519644D02*
X1469507Y1519388D01*
G01X1474937Y1515116D02*
X1476905Y1513148D01*
G01X1459189Y1515510D02*
X1457220Y1517478D01*
G01X1493047Y1519971D02*
X1497767Y1515330D01*
G01X1493047Y1518868D02*
X1497772Y1514222D01*
G01X1469636Y1525957D02*
X1469855Y1525687D01*
G01X1469636Y1522807D02*
X1469855Y1522537D01*
G01X1469636Y1519658D02*
X1469855Y1519388D01*
G01X1443073Y1519840D02*
X1442684Y1519633D01*
G01X1443073Y1522990D02*
X1442684Y1522783D01*
G01X1443073Y1526140D02*
X1442684Y1525932D01*
G01X1443073Y1529289D02*
X1442684Y1529082D01*
G01X1443073Y1532439D02*
X1442684Y1532231D01*
G01X1443073Y1535588D02*
X1442684Y1535381D01*
G01X1443073Y1538738D02*
X1442684Y1538531D01*
G01X1443073Y1541888D02*
X1442684Y1541680D01*
G01X1443073Y1545037D02*
X1442684Y1544830D01*
G01X1443073Y1548187D02*
X1442684Y1547979D01*
G01X1443073Y1551337D02*
X1442684Y1551129D01*
G01X1443073Y1554486D02*
X1442684Y1554279D01*
G01X1443073Y1557636D02*
X1442684Y1557428D01*
G01X1443073Y1560785D02*
X1442684Y1560578D01*
G01X1443073Y1563935D02*
X1442684Y1563727D01*
G01X1443073Y1567085D02*
X1442684Y1566877D01*
G01X1443073Y1570234D02*
X1442684Y1570027D01*
G01X1443073Y1573384D02*
X1442684Y1573176D01*
G01X1496457Y1522569D02*
X1493047Y1520600D01*
G01X1443243Y1519840D02*
X1442772Y1519545D01*
G01X1442684Y1519633D02*
X1442543Y1519545D01*
G01X1443243Y1522990D02*
X1442772Y1522695D01*
G01X1442684Y1522783D02*
X1442543Y1522695D01*
G01X1443243Y1526140D02*
X1442772Y1525844D01*
G01X1442684Y1525932D02*
X1442543Y1525844D01*
G01X1443243Y1529289D02*
X1442772Y1528994D01*
G01X1442684Y1529082D02*
X1442543Y1528994D01*
G01X1443243Y1532439D02*
X1442772Y1532144D01*
G01X1442684Y1532231D02*
X1442543Y1532144D01*
G01X1443243Y1535588D02*
X1442772Y1535293D01*
G01X1442684Y1535381D02*
X1442543Y1535293D01*
G01X1443243Y1538738D02*
X1442772Y1538443D01*
G01X1442684Y1538531D02*
X1442543Y1538443D01*
G01X1443243Y1541888D02*
X1442772Y1541592D01*
G01X1442684Y1541680D02*
X1442543Y1541592D01*
G01X1443243Y1545037D02*
X1442772Y1544742D01*
G01X1442684Y1544830D02*
X1442543Y1544742D01*
G01X1443243Y1548187D02*
X1442772Y1547892D01*
G01X1442684Y1547979D02*
X1442543Y1547892D01*
G01X1443243Y1551337D02*
X1442772Y1551041D01*
G01X1442684Y1551129D02*
X1442543Y1551041D01*
G01X1443243Y1554486D02*
X1442772Y1554191D01*
G01X1442684Y1554279D02*
X1442543Y1554191D01*
G01X1443243Y1557636D02*
X1442772Y1557340D01*
G01X1442684Y1557428D02*
X1442543Y1557340D01*
G01X1476905Y1509211D02*
X1474937Y1507242D01*
G01X1493047Y1518868D02*
Y1520600D01*
G01X1476905Y1513148D02*
Y1509211D01*
G01X1470921Y1519388D02*
Y1518718D01*
G01Y1522537D02*
Y1521868D01*
G01Y1528837D02*
Y1528167D01*
G01Y1525687D02*
Y1525018D01*
G01Y1531986D02*
Y1531317D01*
G01Y1538285D02*
Y1537616D01*
G01Y1535136D02*
Y1534466D01*
G01Y1541435D02*
Y1540766D01*
G01Y1547734D02*
Y1547065D01*
G01Y1544585D02*
Y1543915D01*
G01Y1550884D02*
Y1550214D01*
G01Y1557183D02*
Y1556514D01*
G01Y1554033D02*
Y1553364D01*
G01Y1560333D02*
Y1559663D01*
G01Y1566632D02*
Y1565963D01*
G01Y1563482D02*
Y1562813D01*
G01Y1569781D02*
Y1569112D01*
G01Y1576081D02*
Y1575411D01*
G01Y1572931D02*
Y1572262D01*
G01X1470574Y1519388D02*
Y1518718D01*
G01Y1522537D02*
Y1521868D01*
G01Y1528837D02*
Y1528167D01*
G01Y1525687D02*
Y1525018D01*
G01Y1531986D02*
Y1531317D01*
G01Y1538285D02*
Y1537616D01*
G01Y1535136D02*
Y1534466D01*
G01Y1541435D02*
Y1540766D01*
G01Y1547734D02*
Y1547065D01*
G01Y1544585D02*
Y1543915D01*
G01Y1550884D02*
Y1550214D01*
G01Y1557183D02*
Y1556514D01*
G01Y1554033D02*
Y1553364D01*
G01Y1560333D02*
Y1559663D01*
G01Y1566632D02*
Y1565963D01*
G01Y1563482D02*
Y1562813D01*
G01Y1569781D02*
Y1569112D01*
G01Y1576081D02*
Y1575411D01*
G01Y1572931D02*
Y1572262D01*
G01X1469631Y1519644D02*
Y1518463D01*
G01Y1522793D02*
Y1521612D01*
G01Y1529092D02*
Y1527911D01*
G01Y1525943D02*
Y1524762D01*
G01Y1532242D02*
Y1531061D01*
G01Y1538541D02*
Y1537360D01*
G01Y1535392D02*
Y1534211D01*
G01Y1541691D02*
Y1540510D01*
G01Y1547990D02*
Y1546809D01*
G01Y1544840D02*
Y1543659D01*
G01Y1551140D02*
Y1549959D01*
G01Y1557439D02*
Y1556258D01*
G01Y1554289D02*
Y1553108D01*
G01Y1560588D02*
Y1559407D01*
G01Y1566888D02*
Y1565707D01*
G01Y1563738D02*
Y1562557D01*
G01Y1570037D02*
Y1568856D01*
G01Y1576337D02*
Y1575155D01*
G01Y1573187D02*
Y1572006D01*
G01X1469278Y1519644D02*
Y1518463D01*
G01Y1522793D02*
Y1521612D01*
G01Y1529092D02*
Y1527911D01*
G01Y1525943D02*
Y1524762D01*
G01Y1532242D02*
Y1531061D01*
G01Y1538541D02*
Y1537360D01*
G01Y1535392D02*
Y1534211D01*
G01Y1541691D02*
Y1540510D01*
G01Y1547990D02*
Y1546809D01*
G01Y1544840D02*
Y1543659D01*
G01Y1551140D02*
Y1549959D01*
G01Y1557439D02*
Y1556258D01*
G01Y1554289D02*
Y1553108D01*
G01Y1560588D02*
Y1559407D01*
G01Y1566888D02*
Y1565707D01*
G01Y1563738D02*
Y1562557D01*
G01Y1570037D02*
Y1568856D01*
G01Y1576337D02*
Y1575155D01*
G01Y1573187D02*
Y1572006D01*
G01X1467296Y1519644D02*
Y1518463D01*
G01Y1522793D02*
Y1521612D01*
G01Y1529092D02*
Y1527911D01*
G01Y1525943D02*
Y1524762D01*
G01Y1532242D02*
Y1531061D01*
G01Y1538541D02*
Y1537360D01*
G01Y1535392D02*
Y1534211D01*
G01Y1541691D02*
Y1540510D01*
G01Y1547990D02*
Y1546809D01*
G01Y1544840D02*
Y1543659D01*
G01Y1551140D02*
Y1549959D01*
G01Y1557439D02*
Y1556258D01*
G01Y1554289D02*
Y1553108D01*
G01Y1560588D02*
Y1559407D01*
G01Y1566888D02*
Y1565707D01*
G01Y1563738D02*
Y1562557D01*
G01Y1570037D02*
Y1568856D01*
G01Y1576337D02*
Y1575155D01*
G01Y1573187D02*
Y1572006D01*
G01X1467186Y1519644D02*
Y1518463D01*
G01Y1522793D02*
Y1521612D01*
G01Y1529092D02*
Y1527911D01*
G01Y1525943D02*
Y1524762D01*
G01Y1532242D02*
Y1531061D01*
G01Y1538541D02*
Y1537360D01*
G01Y1535392D02*
Y1534211D01*
G01Y1541691D02*
Y1540510D01*
G01Y1547990D02*
Y1546809D01*
G01Y1544840D02*
Y1543659D01*
G01Y1551140D02*
Y1549959D01*
G01Y1557439D02*
Y1556258D01*
G01Y1554289D02*
Y1553108D01*
G01Y1560588D02*
Y1559407D01*
G01Y1566888D02*
Y1565707D01*
G01Y1563738D02*
Y1562557D01*
G01Y1570037D02*
Y1568856D01*
G01Y1576337D02*
Y1575155D01*
G01Y1573187D02*
Y1572006D01*
G01X1458405Y1519644D02*
Y1518463D01*
G01Y1522793D02*
Y1521612D01*
G01Y1529092D02*
Y1527911D01*
G01Y1525943D02*
Y1524762D01*
G01Y1532242D02*
Y1531061D01*
G01Y1538541D02*
Y1537360D01*
G01Y1535392D02*
Y1534211D01*
G01Y1541691D02*
Y1540510D01*
G01Y1547990D02*
Y1546809D01*
G01Y1544840D02*
Y1543659D01*
G01Y1551140D02*
Y1549959D01*
G01Y1557439D02*
Y1556258D01*
G01Y1554289D02*
Y1553108D01*
G01Y1560588D02*
Y1559407D01*
G01Y1566888D02*
Y1565707D01*
G01Y1563738D02*
Y1562557D01*
G01Y1570037D02*
Y1568856D01*
G01Y1576337D02*
Y1575155D01*
G01Y1573187D02*
Y1572006D01*
G01X1458295Y1519644D02*
Y1518463D01*
G01Y1522793D02*
Y1521612D01*
G01Y1529092D02*
Y1527911D01*
G01Y1525943D02*
Y1524762D01*
G01Y1532242D02*
Y1531061D01*
G01Y1538541D02*
Y1537360D01*
G01Y1535392D02*
Y1534211D01*
G01Y1541691D02*
Y1540510D01*
G01Y1547990D02*
Y1546809D01*
G01Y1544840D02*
Y1543659D01*
G01Y1551140D02*
Y1549959D01*
G01Y1557439D02*
Y1556258D01*
G01Y1554289D02*
Y1553108D01*
G01Y1560588D02*
Y1559407D01*
G01Y1566888D02*
Y1565707D01*
G01Y1563738D02*
Y1562557D01*
G01Y1570037D02*
Y1568856D01*
G01Y1576337D02*
Y1575155D01*
G01Y1573187D02*
Y1572006D01*
G01X1457929Y1519644D02*
Y1518463D01*
G01Y1522793D02*
Y1521612D01*
G01Y1529092D02*
Y1527911D01*
G01Y1525943D02*
Y1524762D01*
G01Y1532242D02*
Y1531061D01*
G01Y1538541D02*
Y1537360D01*
G01Y1535392D02*
Y1534211D01*
G01Y1541691D02*
Y1540510D01*
G01Y1547990D02*
Y1546809D01*
G01Y1544840D02*
Y1543659D01*
G01Y1551140D02*
Y1549959D01*
G01Y1557439D02*
Y1556258D01*
G01Y1554289D02*
Y1553108D01*
G01Y1560588D02*
Y1559407D01*
G01Y1566888D02*
Y1565707D01*
G01Y1563738D02*
Y1562557D01*
G01Y1570037D02*
Y1568856D01*
G01Y1576337D02*
Y1575155D01*
G01Y1573187D02*
Y1572006D01*
G01X1457732Y1518463D02*
Y1517872D01*
G01Y1524762D02*
Y1524171D01*
G01Y1521612D02*
Y1521022D01*
G01Y1523384D02*
Y1522793D01*
G01Y1520234D02*
Y1519644D01*
G01Y1527911D02*
Y1527321D01*
G01Y1526533D02*
Y1525943D01*
G01Y1531061D02*
Y1530470D01*
G01Y1532833D02*
Y1532242D01*
G01Y1529683D02*
Y1529092D01*
G01Y1537360D02*
Y1536770D01*
G01Y1534211D02*
Y1533620D01*
G01Y1535982D02*
Y1535392D01*
G01Y1540510D02*
Y1539919D01*
G01Y1542281D02*
Y1541691D01*
G01Y1539132D02*
Y1538541D01*
G01Y1546809D02*
Y1546218D01*
G01Y1543659D02*
Y1543069D01*
G01Y1545431D02*
Y1544840D01*
G01Y1549959D02*
Y1549368D01*
G01Y1551730D02*
Y1551140D01*
G01Y1548581D02*
Y1547990D01*
G01Y1556258D02*
Y1555667D01*
G01Y1553108D02*
Y1552518D01*
G01Y1554880D02*
Y1554289D01*
G01Y1559407D02*
Y1558817D01*
G01Y1561179D02*
Y1560588D01*
G01Y1558029D02*
Y1557439D01*
G01Y1565707D02*
Y1565116D01*
G01Y1562557D02*
Y1561966D01*
G01Y1564329D02*
Y1563738D01*
G01Y1568856D02*
Y1568266D01*
G01Y1570628D02*
Y1570037D01*
G01Y1567478D02*
Y1566888D01*
G01Y1575155D02*
Y1574565D01*
G01Y1572006D02*
Y1571415D01*
G01Y1573777D02*
Y1573187D01*
G01X1457535Y1518463D02*
Y1517872D01*
G01Y1524762D02*
Y1524171D01*
G01Y1521612D02*
Y1521022D01*
G01Y1523384D02*
Y1522793D01*
G01Y1520234D02*
Y1519644D01*
G01Y1527911D02*
Y1527321D01*
G01Y1526533D02*
Y1525943D01*
G01Y1531061D02*
Y1530470D01*
G01Y1532833D02*
Y1532242D01*
G01Y1529683D02*
Y1529092D01*
G01Y1537360D02*
Y1536770D01*
G01Y1534211D02*
Y1533620D01*
G01Y1535982D02*
Y1535392D01*
G01Y1540510D02*
Y1539919D01*
G01Y1542281D02*
Y1541691D01*
G01Y1539132D02*
Y1538541D01*
G01Y1546809D02*
Y1546218D01*
G01Y1543659D02*
Y1543069D01*
G01Y1545431D02*
Y1544840D01*
G01Y1549959D02*
Y1549368D01*
G01Y1551730D02*
Y1551140D01*
G01Y1548581D02*
Y1547990D01*
G01Y1556258D02*
Y1555667D01*
G01Y1553108D02*
Y1552518D01*
G01Y1554880D02*
Y1554289D01*
G01Y1559407D02*
Y1558817D01*
G01Y1561179D02*
Y1560588D01*
G01Y1558029D02*
Y1557439D01*
G01Y1565707D02*
Y1565116D01*
G01Y1562557D02*
Y1561966D01*
G01Y1564329D02*
Y1563738D01*
G01Y1568856D02*
Y1568266D01*
G01Y1570628D02*
Y1570037D01*
G01Y1567478D02*
Y1566888D01*
G01Y1575155D02*
Y1574565D01*
G01Y1572006D02*
Y1571415D01*
G01Y1573777D02*
Y1573187D01*
G01X1457220Y1922203D02*
Y1517478D01*
G01X1449937Y1696218D02*
Y1515116D01*
G01X1444212Y1519840D02*
Y1518266D01*
G01Y1522990D02*
Y1521415D01*
G01Y1529289D02*
Y1527714D01*
G01Y1526140D02*
Y1524565D01*
G01Y1532439D02*
Y1530864D01*
G01Y1538738D02*
Y1537163D01*
G01Y1535588D02*
Y1534014D01*
G01Y1541888D02*
Y1540313D01*
G01Y1548187D02*
Y1546612D01*
G01Y1545037D02*
Y1543463D01*
G01Y1551337D02*
Y1549762D01*
G01Y1554486D02*
Y1552911D01*
G01Y1560785D02*
Y1559211D01*
G01Y1557636D02*
Y1556061D01*
G01Y1563935D02*
Y1562360D01*
G01Y1570234D02*
Y1568659D01*
G01Y1567085D02*
Y1565510D01*
G01Y1573384D02*
Y1571809D01*
G01Y1576533D02*
Y1574959D01*
G01X1442684Y1519633D02*
Y1518473D01*
G01Y1522783D02*
Y1521623D01*
G01Y1529082D02*
Y1527922D01*
G01Y1525932D02*
Y1524772D01*
G01Y1532231D02*
Y1531072D01*
G01Y1538531D02*
Y1537371D01*
G01Y1535381D02*
Y1534221D01*
G01Y1541680D02*
Y1540520D01*
G01Y1547979D02*
Y1546820D01*
G01Y1544830D02*
Y1543670D01*
G01Y1551129D02*
Y1549969D01*
G01Y1557428D02*
Y1556268D01*
G01Y1554279D02*
Y1553119D01*
G01Y1560578D02*
Y1559418D01*
G01Y1566877D02*
Y1565717D01*
G01Y1563727D02*
Y1562568D01*
G01Y1570027D02*
Y1568867D01*
G01Y1576326D02*
Y1575166D01*
G01Y1573176D02*
Y1572016D01*
G01X1443243Y1560785D02*
X1442772Y1560490D01*
G01X1442684Y1560578D02*
X1442543Y1560490D01*
G01X1443243Y1563935D02*
X1442772Y1563640D01*
G01X1442684Y1563727D02*
X1442543Y1563640D01*
G01X1443243Y1567085D02*
X1442772Y1566789D01*
G01X1442684Y1566877D02*
X1442543Y1566789D01*
G01X1443243Y1570234D02*
X1442772Y1569939D01*
G01X1442684Y1570027D02*
X1442543Y1569939D01*
G01X1443243Y1573384D02*
X1442772Y1573088D01*
G01X1442684Y1573176D02*
X1442543Y1573088D01*
G01X1469507Y1518718D02*
X1469278Y1518463D01*
G01X1469507Y1521868D02*
X1469278Y1521612D01*
G01X1469507Y1525018D02*
X1469278Y1524762D01*
G01X1469507Y1528167D02*
X1469278Y1527911D01*
G01X1469507Y1531317D02*
X1469278Y1531061D01*
G01X1469507Y1534466D02*
X1469278Y1534211D01*
G01X1469507Y1537616D02*
X1469278Y1537360D01*
G01X1469507Y1540766D02*
X1469278Y1540510D01*
G01X1469507Y1543915D02*
X1469278Y1543659D01*
G01X1469507Y1547065D02*
X1469278Y1546809D01*
G01X1469507Y1550214D02*
X1469278Y1549959D01*
G01X1469507Y1553364D02*
X1469278Y1553108D01*
G01X1469507Y1556514D02*
X1469278Y1556258D01*
G01X1469507Y1559663D02*
X1469278Y1559407D01*
G01X1469507Y1562813D02*
X1469278Y1562557D01*
G01X1469507Y1565963D02*
X1469278Y1565707D01*
G01X1469507Y1569112D02*
X1469278Y1568856D01*
G01X1469507Y1572262D02*
X1469278Y1572006D01*
G01X1469507Y1575411D02*
X1469278Y1575155D01*
G01X1469855Y1518718D02*
X1469636Y1518448D01*
G01X1469855Y1521868D02*
X1469636Y1521598D01*
G01X1469855Y1525018D02*
X1469636Y1524748D01*
G01X1469855Y1528167D02*
X1469636Y1527897D01*
G01X1469855Y1531317D02*
X1469636Y1531047D01*
G01X1469855Y1534466D02*
X1469636Y1534196D01*
G01X1469855Y1537616D02*
X1469636Y1537346D01*
G01X1469855Y1540766D02*
X1469636Y1540496D01*
G01X1469855Y1543915D02*
X1469636Y1543645D01*
G01X1469855Y1547065D02*
X1469636Y1546795D01*
G01X1469855Y1550214D02*
X1469636Y1549944D01*
G01X1469855Y1553364D02*
X1469636Y1553094D01*
G01X1469855Y1556514D02*
X1469636Y1556244D01*
G01X1469855Y1559663D02*
X1469636Y1559393D01*
G01X1469855Y1562813D02*
X1469636Y1562543D01*
G01X1469855Y1565963D02*
X1469636Y1565692D01*
G01X1469855Y1569112D02*
X1469636Y1568842D01*
G01X1469855Y1572262D02*
X1469636Y1571992D01*
G01X1469855Y1575411D02*
X1469636Y1575141D01*
G01X1439047Y1576200D02*
X1440094Y1576212D01*
G01X1439047Y1576200D02*
X1440094Y1576212D01*
G01X1438785Y1576200D02*
X1436420Y1576174D01*
G01X1437751Y1576186D02*
X1439047Y1576200D01*
G01X1440094Y1576212D02*
X1441007Y1576222D01*
G01X1439047Y1578441D02*
X1442543Y1578403D01*
G01X1437751Y1578456D02*
X1441007Y1578420D01*
G01X1438785Y1578441D02*
X1436420Y1578468D01*
G01X1441235Y1578420D02*
X1442772Y1578403D01*
G01X1441235Y1578420D02*
X1438785Y1578441D01*
G01X1439047D02*
X1438785D01*
G01X1441235Y1578420D02*
X1441007D01*
G01X1441235Y1576222D02*
X1441007D01*
G01X1439047Y1576200D02*
X1438785D01*
G01X1440094Y1576212D02*
X1438785Y1576200D01*
G01X1441235Y1576222D02*
X1440094Y1576212D01*
G01X1437751Y1576186D02*
X1436420Y1576174D01*
G01X1442543Y1576238D02*
X1441007Y1576222D01*
G01X1441235D02*
X1442772Y1576238D01*
G01X1441235Y1579371D02*
Y1578420D01*
G01X1441007Y1579371D02*
Y1578420D01*
G01X1439047Y1579350D02*
Y1578441D01*
G01X1438785Y1579350D02*
Y1578441D01*
G01X1439047Y1647733D02*
X1442543Y1647695D01*
G01X1437751Y1647747D02*
X1441007Y1647711D01*
G01X1439047Y1644583D02*
X1442543Y1644545D01*
G01X1437751Y1644597D02*
X1441007Y1644562D01*
G01X1439047Y1641434D02*
X1442543Y1641396D01*
G01X1437751Y1641448D02*
X1441007Y1641412D01*
G01X1439047Y1638284D02*
X1442543Y1638246D01*
G01X1437751Y1638298D02*
X1441007Y1638262D01*
G01X1439047Y1635134D02*
X1442543Y1635096D01*
G01X1437751Y1635149D02*
X1441007Y1635113D01*
G01X1439047Y1631985D02*
X1442543Y1631947D01*
G01X1437751Y1631999D02*
X1441007Y1631963D01*
G01X1439047Y1628835D02*
X1442543Y1628797D01*
G01X1437751Y1628849D02*
X1441007Y1628814D01*
G01X1439047Y1625686D02*
X1442543Y1625648D01*
G01X1437751Y1625700D02*
X1441007Y1625664D01*
G01X1439047Y1622536D02*
X1442543Y1622498D01*
G01X1437751Y1622550D02*
X1441007Y1622514D01*
G01X1439047Y1619386D02*
X1442543Y1619348D01*
G01X1437751Y1619401D02*
X1441007Y1619365D01*
G01X1439047Y1616237D02*
X1442543Y1616199D01*
G01X1437751Y1616251D02*
X1441007Y1616215D01*
G01X1439047Y1613087D02*
X1442543Y1613049D01*
G01X1437751Y1613101D02*
X1441007Y1613066D01*
G01X1439047Y1609937D02*
X1442543Y1609900D01*
G01X1437751Y1609952D02*
X1441007Y1609916D01*
G01X1439047Y1606788D02*
X1442543Y1606750D01*
G01X1437751Y1606802D02*
X1441007Y1606766D01*
G01X1439047Y1603638D02*
X1442543Y1603600D01*
G01X1437751Y1603653D02*
X1441007Y1603617D01*
G01X1439047Y1600489D02*
X1442543Y1600451D01*
G01X1437751Y1600503D02*
X1441007Y1600467D01*
G01X1439047Y1597339D02*
X1442543Y1597301D01*
G01X1437751Y1597353D02*
X1441007Y1597318D01*
G01X1439047Y1594189D02*
X1442543Y1594151D01*
G01X1437751Y1594204D02*
X1441007Y1594168D01*
G01X1439047Y1591040D02*
X1442543Y1591002D01*
G01X1437751Y1591054D02*
X1441007Y1591018D01*
G01X1439047Y1587890D02*
X1442543Y1587852D01*
G01X1437751Y1587905D02*
X1441007Y1587869D01*
G01X1438785Y1647733D02*
X1436420Y1647759D01*
G01X1438785Y1644583D02*
X1436420Y1644609D01*
G01X1438785Y1641434D02*
X1436420Y1641460D01*
G01X1438785Y1638284D02*
X1436420Y1638310D01*
G01X1438785Y1635134D02*
X1436420Y1635160D01*
G01X1438785Y1631985D02*
X1436420Y1632011D01*
G01X1438785Y1628835D02*
X1436420Y1628861D01*
G01X1438785Y1625686D02*
X1436420Y1625712D01*
G01X1438785Y1622536D02*
X1436420Y1622562D01*
G01X1438785Y1619386D02*
X1436420Y1619412D01*
G01X1438785Y1616237D02*
X1436420Y1616263D01*
G01X1438785Y1613087D02*
X1436420Y1613113D01*
G01X1438785Y1609938D02*
X1436420Y1609964D01*
G01X1438785Y1606788D02*
X1436420Y1606814D01*
G01X1438785Y1603638D02*
X1436420Y1603664D01*
G01X1438785Y1600489D02*
X1436420Y1600515D01*
G01X1438785Y1597339D02*
X1436420Y1597365D01*
G01X1438785Y1594190D02*
X1436420Y1594216D01*
G01X1438785Y1591040D02*
X1436420Y1591066D01*
G01X1438785Y1587890D02*
X1436420Y1587916D01*
G01X1441235Y1647711D02*
X1442772Y1647695D01*
G01X1441235Y1644562D02*
X1442772Y1644545D01*
G01X1441235Y1641412D02*
X1442772Y1641396D01*
G01X1441235Y1638262D02*
X1442772Y1638246D01*
G01X1441235Y1635113D02*
X1442772Y1635096D01*
G01X1441235Y1631963D02*
X1442772Y1631947D01*
G01X1441235Y1628814D02*
X1442772Y1628797D01*
G01X1441235Y1625664D02*
X1442772Y1625648D01*
G01X1441235Y1622514D02*
X1442772Y1622498D01*
G01X1441235Y1619365D02*
X1442772Y1619348D01*
G01X1441235Y1616215D02*
X1442772Y1616199D01*
G01X1441235Y1613066D02*
X1442772Y1613049D01*
G01X1441235Y1609916D02*
X1442772Y1609900D01*
G01X1441235Y1606766D02*
X1442772Y1606750D01*
G01X1441235Y1603617D02*
X1442772Y1603600D01*
G01X1441235Y1600467D02*
X1442772Y1600451D01*
G01X1441235Y1597318D02*
X1442772Y1597301D01*
G01X1441235Y1594168D02*
X1442772Y1594151D01*
G01X1441235Y1591018D02*
X1442772Y1591002D01*
G01X1441235Y1587869D02*
X1442772Y1587852D01*
G01X1441235Y1647711D02*
X1438785Y1647733D01*
G01X1437751Y1647747D02*
X1436420Y1647759D01*
G01X1441235Y1644562D02*
X1438785Y1644583D01*
G01X1437751Y1644597D02*
X1436420Y1644609D01*
G01X1441235Y1641412D02*
X1438785Y1641434D01*
G01X1437751Y1641448D02*
X1436420Y1641460D01*
G01X1441235Y1638262D02*
X1438785Y1638284D01*
G01X1437751Y1638298D02*
X1436420Y1638310D01*
G01X1441235Y1635113D02*
X1438785Y1635134D01*
G01X1437751Y1635149D02*
X1436420Y1635160D01*
G01X1441235Y1631963D02*
X1438785Y1631985D01*
G01X1437751Y1631999D02*
X1436420Y1632011D01*
G01X1441235Y1628814D02*
X1438785Y1628835D01*
G01X1437751Y1628849D02*
X1436420Y1628861D01*
G01X1441235Y1625664D02*
X1438785Y1625686D01*
G01X1437751Y1625700D02*
X1436420Y1625712D01*
G01X1441235Y1622514D02*
X1438785Y1622536D01*
G01X1437751Y1622550D02*
X1436420Y1622562D01*
G01X1441235Y1619365D02*
X1438785Y1619386D01*
G01X1437751Y1619401D02*
X1436420Y1619412D01*
G01X1441235Y1616215D02*
X1438785Y1616237D01*
G01X1437751Y1616251D02*
X1436420Y1616263D01*
G01X1441235Y1613066D02*
X1438785Y1613087D01*
G01X1437751Y1613101D02*
X1436420Y1613113D01*
G01X1441235Y1609916D02*
X1438785Y1609938D01*
G01X1437751Y1609952D02*
X1436420Y1609964D01*
G01X1441235Y1606766D02*
X1438785Y1606788D01*
G01X1437751Y1606802D02*
X1436420Y1606814D01*
G01X1441235Y1603617D02*
X1438785Y1603638D01*
G01X1437751Y1603653D02*
X1436420Y1603664D01*
G01X1441235Y1600467D02*
X1438785Y1600489D01*
G01X1437751Y1600503D02*
X1436420Y1600515D01*
G01X1441235Y1597318D02*
X1438785Y1597339D01*
G01X1437751Y1597353D02*
X1436420Y1597365D01*
G01X1441235Y1594168D02*
X1438785Y1594190D01*
G01X1437751Y1594204D02*
X1436420Y1594216D01*
G01X1441235Y1591018D02*
X1438785Y1591040D01*
G01X1437751Y1591054D02*
X1436420Y1591066D01*
G01X1441235Y1587869D02*
X1438785Y1587890D01*
G01X1437751Y1587905D02*
X1436420Y1587916D01*
G01X1436614Y1647826D02*
X1436111D01*
G01X1441472D02*
X1437284D01*
G01X1439047Y1647733D02*
X1438785D01*
G01X1441235Y1647711D02*
X1441007D01*
G01X1441472Y1647006D02*
X1436111D01*
G01X1441235Y1645513D02*
X1441007D01*
G01X1439047Y1645491D02*
X1438785D01*
G01X1439047Y1644583D02*
X1438785D01*
G01X1441235Y1644562D02*
X1441007D01*
G01X1441235Y1642363D02*
X1441007D01*
G01X1439047Y1642342D02*
X1438785D01*
G01X1439047Y1641434D02*
X1438785D01*
G01X1441235Y1641412D02*
X1441007D01*
G01X1441235Y1639214D02*
X1441007D01*
G01X1439047Y1639192D02*
X1438785D01*
G01X1439047Y1638284D02*
X1438785D01*
G01X1441235Y1638262D02*
X1441007D01*
G01X1441235Y1636064D02*
X1441007D01*
G01X1439047Y1636043D02*
X1438785D01*
G01X1439047Y1635134D02*
X1438785D01*
G01X1441235Y1635113D02*
X1441007D01*
G01X1441235Y1632915D02*
X1441007D01*
G01X1439047Y1632893D02*
X1438785D01*
G01X1439047Y1631985D02*
X1438785D01*
G01X1441235Y1631963D02*
X1441007D01*
G01X1441235Y1629765D02*
X1441007D01*
G01X1439047Y1629743D02*
X1438785D01*
G01X1439047Y1628835D02*
X1438785D01*
G01X1441235Y1628814D02*
X1441007D01*
G01X1441235Y1626615D02*
X1441007D01*
G01X1439047Y1626594D02*
X1438785D01*
G01X1439047Y1625686D02*
X1438785D01*
G01X1441235Y1625664D02*
X1441007D01*
G01X1441235Y1623466D02*
X1441007D01*
G01X1439047Y1623444D02*
X1438785D01*
G01X1439047Y1622536D02*
X1438785D01*
G01X1441235Y1622514D02*
X1441007D01*
G01X1441235Y1620316D02*
X1441007D01*
G01X1439047Y1620295D02*
X1438785D01*
G01X1439047Y1619386D02*
X1438785D01*
G01X1441235Y1619365D02*
X1441007D01*
G01X1441235Y1617167D02*
X1441007D01*
G01X1439047Y1617145D02*
X1438785D01*
G01X1439047Y1616237D02*
X1438785D01*
G01X1441235Y1616215D02*
X1441007D01*
G01X1441235Y1614017D02*
X1441007D01*
G01X1439047Y1613995D02*
X1438785D01*
G01X1439047Y1613087D02*
X1438785D01*
G01X1441235Y1613066D02*
X1441007D01*
G01X1441235Y1610867D02*
X1441007D01*
G01X1439047Y1610846D02*
X1438785D01*
G01X1439047Y1609938D02*
X1438785D01*
G01X1441235Y1609916D02*
X1441007D01*
G01X1441235Y1607718D02*
X1441007D01*
G01X1439047Y1607696D02*
X1438785D01*
G01X1439047Y1606788D02*
X1438785D01*
G01X1441235Y1606766D02*
X1441007D01*
G01X1441235Y1604568D02*
X1441007D01*
G01X1439047Y1604547D02*
X1438785D01*
G01X1439047Y1603638D02*
X1438785D01*
G01X1441235Y1603617D02*
X1441007D01*
G01X1441235Y1601418D02*
X1441007D01*
G01X1439047Y1601397D02*
X1438785D01*
G01X1439047Y1600489D02*
X1438785D01*
G01X1441235Y1600467D02*
X1441007D01*
G01X1441235Y1598269D02*
X1441007D01*
G01X1439047Y1598247D02*
X1438785D01*
G01X1439047Y1597339D02*
X1438785D01*
G01X1441235Y1597318D02*
X1441007D01*
G01X1441235Y1595119D02*
X1441007D01*
G01X1439047Y1595098D02*
X1438785D01*
G01X1439047Y1594190D02*
X1438785D01*
G01X1441235Y1594168D02*
X1441007D01*
G01X1441235Y1591970D02*
X1441007D01*
G01X1439047Y1591948D02*
X1438785D01*
G01X1439047Y1591040D02*
X1438785D01*
G01X1441235Y1591018D02*
X1441007D01*
G01X1441235Y1588820D02*
X1441007D01*
G01X1439047Y1588798D02*
X1438785D01*
G01X1439047Y1587890D02*
X1438785D01*
G01X1441235Y1587869D02*
X1441007D01*
G01X1441235Y1585670D02*
X1441007D01*
G01X1439047Y1585649D02*
X1438785D01*
G01X1439047Y1584741D02*
X1438785D01*
G01X1441235Y1584719D02*
X1441007D01*
G01X1441235Y1582521D02*
X1441007D01*
G01X1439047Y1582499D02*
X1438785D01*
G01X1440094Y1645503D02*
X1438785Y1645491D01*
G01X1441235Y1645513D02*
X1440094Y1645503D01*
G01Y1642353D02*
X1438785Y1642342D01*
G01X1441235Y1642363D02*
X1440094Y1642353D01*
G01Y1639204D02*
X1438785Y1639192D01*
G01X1441235Y1639214D02*
X1440094Y1639204D01*
G01Y1636054D02*
X1438785Y1636043D01*
G01X1441235Y1636064D02*
X1440094Y1636054D01*
G01Y1632905D02*
X1438785Y1632893D01*
G01X1441235Y1632915D02*
X1440094Y1632905D01*
G01Y1629755D02*
X1438785Y1629743D01*
G01X1441235Y1629765D02*
X1440094Y1629755D01*
G01Y1626605D02*
X1438785Y1626594D01*
G01X1441235Y1626615D02*
X1440094Y1626605D01*
G01Y1623456D02*
X1438785Y1623444D01*
G01X1441235Y1623466D02*
X1440094Y1623456D01*
G01Y1620306D02*
X1438785Y1620295D01*
G01X1441235Y1620316D02*
X1440094Y1620306D01*
G01Y1617157D02*
X1438785Y1617145D01*
G01X1441235Y1617167D02*
X1440094Y1617157D01*
G01Y1614007D02*
X1438785Y1613995D01*
G01X1441235Y1614017D02*
X1440094Y1614007D01*
G01Y1610857D02*
X1438785Y1610846D01*
G01X1441235Y1610867D02*
X1440094Y1610857D01*
G01Y1607708D02*
X1438785Y1607696D01*
G01X1441235Y1607718D02*
X1440094Y1607708D01*
G01Y1604558D02*
X1438785Y1604547D01*
G01X1441235Y1604568D02*
X1440094Y1604558D01*
G01Y1601408D02*
X1438785Y1601397D01*
G01X1441235Y1601418D02*
X1440094Y1601408D01*
G01Y1598259D02*
X1438785Y1598247D01*
G01X1441235Y1598269D02*
X1440094Y1598259D01*
G01Y1595109D02*
X1438785Y1595098D01*
G01X1441235Y1595119D02*
X1440094Y1595109D01*
G01Y1591960D02*
X1438785Y1591948D01*
G01X1441235Y1591970D02*
X1440094Y1591960D01*
G01Y1588810D02*
X1438785Y1588798D01*
G01X1441235Y1588820D02*
X1440094Y1588810D01*
G01Y1585660D02*
X1438785Y1585649D01*
G01X1441235Y1585670D02*
X1440094Y1585660D01*
G01Y1582511D02*
X1438785Y1582499D01*
G01X1441235Y1582521D02*
X1440094Y1582511D01*
G01Y1579361D02*
X1438785Y1579350D01*
G01X1441235Y1579371D02*
X1440094Y1579361D01*
G01X1437751Y1645477D02*
X1436420Y1645465D01*
G01X1437751Y1642328D02*
X1436420Y1642316D01*
G01X1437751Y1639178D02*
X1436420Y1639166D01*
G01X1437751Y1636028D02*
X1436420Y1636017D01*
G01X1437751Y1632879D02*
X1436420Y1632867D01*
G01X1437751Y1629729D02*
X1436420Y1629717D01*
G01X1437751Y1626579D02*
X1436420Y1626568D01*
G01X1437751Y1623430D02*
X1436420Y1623418D01*
G01X1437751Y1620280D02*
X1436420Y1620268D01*
G01X1437751Y1617131D02*
X1436420Y1617119D01*
G01X1437751Y1613981D02*
X1436420Y1613969D01*
G01X1437751Y1610831D02*
X1436420Y1610820D01*
G01X1437751Y1607682D02*
X1436420Y1607670D01*
G01X1437751Y1604532D02*
X1436420Y1604520D01*
G01X1437751Y1601383D02*
X1436420Y1601371D01*
G01X1437751Y1598233D02*
X1436420Y1598221D01*
G01X1437751Y1595083D02*
X1436420Y1595072D01*
G01X1437751Y1591934D02*
X1436420Y1591922D01*
G01X1437751Y1588784D02*
X1436420Y1588772D01*
G01X1437751Y1585635D02*
X1436420Y1585623D01*
G01X1437751Y1582485D02*
X1436420Y1582473D01*
G01X1437751Y1579335D02*
X1436420Y1579324D01*
G01X1442543Y1645529D02*
X1441007Y1645513D01*
G01X1442543Y1645529D02*
X1439047Y1645491D01*
G01X1441235Y1645513D02*
X1442772Y1645529D01*
G01X1442543Y1642380D02*
X1441007Y1642363D01*
G01X1442543Y1642380D02*
X1439047Y1642342D01*
G01X1441235Y1642363D02*
X1442772Y1642380D01*
G01X1442543Y1639230D02*
X1441007Y1639214D01*
G01X1442543Y1639230D02*
X1439047Y1639192D01*
G01X1441235Y1639214D02*
X1442772Y1639230D01*
G01X1442543Y1636081D02*
X1441007Y1636064D01*
G01X1442543Y1636081D02*
X1439047Y1636043D01*
G01X1441235Y1636064D02*
X1442772Y1636081D01*
G01X1442543Y1632931D02*
X1441007Y1632915D01*
G01X1442543Y1632931D02*
X1439047Y1632893D01*
G01X1441235Y1632915D02*
X1442772Y1632931D01*
G01X1442543Y1629781D02*
X1441007Y1629765D01*
G01X1442543Y1629781D02*
X1439047Y1629743D01*
G01X1441235Y1629765D02*
X1442772Y1629781D01*
G01X1442543Y1626632D02*
X1441007Y1626615D01*
G01X1442543Y1626632D02*
X1439047Y1626594D01*
G01X1441235Y1626615D02*
X1442772Y1626632D01*
G01X1442543Y1623482D02*
X1441007Y1623466D01*
G01X1442543Y1623482D02*
X1439047Y1623444D01*
G01X1441235Y1623466D02*
X1442772Y1623482D01*
G01X1442543Y1620333D02*
X1441007Y1620316D01*
G01X1442543Y1620333D02*
X1439047Y1620295D01*
G01X1441235Y1620316D02*
X1442772Y1620333D01*
G01X1442543Y1617183D02*
X1441007Y1617167D01*
G01X1442543Y1617183D02*
X1439047Y1617145D01*
G01X1441235Y1617167D02*
X1442772Y1617183D01*
G01X1442543Y1614033D02*
X1441007Y1614017D01*
G01X1442543Y1614033D02*
X1439047Y1613995D01*
G01X1441235Y1614017D02*
X1442772Y1614033D01*
G01X1442543Y1610884D02*
X1441007Y1610867D01*
G01X1442543Y1610884D02*
X1439047Y1610846D01*
G01X1441235Y1610867D02*
X1442772Y1610884D01*
G01X1442543Y1607734D02*
X1441007Y1607718D01*
G01X1442543Y1607734D02*
X1439047Y1607696D01*
G01X1441235Y1607718D02*
X1442772Y1607734D01*
G01X1442543Y1604585D02*
X1441007Y1604568D01*
G01X1442543Y1604585D02*
X1439047Y1604547D01*
G01X1441235Y1604568D02*
X1442772Y1604585D01*
G01X1442543Y1601435D02*
X1441007Y1601418D01*
G01X1442543Y1601435D02*
X1439047Y1601397D01*
G01X1441235Y1601418D02*
X1442772Y1601435D01*
G01X1442543Y1598285D02*
X1441007Y1598269D01*
G01X1442543Y1598285D02*
X1439047Y1598247D01*
G01X1441235Y1598269D02*
X1442772Y1598285D01*
G01X1442543Y1595136D02*
X1441007Y1595119D01*
G01X1442543Y1595136D02*
X1439047Y1595098D01*
G01X1441235Y1595119D02*
X1442772Y1595136D01*
G01X1442543Y1591986D02*
X1441007Y1591970D01*
G01X1442543Y1591986D02*
X1439047Y1591948D01*
G01X1441235Y1591970D02*
X1442772Y1591986D01*
G01X1442543Y1588837D02*
X1441007Y1588820D01*
G01X1442543Y1588837D02*
X1439047Y1588799D01*
G01X1441235Y1588820D02*
X1442772Y1588837D01*
G01X1442543Y1585687D02*
X1441007Y1585670D01*
G01X1442543Y1585687D02*
X1439047Y1585649D01*
G01X1441235Y1585670D02*
X1442772Y1585687D01*
G01X1442543Y1582537D02*
X1441007Y1582521D01*
G01X1442543Y1582537D02*
X1439047Y1582499D01*
G01X1441235Y1582521D02*
X1442772Y1582537D01*
G01X1442543Y1579388D02*
X1441007Y1579371D01*
G01X1442543Y1579388D02*
X1439047Y1579350D01*
G01X1441235Y1579371D02*
X1442772Y1579388D01*
G01X1439047Y1645491D02*
X1440094Y1645503D01*
G01X1438785Y1645491D02*
X1436420Y1645465D01*
G01X1437751Y1645477D02*
X1439047Y1645491D01*
G01Y1642342D02*
X1440094Y1642353D01*
G01X1438785Y1642342D02*
X1436420Y1642316D01*
G01X1437751Y1642328D02*
X1439047Y1642342D01*
G01Y1639192D02*
X1440094Y1639204D01*
G01X1438785Y1639192D02*
X1436420Y1639166D01*
G01X1437751Y1639178D02*
X1439047Y1639192D01*
G01Y1636043D02*
X1440094Y1636054D01*
G01X1438785Y1636043D02*
X1436420Y1636017D01*
G01X1437751Y1636028D02*
X1439047Y1636043D01*
G01Y1632893D02*
X1440094Y1632905D01*
G01X1438785Y1632893D02*
X1436420Y1632867D01*
G01X1437751Y1632879D02*
X1439047Y1632893D01*
G01Y1629743D02*
X1440094Y1629755D01*
G01X1438785Y1629743D02*
X1436420Y1629717D01*
G01X1437751Y1629729D02*
X1439047Y1629743D01*
G01Y1626594D02*
X1440094Y1626605D01*
G01X1438785Y1626594D02*
X1436420Y1626568D01*
G01X1437751Y1626579D02*
X1439047Y1626594D01*
G01Y1623444D02*
X1440094Y1623456D01*
G01X1438785Y1623444D02*
X1436420Y1623418D01*
G01X1437751Y1623430D02*
X1439047Y1623444D01*
G01Y1620295D02*
X1440094Y1620306D01*
G01X1438785Y1620295D02*
X1436420Y1620268D01*
G01X1437751Y1620280D02*
X1439047Y1620295D01*
G01Y1617145D02*
X1440094Y1617157D01*
G01X1438785Y1617145D02*
X1436420Y1617119D01*
G01X1437751Y1617131D02*
X1439047Y1617145D01*
G01Y1613995D02*
X1440094Y1614007D01*
G01X1438785Y1613995D02*
X1436420Y1613969D01*
G01X1437751Y1613981D02*
X1439047Y1613995D01*
G01Y1610846D02*
X1440094Y1610857D01*
G01X1438785Y1610846D02*
X1436420Y1610820D01*
G01X1437751Y1610831D02*
X1439047Y1610846D01*
G01Y1607696D02*
X1440094Y1607708D01*
G01X1438785Y1607696D02*
X1436420Y1607670D01*
G01X1437751Y1607682D02*
X1439047Y1607696D01*
G01Y1604547D02*
X1440094Y1604558D01*
G01X1438785Y1604547D02*
X1436420Y1604520D01*
G01X1437751Y1604532D02*
X1439047Y1604547D01*
G01Y1601397D02*
X1440094Y1601408D01*
G01X1438785Y1601397D02*
X1436420Y1601371D01*
G01X1437751Y1601383D02*
X1439047Y1601397D01*
G01Y1598247D02*
X1440094Y1598259D01*
G01X1438785Y1598247D02*
X1436420Y1598221D01*
G01X1437751Y1598233D02*
X1439047Y1598247D01*
G01Y1595098D02*
X1440094Y1595109D01*
G01X1438785Y1595098D02*
X1436420Y1595072D01*
G01X1437751Y1595083D02*
X1439047Y1595098D01*
G01Y1591948D02*
X1440094Y1591960D01*
G01X1438785Y1591948D02*
X1436420Y1591922D01*
G01X1437751Y1591934D02*
X1439047Y1591948D01*
G01Y1588798D02*
X1440094Y1588810D01*
G01X1438785Y1588798D02*
X1436420Y1588772D01*
G01X1437751Y1588784D02*
X1439047Y1588798D01*
G01Y1585649D02*
X1440094Y1585660D01*
G01X1438785Y1585649D02*
X1436420Y1585623D01*
G01X1437751Y1585635D02*
X1439047Y1585649D01*
G01Y1582499D02*
X1440094Y1582511D01*
G01X1438785Y1582499D02*
X1436420Y1582473D01*
G01X1437751Y1582485D02*
X1439047Y1582499D01*
G01Y1579350D02*
X1440094Y1579361D01*
G01X1438785Y1579350D02*
X1436420Y1579324D01*
G01X1437751Y1579335D02*
X1439047Y1579350D01*
G01Y1584741D02*
X1442543Y1584703D01*
G01X1437751Y1584755D02*
X1441007Y1584719D01*
G01X1439047Y1581591D02*
X1442543Y1581553D01*
G01X1437751Y1581605D02*
X1441007Y1581570D01*
G01X1438785Y1584741D02*
X1436420Y1584767D01*
G01X1438785Y1581591D02*
X1436420Y1581617D01*
G01X1441235Y1584719D02*
X1442772Y1584703D01*
G01X1441235Y1581570D02*
X1442772Y1581553D01*
G01X1441235Y1584719D02*
X1438785Y1584741D01*
G01X1437751Y1584755D02*
X1436420Y1584767D01*
G01X1441235Y1581570D02*
X1438785Y1581591D01*
G01X1437751Y1581605D02*
X1436420Y1581617D01*
G01X1437751Y1578456D02*
X1436420Y1578468D01*
G01X1439047Y1581591D02*
X1438785D01*
G01X1441235Y1581570D02*
X1441007D01*
G01X1441235Y1579371D02*
X1441007D01*
G01X1439047Y1579350D02*
X1438785D01*
G01X1433598Y1641756D02*
X1441472Y1639132D01*
G01Y1640116D02*
X1439462Y1640772D01*
G01X1434268Y1642413D02*
X1438792Y1640936D01*
G01X1436949Y1648154D02*
X1437284Y1647826D01*
G01X1436279Y1648154D02*
X1436614Y1647826D01*
G01X1436781Y1648646D02*
X1436949Y1648154D01*
G01X1436111Y1648646D02*
X1436279Y1648154D01*
G01X1441472Y1644709D02*
X1439462Y1644053D01*
G01X1438792Y1643889D02*
X1434268Y1642413D01*
G01X1441235Y1585670D02*
Y1584719D01*
G01Y1582521D02*
Y1581570D01*
G01Y1588820D02*
Y1587869D01*
G01Y1591970D02*
Y1591018D01*
G01Y1598269D02*
Y1597318D01*
G01Y1595119D02*
Y1594168D01*
G01Y1601418D02*
Y1600467D01*
G01Y1607718D02*
Y1606766D01*
G01Y1604568D02*
Y1603617D01*
G01Y1610867D02*
Y1609916D01*
G01Y1617166D02*
Y1616215D01*
G01Y1614017D02*
Y1613066D01*
G01Y1620316D02*
Y1619365D01*
G01Y1626615D02*
Y1625664D01*
G01Y1623466D02*
Y1622514D01*
G01Y1629765D02*
Y1628814D01*
G01Y1636064D02*
Y1635113D01*
G01Y1632914D02*
Y1631963D01*
G01Y1639214D02*
Y1638262D01*
G01Y1645513D02*
Y1644562D01*
G01Y1642363D02*
Y1641412D01*
G01Y1648663D02*
Y1647711D01*
G01X1441007Y1585670D02*
Y1584719D01*
G01Y1582521D02*
Y1581570D01*
G01Y1588820D02*
Y1587869D01*
G01Y1591970D02*
Y1591018D01*
G01Y1598269D02*
Y1597318D01*
G01Y1595119D02*
Y1594168D01*
G01Y1601418D02*
Y1600467D01*
G01Y1607718D02*
Y1606766D01*
G01Y1604568D02*
Y1603617D01*
G01Y1610867D02*
Y1609916D01*
G01Y1617167D02*
Y1616215D01*
G01Y1614017D02*
Y1613066D01*
G01Y1620316D02*
Y1619365D01*
G01Y1626615D02*
Y1625664D01*
G01Y1623466D02*
Y1622514D01*
G01Y1629765D02*
Y1628814D01*
G01Y1636064D02*
Y1635113D01*
G01Y1632915D02*
Y1631963D01*
G01Y1639214D02*
Y1638262D01*
G01Y1645513D02*
Y1644562D01*
G01Y1642363D02*
Y1641412D01*
G01Y1648663D02*
Y1647711D01*
G01X1441472Y1645693D02*
X1433598Y1643069D01*
G01X1439462Y1644053D02*
Y1640772D01*
G01X1439047Y1585649D02*
Y1584741D01*
G01Y1582499D02*
Y1581591D01*
G01Y1588799D02*
Y1587890D01*
G01Y1591948D02*
Y1591040D01*
G01Y1598247D02*
Y1597339D01*
G01Y1595098D02*
Y1594189D01*
G01Y1601397D02*
Y1600489D01*
G01Y1607696D02*
Y1606788D01*
G01Y1604547D02*
Y1603638D01*
G01Y1610846D02*
Y1609937D01*
G01Y1617145D02*
Y1616237D01*
G01Y1613995D02*
Y1613087D01*
G01Y1620295D02*
Y1619386D01*
G01Y1626594D02*
Y1625686D01*
G01Y1623444D02*
Y1622536D01*
G01Y1629743D02*
Y1628835D01*
G01Y1636043D02*
Y1635134D01*
G01Y1632893D02*
Y1631985D01*
G01Y1639192D02*
Y1638284D01*
G01Y1645491D02*
Y1644583D01*
G01Y1642342D02*
Y1641434D01*
G01Y1648641D02*
Y1647733D01*
G01X1438792Y1643889D02*
Y1640936D01*
G01X1438785Y1585649D02*
Y1584741D01*
G01Y1582499D02*
Y1581591D01*
G01Y1588799D02*
Y1587890D01*
G01Y1591948D02*
Y1591040D01*
G01Y1598247D02*
Y1597339D01*
G01Y1595098D02*
Y1594190D01*
G01Y1601397D02*
Y1600489D01*
G01Y1607696D02*
Y1606788D01*
G01Y1604547D02*
Y1603638D01*
G01Y1610846D02*
Y1609938D01*
G01Y1617145D02*
Y1616237D01*
G01Y1613995D02*
Y1613087D01*
G01Y1620295D02*
Y1619386D01*
G01Y1626594D02*
Y1625686D01*
G01Y1623444D02*
Y1622536D01*
G01Y1629743D02*
Y1628835D01*
G01Y1636043D02*
Y1635134D01*
G01Y1632893D02*
Y1631985D01*
G01Y1639192D02*
Y1638284D01*
G01Y1645491D02*
Y1644583D01*
G01Y1642342D02*
Y1641434D01*
G01Y1648641D02*
Y1647733D01*
G01X1437751Y1579329D02*
Y1578462D01*
G01Y1585629D02*
Y1584761D01*
G01Y1582479D02*
Y1581611D01*
G01Y1588778D02*
Y1587910D01*
G01Y1591928D02*
Y1591060D01*
G01Y1598227D02*
Y1597359D01*
G01Y1595078D02*
Y1594210D01*
G01Y1601377D02*
Y1600509D01*
G01Y1607676D02*
Y1606808D01*
G01Y1604526D02*
Y1603659D01*
G01Y1610826D02*
Y1609958D01*
G01Y1617125D02*
Y1616257D01*
G01Y1613975D02*
Y1613107D01*
G01Y1620274D02*
Y1619407D01*
G01Y1626574D02*
Y1625706D01*
G01Y1623424D02*
Y1622556D01*
G01Y1629723D02*
Y1628855D01*
G01Y1636022D02*
Y1635155D01*
G01Y1632873D02*
Y1632005D01*
G01Y1639172D02*
Y1638304D01*
G01Y1645471D02*
Y1644603D01*
G01Y1642322D02*
Y1641454D01*
G01Y1648621D02*
Y1647753D01*
G01X1436420Y1579324D02*
Y1578468D01*
G01Y1585623D02*
Y1584767D01*
G01Y1582473D02*
Y1581617D01*
G01Y1588772D02*
Y1587916D01*
G01Y1591922D02*
Y1591066D01*
G01Y1598221D02*
Y1597365D01*
G01Y1595072D02*
Y1594216D01*
G01Y1601371D02*
Y1600515D01*
G01Y1607670D02*
Y1606814D01*
G01Y1604520D02*
Y1603664D01*
G01Y1610820D02*
Y1609964D01*
G01Y1617119D02*
Y1616263D01*
G01Y1613969D02*
Y1613113D01*
G01Y1620268D02*
Y1619412D01*
G01Y1626568D02*
Y1625712D01*
G01Y1623418D02*
Y1622562D01*
G01Y1629717D02*
Y1628861D01*
G01Y1636017D02*
Y1635160D01*
G01Y1632867D02*
Y1632011D01*
G01Y1639166D02*
Y1638310D01*
G01Y1645465D02*
Y1644609D01*
G01Y1642316D02*
Y1641460D01*
G01Y1648615D02*
Y1647759D01*
G01X1436111Y1647826D02*
Y1647006D01*
G01X1433598Y1643069D02*
Y1641756D01*
G01X1442772Y1578403D02*
X1442543D01*
G01X1469631Y1578305D02*
X1457535D01*
G01X1444212Y1578108D02*
X1443073D01*
G01X1457732Y1577714D02*
X1457220D01*
G01X1457732Y1576927D02*
X1457220D01*
G01X1444212Y1576533D02*
X1443073D01*
G01X1469631Y1576337D02*
X1457535D01*
G01X1442772Y1576238D02*
X1442543D01*
G01X1470921Y1576081D02*
X1469507D01*
G01X1442684Y1578316D02*
X1443073Y1578108D01*
G01X1442772Y1578403D02*
X1443243Y1578108D01*
G01X1442543Y1578403D02*
X1442684Y1578316D01*
G01X1469636Y1576351D02*
X1469855Y1576081D01*
G01X1469278Y1576337D02*
X1469507Y1576081D01*
G01X1443073Y1576533D02*
X1442684Y1576326D01*
G01X1469631Y1579486D02*
Y1578305D01*
G01X1469278Y1579486D02*
Y1578305D01*
G01X1467296Y1579486D02*
Y1578305D01*
G01X1467186Y1579486D02*
Y1578305D01*
G01X1458405Y1579486D02*
Y1578305D01*
G01X1458295Y1579486D02*
Y1578305D01*
G01X1457929Y1579486D02*
Y1578305D01*
G01X1457732D02*
Y1577714D01*
G01Y1576927D02*
Y1576337D01*
G01X1457535Y1578305D02*
Y1577714D01*
G01Y1576927D02*
Y1576337D01*
G01X1444212Y1579683D02*
Y1578108D01*
G01X1442684Y1579476D02*
Y1578316D01*
G01X1443243Y1576533D02*
X1442772Y1576238D01*
G01X1442684Y1576326D02*
X1442543Y1576238D01*
G01X1469507Y1578561D02*
X1469278Y1578305D01*
G01X1469855Y1578561D02*
X1469636Y1578291D01*
G01X1470921Y1647852D02*
X1469507D01*
G01X1442772Y1647695D02*
X1442543D01*
G01X1469631Y1647596D02*
X1457535D01*
G01X1444212Y1647400D02*
X1443073D01*
G01X1457732Y1647006D02*
X1457220D01*
G01X1457732Y1646218D02*
X1457220D01*
G01X1444212Y1645825D02*
X1443073D01*
G01X1469631Y1645628D02*
X1457535D01*
G01X1442772Y1645529D02*
X1442543D01*
G01X1470921Y1645372D02*
X1469507D01*
G01X1470921Y1644703D02*
X1469507D01*
G01X1442772Y1644545D02*
X1442543D01*
G01X1469631Y1644447D02*
X1457535D01*
G01X1444212Y1644250D02*
X1443073D01*
G01X1457732Y1643856D02*
X1457220D01*
G01X1457732Y1643069D02*
X1457220D01*
G01X1444212Y1642675D02*
X1443073D01*
G01X1469631Y1642478D02*
X1457535D01*
G01X1442772Y1642380D02*
X1442543D01*
G01X1470921Y1642222D02*
X1469507D01*
G01X1470921Y1641553D02*
X1469507D01*
G01X1442772Y1641396D02*
X1442543D01*
G01X1469631Y1641297D02*
X1457535D01*
G01X1444212Y1641100D02*
X1443073D01*
G01X1457732Y1640707D02*
X1457220D01*
G01X1457732Y1639919D02*
X1457220D01*
G01X1444212Y1639525D02*
X1443073D01*
G01X1469631Y1639329D02*
X1457535D01*
G01X1442772Y1639230D02*
X1442543D01*
G01X1470921Y1639073D02*
X1469507D01*
G01X1470921Y1638403D02*
X1469507D01*
G01X1442772Y1638246D02*
X1442543D01*
G01X1469631Y1638148D02*
X1457535D01*
G01X1444212Y1637951D02*
X1443073D01*
G01X1457732Y1637557D02*
X1457220D01*
G01X1457732Y1636770D02*
X1457220D01*
G01X1444212Y1636376D02*
X1443073D01*
G01X1469631Y1636179D02*
X1457535D01*
G01X1442772Y1636081D02*
X1442543D01*
G01X1470921Y1635923D02*
X1469507D01*
G01X1470921Y1635254D02*
X1469507D01*
G01X1442772Y1635096D02*
X1442543D01*
G01X1469631Y1634998D02*
X1457535D01*
G01X1444212Y1634801D02*
X1443073D01*
G01X1457732Y1634407D02*
X1457220D01*
G01X1457732Y1633620D02*
X1457220D01*
G01X1444212Y1633226D02*
X1443073D01*
G01X1469631Y1633029D02*
X1457535D01*
G01X1442772Y1632931D02*
X1442543D01*
G01X1470921Y1632774D02*
X1469507D01*
G01X1470921Y1632104D02*
X1469507D01*
G01X1442772Y1631947D02*
X1442543D01*
G01X1469631Y1631848D02*
X1457535D01*
G01X1444212Y1631651D02*
X1443073D01*
G01X1457732Y1631258D02*
X1457220D01*
G01X1457732Y1630470D02*
X1457220D01*
G01X1444212Y1630077D02*
X1443073D01*
G01X1469631Y1629880D02*
X1457535D01*
G01X1442772Y1629781D02*
X1442543D01*
G01X1470921Y1629624D02*
X1469507D01*
G01X1470921Y1628955D02*
X1469507D01*
G01X1442772Y1628797D02*
X1442543D01*
G01X1469631Y1628699D02*
X1457535D01*
G01X1444212Y1628502D02*
X1443073D01*
G01X1457732Y1628108D02*
X1457220D01*
G01X1457732Y1627321D02*
X1457220D01*
G01X1444212Y1626927D02*
X1443073D01*
G01X1469631Y1626730D02*
X1457535D01*
G01X1442772Y1626632D02*
X1442543D01*
G01X1470921Y1626474D02*
X1469507D01*
G01X1470921Y1625805D02*
X1469507D01*
G01X1442772Y1625648D02*
X1442543D01*
G01X1469631Y1625549D02*
X1457535D01*
G01X1444212Y1625352D02*
X1443073D01*
G01X1457732Y1624959D02*
X1457220D01*
G01X1457732Y1624171D02*
X1457220D01*
G01X1444212Y1623777D02*
X1443073D01*
G01X1469631Y1623581D02*
X1457535D01*
G01X1442772Y1623482D02*
X1442543D01*
G01X1470921Y1623325D02*
X1469507D01*
G01X1470921Y1622655D02*
X1469507D01*
G01X1442772Y1622498D02*
X1442543D01*
G01X1469631Y1622400D02*
X1457535D01*
G01X1444212Y1622203D02*
X1443073D01*
G01X1457732Y1621809D02*
X1457220D01*
G01X1457732Y1621022D02*
X1457220D01*
G01X1444212Y1620628D02*
X1443073D01*
G01X1469631Y1620431D02*
X1457535D01*
G01X1442772Y1620333D02*
X1442543D01*
G01X1470921Y1620175D02*
X1469507D01*
G01X1470921Y1619506D02*
X1469507D01*
G01X1442772Y1619348D02*
X1442543D01*
G01X1469631Y1619250D02*
X1457535D01*
G01X1444212Y1619053D02*
X1443073D01*
G01X1457732Y1618659D02*
X1457220D01*
G01X1457732Y1617872D02*
X1457220D01*
G01X1444212Y1617478D02*
X1443073D01*
G01X1469631Y1617281D02*
X1457535D01*
G01X1442772Y1617183D02*
X1442543D01*
G01X1470921Y1617025D02*
X1469507D01*
G01X1470921Y1616356D02*
X1469507D01*
G01X1442772Y1616199D02*
X1442543D01*
G01X1469631Y1616100D02*
X1457535D01*
G01X1444212Y1615903D02*
X1443073D01*
G01X1457732Y1615510D02*
X1457220D01*
G01X1457732Y1614722D02*
X1457220D01*
G01X1444212Y1614329D02*
X1443073D01*
G01X1469631Y1614132D02*
X1457535D01*
G01X1442772Y1614033D02*
X1442543D01*
G01X1470921Y1613876D02*
X1469507D01*
G01X1470921Y1613207D02*
X1469507D01*
G01X1442772Y1613049D02*
X1442543D01*
G01X1469631Y1612951D02*
X1457535D01*
G01X1444212Y1612754D02*
X1443073D01*
G01X1457732Y1612360D02*
X1457220D01*
G01X1457732Y1611573D02*
X1457220D01*
G01X1444212Y1611179D02*
X1443073D01*
G01X1469631Y1610982D02*
X1457535D01*
G01X1442772Y1610884D02*
X1442543D01*
G01X1470921Y1610726D02*
X1469507D01*
G01X1470921Y1610057D02*
X1469507D01*
G01X1442772Y1609900D02*
X1442543D01*
G01X1469631Y1609801D02*
X1457535D01*
G01X1444212Y1609604D02*
X1443073D01*
G01X1457732Y1609211D02*
X1457220D01*
G01X1457732Y1608423D02*
X1457220D01*
G01X1444212Y1608029D02*
X1443073D01*
G01X1469631Y1607833D02*
X1457535D01*
G01X1442772Y1607734D02*
X1442543D01*
G01X1470921Y1607577D02*
X1469507D01*
G01X1470921Y1606907D02*
X1469507D01*
G01X1442772Y1606750D02*
X1442543D01*
G01X1469631Y1606651D02*
X1457535D01*
G01X1444212Y1606455D02*
X1443073D01*
G01X1457732Y1606061D02*
X1457220D01*
G01X1457732Y1605274D02*
X1457220D01*
G01X1444212Y1604880D02*
X1443073D01*
G01X1469631Y1604683D02*
X1457535D01*
G01X1442772Y1604585D02*
X1442543D01*
G01X1470921Y1604427D02*
X1469507D01*
G01X1470921Y1603758D02*
X1469507D01*
G01X1442772Y1603600D02*
X1442543D01*
G01X1469631Y1603502D02*
X1457535D01*
G01X1444212Y1603305D02*
X1443073D01*
G01X1457732Y1602911D02*
X1457220D01*
G01X1457732Y1602124D02*
X1457220D01*
G01X1444212Y1601730D02*
X1443073D01*
G01X1469631Y1601533D02*
X1457535D01*
G01X1442772Y1601435D02*
X1442543D01*
G01X1470921Y1601277D02*
X1469507D01*
G01X1470921Y1600608D02*
X1469507D01*
G01X1442772Y1600451D02*
X1442543D01*
G01X1469631Y1600352D02*
X1457535D01*
G01X1444212Y1600155D02*
X1443073D01*
G01X1457732Y1599762D02*
X1457220D01*
G01X1457732Y1598974D02*
X1457220D01*
G01X1444212Y1598581D02*
X1443073D01*
G01X1469631Y1598384D02*
X1457535D01*
G01X1442772Y1598285D02*
X1442543D01*
G01X1470921Y1598128D02*
X1469507D01*
G01X1470921Y1597459D02*
X1469507D01*
G01X1442772Y1597301D02*
X1442543D01*
G01X1469631Y1597203D02*
X1457535D01*
G01X1444212Y1597006D02*
X1443073D01*
G01X1457732Y1596612D02*
X1457220D01*
G01X1457732Y1595825D02*
X1457220D01*
G01X1444212Y1595431D02*
X1443073D01*
G01X1469631Y1595234D02*
X1457535D01*
G01X1442772Y1595136D02*
X1442543D01*
G01X1470921Y1594978D02*
X1469507D01*
G01X1470921Y1594309D02*
X1469507D01*
G01X1442772Y1594151D02*
X1442543D01*
G01X1469631Y1594053D02*
X1457535D01*
G01X1444212Y1593856D02*
X1443073D01*
G01X1457732Y1593463D02*
X1457220D01*
G01X1457732Y1592675D02*
X1457220D01*
G01X1444212Y1592281D02*
X1443073D01*
G01X1469631Y1592085D02*
X1457535D01*
G01X1442772Y1591986D02*
X1442543D01*
G01X1470921Y1591829D02*
X1469507D01*
G01X1470921Y1591159D02*
X1469507D01*
G01X1442772Y1591002D02*
X1442543D01*
G01X1469631Y1590903D02*
X1457535D01*
G01X1444212Y1590707D02*
X1443073D01*
G01X1457732Y1590313D02*
X1457220D01*
G01X1457732Y1589525D02*
X1457220D01*
G01X1444212Y1589132D02*
X1443073D01*
G01X1469631Y1588935D02*
X1457535D01*
G01X1442772Y1588837D02*
X1442543D01*
G01X1470921Y1588679D02*
X1469507D01*
G01X1470921Y1588010D02*
X1469507D01*
G01X1442772Y1587852D02*
X1442543D01*
G01X1469631Y1587754D02*
X1457535D01*
G01X1444212Y1587557D02*
X1443073D01*
G01X1457732Y1587163D02*
X1457220D01*
G01X1457732Y1586376D02*
X1457220D01*
G01X1444212Y1585982D02*
X1443073D01*
G01X1469631Y1585785D02*
X1457535D01*
G01X1442772Y1585687D02*
X1442543D01*
G01X1470921Y1585529D02*
X1469507D01*
G01X1470921Y1584860D02*
X1469507D01*
G01X1442772Y1584703D02*
X1442543D01*
G01X1469631Y1584604D02*
X1457535D01*
G01X1444212Y1584407D02*
X1443073D01*
G01X1457732Y1584014D02*
X1457220D01*
G01X1457732Y1583226D02*
X1457220D01*
G01X1444212Y1582833D02*
X1443073D01*
G01X1469631Y1582636D02*
X1457535D01*
G01X1442772Y1582537D02*
X1442543D01*
G01X1470921Y1582380D02*
X1469507D01*
G01X1470921Y1581711D02*
X1469507D01*
G01X1442772Y1581553D02*
X1442543D01*
G01X1469631Y1581455D02*
X1457535D01*
G01X1444212Y1581258D02*
X1443073D01*
G01X1457732Y1580864D02*
X1457220D01*
G01X1457732Y1580077D02*
X1457220D01*
G01X1444212Y1579683D02*
X1443073D01*
G01X1469631Y1579486D02*
X1457535D01*
G01X1442772Y1579388D02*
X1442543D01*
G01X1470921Y1579230D02*
X1469507D01*
G01X1470921Y1578561D02*
X1469507D01*
G01X1442684Y1647607D02*
X1443073Y1647400D01*
G01X1442684Y1644457D02*
X1443073Y1644250D01*
G01X1442772Y1647695D02*
X1443243Y1647400D01*
G01X1442543Y1647695D02*
X1442684Y1647607D01*
G01X1442772Y1644545D02*
X1443243Y1644250D01*
G01X1442543Y1644545D02*
X1442684Y1644457D01*
G01X1442772Y1641396D02*
X1443243Y1641100D01*
G01X1442543Y1641396D02*
X1442684Y1641308D01*
G01X1442772Y1638246D02*
X1443243Y1637951D01*
G01X1442543Y1638246D02*
X1442684Y1638158D01*
G01X1442772Y1635096D02*
X1443243Y1634801D01*
G01X1442543Y1635096D02*
X1442684Y1635009D01*
G01X1442772Y1631947D02*
X1443243Y1631651D01*
G01X1442543Y1631947D02*
X1442684Y1631859D01*
G01X1442772Y1628797D02*
X1443243Y1628502D01*
G01X1442543Y1628797D02*
X1442684Y1628709D01*
G01X1442772Y1625648D02*
X1443243Y1625352D01*
G01X1442543Y1625648D02*
X1442684Y1625560D01*
G01X1442772Y1622498D02*
X1443243Y1622203D01*
G01X1442543Y1622498D02*
X1442684Y1622410D01*
G01X1442772Y1619348D02*
X1443243Y1619053D01*
G01X1442543Y1619348D02*
X1442684Y1619261D01*
G01X1442772Y1616199D02*
X1443243Y1615903D01*
G01X1442543Y1616199D02*
X1442684Y1616111D01*
G01X1442772Y1613049D02*
X1443243Y1612754D01*
G01X1442543Y1613049D02*
X1442684Y1612961D01*
G01X1442772Y1609900D02*
X1443243Y1609604D01*
G01X1442543Y1609900D02*
X1442684Y1609812D01*
G01X1442772Y1606750D02*
X1443243Y1606455D01*
G01X1442543Y1606750D02*
X1442684Y1606662D01*
G01Y1641308D02*
X1443073Y1641100D01*
G01X1442684Y1638158D02*
X1443073Y1637951D01*
G01X1442684Y1635009D02*
X1443073Y1634801D01*
G01X1442684Y1631859D02*
X1443073Y1631651D01*
G01X1442684Y1628709D02*
X1443073Y1628502D01*
G01X1442684Y1625560D02*
X1443073Y1625352D01*
G01X1442684Y1622410D02*
X1443073Y1622203D01*
G01X1442684Y1619261D02*
X1443073Y1619053D01*
G01X1442684Y1616111D02*
X1443073Y1615903D01*
G01X1442684Y1612961D02*
X1443073Y1612754D01*
G01X1442684Y1609812D02*
X1443073Y1609604D01*
G01X1442684Y1606662D02*
X1443073Y1606455D01*
G01X1442684Y1603512D02*
X1443073Y1603305D01*
G01X1442684Y1600363D02*
X1443073Y1600155D01*
G01X1442684Y1597213D02*
X1443073Y1597006D01*
G01X1442684Y1594064D02*
X1443073Y1593856D01*
G01X1442684Y1590914D02*
X1443073Y1590707D01*
G01X1442684Y1587764D02*
X1443073Y1587557D01*
G01X1442684Y1584615D02*
X1443073Y1584407D01*
G01X1442684Y1581465D02*
X1443073Y1581258D01*
G01X1442772Y1603600D02*
X1443243Y1603305D01*
G01X1442543Y1603600D02*
X1442684Y1603512D01*
G01X1442772Y1600451D02*
X1443243Y1600155D01*
G01X1442543Y1600451D02*
X1442684Y1600363D01*
G01X1442772Y1597301D02*
X1443243Y1597006D01*
G01X1442543Y1597301D02*
X1442684Y1597213D01*
G01X1442772Y1594151D02*
X1443243Y1593856D01*
G01X1442543Y1594151D02*
X1442684Y1594064D01*
G01X1442772Y1591002D02*
X1443243Y1590707D01*
G01X1442543Y1591002D02*
X1442684Y1590914D01*
G01X1442772Y1587852D02*
X1443243Y1587557D01*
G01X1442543Y1587852D02*
X1442684Y1587764D01*
G01X1442772Y1584703D02*
X1443243Y1584407D01*
G01X1442543Y1584703D02*
X1442684Y1584615D01*
G01X1442772Y1581553D02*
X1443243Y1581258D01*
G01X1442543Y1581553D02*
X1442684Y1581465D01*
G01X1469278Y1645628D02*
X1469507Y1645372D01*
G01X1469278Y1642478D02*
X1469507Y1642222D01*
G01X1469278Y1639329D02*
X1469507Y1639073D01*
G01X1469278Y1636179D02*
X1469507Y1635923D01*
G01X1469278Y1633029D02*
X1469507Y1632774D01*
G01X1469278Y1629880D02*
X1469507Y1629624D01*
G01X1469278Y1626730D02*
X1469507Y1626474D01*
G01X1469278Y1623581D02*
X1469507Y1623325D01*
G01X1469278Y1620431D02*
X1469507Y1620175D01*
G01X1469278Y1617281D02*
X1469507Y1617025D01*
G01X1469278Y1614132D02*
X1469507Y1613876D01*
G01X1469278Y1610982D02*
X1469507Y1610726D01*
G01X1469278Y1607833D02*
X1469507Y1607577D01*
G01X1469278Y1604683D02*
X1469507Y1604427D01*
G01X1469636Y1645642D02*
X1469855Y1645372D01*
G01X1469636Y1642492D02*
X1469855Y1642222D01*
G01X1469636Y1639343D02*
X1469855Y1639073D01*
G01X1469636Y1636193D02*
X1469855Y1635923D01*
G01X1469636Y1633044D02*
X1469855Y1632774D01*
G01X1469636Y1629894D02*
X1469855Y1629624D01*
G01X1469636Y1626744D02*
X1469855Y1626474D01*
G01X1469636Y1623595D02*
X1469855Y1623325D01*
G01X1469636Y1620445D02*
X1469855Y1620175D01*
G01X1469636Y1617296D02*
X1469855Y1617025D01*
G01X1469636Y1614146D02*
X1469855Y1613876D01*
G01X1469636Y1610996D02*
X1469855Y1610726D01*
G01X1469636Y1607847D02*
X1469855Y1607577D01*
G01X1469636Y1604697D02*
X1469855Y1604427D01*
G01X1469636Y1601547D02*
X1469855Y1601277D01*
G01X1469636Y1598398D02*
X1469855Y1598128D01*
G01X1469636Y1595248D02*
X1469855Y1594978D01*
G01X1469636Y1592099D02*
X1469855Y1591829D01*
G01X1469636Y1588949D02*
X1469855Y1588679D01*
G01X1469636Y1585799D02*
X1469855Y1585529D01*
G01X1469636Y1582650D02*
X1469855Y1582380D01*
G01X1469636Y1579500D02*
X1469855Y1579230D01*
G01X1469278Y1601533D02*
X1469507Y1601277D01*
G01X1469278Y1598384D02*
X1469507Y1598128D01*
G01X1469278Y1595234D02*
X1469507Y1594978D01*
G01X1469278Y1592085D02*
X1469507Y1591829D01*
G01X1469278Y1588935D02*
X1469507Y1588679D01*
G01X1469278Y1585785D02*
X1469507Y1585529D01*
G01X1469278Y1582636D02*
X1469507Y1582380D01*
G01X1469278Y1579486D02*
X1469507Y1579230D01*
G01X1443073Y1579683D02*
X1442684Y1579476D01*
G01X1443073Y1582833D02*
X1442684Y1582625D01*
G01X1470921Y1579230D02*
Y1578561D01*
G01Y1585529D02*
Y1584860D01*
G01Y1582380D02*
Y1581711D01*
G01Y1588679D02*
Y1588010D01*
G01Y1594978D02*
Y1594309D01*
G01Y1591829D02*
Y1591159D01*
G01Y1598128D02*
Y1597459D01*
G01Y1601277D02*
Y1600608D01*
G01Y1607577D02*
Y1606907D01*
G01Y1604427D02*
Y1603758D01*
G01Y1610726D02*
Y1610057D01*
G01Y1617025D02*
Y1616356D01*
G01Y1613876D02*
Y1613207D01*
G01Y1620175D02*
Y1619506D01*
G01Y1626474D02*
Y1625805D01*
G01Y1623325D02*
Y1622655D01*
G01Y1629624D02*
Y1628955D01*
G01Y1635923D02*
Y1635254D01*
G01Y1632774D02*
Y1632104D01*
G01Y1639073D02*
Y1638403D01*
G01Y1645372D02*
Y1644703D01*
G01Y1642222D02*
Y1641553D01*
G01Y1648522D02*
Y1647852D01*
G01X1470574Y1579230D02*
Y1578561D01*
G01Y1585529D02*
Y1584860D01*
G01Y1582380D02*
Y1581711D01*
G01Y1588679D02*
Y1588010D01*
G01Y1594978D02*
Y1594309D01*
G01Y1591829D02*
Y1591159D01*
G01Y1598128D02*
Y1597459D01*
G01Y1601277D02*
Y1600608D01*
G01Y1607577D02*
Y1606907D01*
G01Y1604427D02*
Y1603758D01*
G01Y1610726D02*
Y1610057D01*
G01Y1617025D02*
Y1616356D01*
G01Y1613876D02*
Y1613207D01*
G01Y1620175D02*
Y1619506D01*
G01Y1626474D02*
Y1625805D01*
G01Y1623325D02*
Y1622655D01*
G01Y1629624D02*
Y1628955D01*
G01Y1635923D02*
Y1635254D01*
G01Y1632774D02*
Y1632104D01*
G01Y1639073D02*
Y1638403D01*
G01Y1645372D02*
Y1644703D01*
G01Y1642222D02*
Y1641553D01*
G01Y1648522D02*
Y1647852D01*
G01X1469631Y1582636D02*
Y1581455D01*
G01Y1588935D02*
Y1587754D01*
G01Y1585785D02*
Y1584604D01*
G01Y1592085D02*
Y1590903D01*
G01Y1598384D02*
Y1597203D01*
G01Y1595234D02*
Y1594053D01*
G01Y1601533D02*
Y1600352D01*
G01Y1607833D02*
Y1606651D01*
G01Y1604683D02*
Y1603502D01*
G01Y1610982D02*
Y1609801D01*
G01Y1617281D02*
Y1616100D01*
G01Y1614132D02*
Y1612951D01*
G01Y1620431D02*
Y1619250D01*
G01Y1626730D02*
Y1625549D01*
G01Y1623581D02*
Y1622400D01*
G01Y1629880D02*
Y1628699D01*
G01Y1636179D02*
Y1634998D01*
G01Y1633029D02*
Y1631848D01*
G01Y1639329D02*
Y1638148D01*
G01Y1645628D02*
Y1644447D01*
G01Y1642478D02*
Y1641297D01*
G01Y1648777D02*
Y1647596D01*
G01X1469278Y1582636D02*
Y1581455D01*
G01Y1588935D02*
Y1587754D01*
G01Y1585785D02*
Y1584604D01*
G01Y1592085D02*
Y1590903D01*
G01Y1598384D02*
Y1597203D01*
G01Y1595234D02*
Y1594053D01*
G01Y1601533D02*
Y1600352D01*
G01Y1607833D02*
Y1606651D01*
G01Y1604683D02*
Y1603502D01*
G01Y1610982D02*
Y1609801D01*
G01Y1617281D02*
Y1616100D01*
G01Y1614132D02*
Y1612951D01*
G01Y1620431D02*
Y1619250D01*
G01Y1626730D02*
Y1625549D01*
G01Y1623581D02*
Y1622400D01*
G01Y1629880D02*
Y1628699D01*
G01Y1636179D02*
Y1634998D01*
G01Y1633029D02*
Y1631848D01*
G01Y1639329D02*
Y1638148D01*
G01Y1645628D02*
Y1644447D01*
G01Y1642478D02*
Y1641297D01*
G01Y1648777D02*
Y1647596D01*
G01X1467296Y1582636D02*
Y1581455D01*
G01Y1588935D02*
Y1587754D01*
G01Y1585785D02*
Y1584604D01*
G01Y1592085D02*
Y1590903D01*
G01Y1598384D02*
Y1597203D01*
G01Y1595234D02*
Y1594053D01*
G01Y1601533D02*
Y1600352D01*
G01Y1607833D02*
Y1606651D01*
G01Y1604683D02*
Y1603502D01*
G01Y1610982D02*
Y1609801D01*
G01Y1617281D02*
Y1616100D01*
G01Y1614132D02*
Y1612951D01*
G01Y1620431D02*
Y1619250D01*
G01Y1626730D02*
Y1625549D01*
G01Y1623581D02*
Y1622400D01*
G01Y1629880D02*
Y1628699D01*
G01Y1636179D02*
Y1634998D01*
G01Y1633029D02*
Y1631848D01*
G01Y1639329D02*
Y1638148D01*
G01Y1645628D02*
Y1644447D01*
G01Y1642478D02*
Y1641297D01*
G01Y1648777D02*
Y1647596D01*
G01X1467186Y1582636D02*
Y1581455D01*
G01Y1588935D02*
Y1587754D01*
G01Y1585785D02*
Y1584604D01*
G01Y1592085D02*
Y1590903D01*
G01Y1598384D02*
Y1597203D01*
G01Y1595234D02*
Y1594053D01*
G01Y1601533D02*
Y1600352D01*
G01Y1607833D02*
Y1606651D01*
G01Y1604683D02*
Y1603502D01*
G01Y1610982D02*
Y1609801D01*
G01Y1617281D02*
Y1616100D01*
G01Y1614132D02*
Y1612951D01*
G01Y1620431D02*
Y1619250D01*
G01Y1626730D02*
Y1625549D01*
G01Y1623581D02*
Y1622400D01*
G01Y1629880D02*
Y1628699D01*
G01Y1636179D02*
Y1634998D01*
G01Y1633029D02*
Y1631848D01*
G01Y1639329D02*
Y1638148D01*
G01Y1645628D02*
Y1644447D01*
G01Y1642478D02*
Y1641297D01*
G01Y1648777D02*
Y1647596D01*
G01X1458405Y1582636D02*
Y1581455D01*
G01Y1588935D02*
Y1587754D01*
G01Y1585785D02*
Y1584604D01*
G01Y1592085D02*
Y1590903D01*
G01Y1598384D02*
Y1597203D01*
G01Y1595234D02*
Y1594053D01*
G01Y1601533D02*
Y1600352D01*
G01Y1607833D02*
Y1606651D01*
G01Y1604683D02*
Y1603502D01*
G01Y1610982D02*
Y1609801D01*
G01Y1617281D02*
Y1616100D01*
G01Y1614132D02*
Y1612951D01*
G01Y1620431D02*
Y1619250D01*
G01Y1626730D02*
Y1625549D01*
G01Y1623581D02*
Y1622400D01*
G01Y1629880D02*
Y1628699D01*
G01Y1636179D02*
Y1634998D01*
G01Y1633029D02*
Y1631848D01*
G01Y1639329D02*
Y1638148D01*
G01Y1645628D02*
Y1644447D01*
G01Y1642478D02*
Y1641297D01*
G01Y1648777D02*
Y1647596D01*
G01X1458295Y1582636D02*
Y1581455D01*
G01Y1588935D02*
Y1587754D01*
G01Y1585785D02*
Y1584604D01*
G01Y1592085D02*
Y1590903D01*
G01Y1598384D02*
Y1597203D01*
G01Y1595234D02*
Y1594053D01*
G01Y1601533D02*
Y1600352D01*
G01Y1607833D02*
Y1606651D01*
G01Y1604683D02*
Y1603502D01*
G01Y1610982D02*
Y1609801D01*
G01Y1617281D02*
Y1616100D01*
G01Y1614132D02*
Y1612951D01*
G01Y1620431D02*
Y1619250D01*
G01Y1626730D02*
Y1625549D01*
G01Y1623581D02*
Y1622400D01*
G01Y1629880D02*
Y1628699D01*
G01Y1636179D02*
Y1634998D01*
G01Y1633029D02*
Y1631848D01*
G01Y1639329D02*
Y1638148D01*
G01Y1645628D02*
Y1644447D01*
G01Y1642478D02*
Y1641297D01*
G01Y1648777D02*
Y1647596D01*
G01X1457929Y1582636D02*
Y1581455D01*
G01Y1588935D02*
Y1587754D01*
G01Y1585785D02*
Y1584604D01*
G01Y1592085D02*
Y1590903D01*
G01Y1598384D02*
Y1597203D01*
G01Y1595234D02*
Y1594053D01*
G01Y1601533D02*
Y1600352D01*
G01Y1607833D02*
Y1606651D01*
G01Y1604683D02*
Y1603502D01*
G01Y1610982D02*
Y1609801D01*
G01Y1617281D02*
Y1616100D01*
G01Y1614132D02*
Y1612951D01*
G01Y1620431D02*
Y1619250D01*
G01Y1626730D02*
Y1625549D01*
G01Y1623581D02*
Y1622400D01*
G01Y1629880D02*
Y1628699D01*
G01Y1636179D02*
Y1634998D01*
G01Y1633029D02*
Y1631848D01*
G01Y1639329D02*
Y1638148D01*
G01Y1645628D02*
Y1644447D01*
G01Y1642478D02*
Y1641297D01*
G01Y1648777D02*
Y1647596D01*
G01X1457732Y1580077D02*
Y1579486D01*
G01Y1584604D02*
Y1584014D01*
G01Y1581455D02*
Y1580864D01*
G01Y1583226D02*
Y1582636D01*
G01Y1587754D02*
Y1587163D01*
G01Y1589525D02*
Y1588935D01*
G01Y1586376D02*
Y1585785D01*
G01Y1594053D02*
Y1593463D01*
G01Y1590903D02*
Y1590313D01*
G01Y1592675D02*
Y1592085D01*
G01Y1597203D02*
Y1596612D01*
G01Y1598974D02*
Y1598384D01*
G01Y1595825D02*
Y1595234D01*
G01Y1603502D02*
Y1602911D01*
G01Y1600352D02*
Y1599762D01*
G01Y1602124D02*
Y1601533D01*
G01Y1606651D02*
Y1606061D01*
G01Y1608423D02*
Y1607833D01*
G01Y1605274D02*
Y1604683D01*
G01Y1612951D02*
Y1612360D01*
G01Y1609801D02*
Y1609211D01*
G01Y1611573D02*
Y1610982D01*
G01Y1616100D02*
Y1615510D01*
G01Y1617872D02*
Y1617281D01*
G01Y1614722D02*
Y1614132D01*
G01Y1622400D02*
Y1621809D01*
G01Y1619250D02*
Y1618659D01*
G01Y1621022D02*
Y1620431D01*
G01Y1625549D02*
Y1624959D01*
G01Y1627321D02*
Y1626730D01*
G01Y1624171D02*
Y1623581D01*
G01Y1631848D02*
Y1631258D01*
G01Y1628699D02*
Y1628108D01*
G01Y1630470D02*
Y1629880D01*
G01Y1634998D02*
Y1634407D01*
G01Y1636770D02*
Y1636179D01*
G01Y1633620D02*
Y1633029D01*
G01Y1641297D02*
Y1640707D01*
G01Y1638148D02*
Y1637557D01*
G01Y1639919D02*
Y1639329D01*
G01Y1644447D02*
Y1643856D01*
G01Y1646218D02*
Y1645628D01*
G01Y1643069D02*
Y1642478D01*
G01Y1647596D02*
Y1647006D01*
G01X1457535Y1580077D02*
Y1579486D01*
G01Y1584604D02*
Y1584014D01*
G01Y1581455D02*
Y1580864D01*
G01Y1583226D02*
Y1582636D01*
G01Y1587754D02*
Y1587163D01*
G01Y1589525D02*
Y1588935D01*
G01Y1586376D02*
Y1585785D01*
G01Y1594053D02*
Y1593463D01*
G01Y1590903D02*
Y1590313D01*
G01Y1592675D02*
Y1592085D01*
G01Y1597203D02*
Y1596612D01*
G01Y1598974D02*
Y1598384D01*
G01Y1595825D02*
Y1595234D01*
G01Y1603502D02*
Y1602911D01*
G01Y1600352D02*
Y1599762D01*
G01Y1602124D02*
Y1601533D01*
G01Y1606651D02*
Y1606061D01*
G01Y1608423D02*
Y1607833D01*
G01Y1605274D02*
Y1604683D01*
G01Y1612951D02*
Y1612360D01*
G01Y1609801D02*
Y1609211D01*
G01Y1611573D02*
Y1610982D01*
G01Y1616100D02*
Y1615510D01*
G01Y1617872D02*
Y1617281D01*
G01Y1614722D02*
Y1614132D01*
G01Y1622400D02*
Y1621809D01*
G01Y1619250D02*
Y1618659D01*
G01Y1621022D02*
Y1620431D01*
G01Y1625549D02*
Y1624959D01*
G01Y1627321D02*
Y1626730D01*
G01Y1624171D02*
Y1623581D01*
G01Y1631848D02*
Y1631258D01*
G01Y1628699D02*
Y1628108D01*
G01Y1630470D02*
Y1629880D01*
G01Y1634998D02*
Y1634407D01*
G01Y1636770D02*
Y1636179D01*
G01Y1633620D02*
Y1633029D01*
G01Y1641297D02*
Y1640707D01*
G01Y1638148D02*
Y1637557D01*
G01Y1639919D02*
Y1639329D01*
G01Y1644447D02*
Y1643856D01*
G01Y1646218D02*
Y1645628D01*
G01Y1643069D02*
Y1642478D01*
G01Y1647596D02*
Y1647006D01*
G01X1444212Y1582833D02*
Y1581258D01*
G01Y1589132D02*
Y1587557D01*
G01Y1585982D02*
Y1584407D01*
G01Y1592281D02*
Y1590707D01*
G01Y1598581D02*
Y1597006D01*
G01Y1595431D02*
Y1593856D01*
G01Y1601730D02*
Y1600155D01*
G01Y1608029D02*
Y1606455D01*
G01Y1604880D02*
Y1603305D01*
G01Y1611179D02*
Y1609604D01*
G01Y1617478D02*
Y1615903D01*
G01Y1614329D02*
Y1612754D01*
G01Y1620628D02*
Y1619053D01*
G01Y1626927D02*
Y1625352D01*
G01Y1623777D02*
Y1622203D01*
G01Y1630077D02*
Y1628502D01*
G01Y1636376D02*
Y1634801D01*
G01Y1633226D02*
Y1631651D01*
G01Y1639525D02*
Y1637951D01*
G01Y1645825D02*
Y1644250D01*
G01Y1642675D02*
Y1641100D01*
G01Y1648974D02*
Y1647400D01*
G01X1442684Y1582625D02*
Y1581465D01*
G01Y1588924D02*
Y1587764D01*
G01Y1585775D02*
Y1584615D01*
G01Y1592074D02*
Y1590914D01*
G01Y1598373D02*
Y1597213D01*
G01Y1595224D02*
Y1594064D01*
G01Y1601523D02*
Y1600363D01*
G01Y1607822D02*
Y1606662D01*
G01Y1604672D02*
Y1603512D01*
G01Y1610972D02*
Y1609812D01*
G01Y1617271D02*
Y1616111D01*
G01Y1614121D02*
Y1612961D01*
G01Y1620420D02*
Y1619261D01*
G01Y1626720D02*
Y1625560D01*
G01Y1623570D02*
Y1622410D01*
G01Y1629869D02*
Y1628709D01*
G01Y1636168D02*
Y1635009D01*
G01Y1633019D02*
Y1631859D01*
G01Y1639318D02*
Y1638158D01*
G01Y1645617D02*
Y1644457D01*
G01Y1642468D02*
Y1641308D01*
G01Y1648767D02*
Y1647607D01*
G01X1441472Y1640116D02*
Y1639132D01*
G01Y1645693D02*
Y1644709D01*
G01Y1647826D02*
Y1647006D01*
G01X1443073Y1585982D02*
X1442684Y1585775D01*
G01X1443073Y1589132D02*
X1442684Y1588924D01*
G01X1443073Y1592281D02*
X1442684Y1592074D01*
G01X1443073Y1595431D02*
X1442684Y1595224D01*
G01X1443073Y1598581D02*
X1442684Y1598373D01*
G01X1443073Y1601730D02*
X1442684Y1601523D01*
G01X1443073Y1604880D02*
X1442684Y1604672D01*
G01X1443073Y1608029D02*
X1442684Y1607822D01*
G01X1443073Y1611179D02*
X1442684Y1610972D01*
G01X1443073Y1614329D02*
X1442684Y1614121D01*
G01X1443073Y1617478D02*
X1442684Y1617271D01*
G01X1443073Y1620628D02*
X1442684Y1620420D01*
G01X1443073Y1623777D02*
X1442684Y1623570D01*
G01X1443073Y1626927D02*
X1442684Y1626720D01*
G01X1443073Y1630077D02*
X1442684Y1629869D01*
G01X1443073Y1633226D02*
X1442684Y1633019D01*
G01X1443073Y1636376D02*
X1442684Y1636168D01*
G01X1443073Y1639525D02*
X1442684Y1639318D01*
G01X1443073Y1642675D02*
X1442684Y1642468D01*
G01X1443073Y1645825D02*
X1442684Y1645617D01*
G01X1443243Y1579683D02*
X1442772Y1579388D01*
G01X1442684Y1579476D02*
X1442543Y1579388D01*
G01X1443243Y1582833D02*
X1442772Y1582537D01*
G01X1442684Y1582625D02*
X1442543Y1582537D01*
G01X1443243Y1585982D02*
X1442772Y1585687D01*
G01X1442684Y1585775D02*
X1442543Y1585687D01*
G01X1443243Y1589132D02*
X1442772Y1588837D01*
G01X1442684Y1588924D02*
X1442543Y1588837D01*
G01X1443243Y1592281D02*
X1442772Y1591986D01*
G01X1442684Y1592074D02*
X1442543Y1591986D01*
G01X1443243Y1595431D02*
X1442772Y1595136D01*
G01X1442684Y1595224D02*
X1442543Y1595136D01*
G01X1443243Y1598581D02*
X1442772Y1598285D01*
G01X1442684Y1598373D02*
X1442543Y1598285D01*
G01X1443243Y1601730D02*
X1442772Y1601435D01*
G01X1442684Y1601523D02*
X1442543Y1601435D01*
G01X1443243Y1604880D02*
X1442772Y1604585D01*
G01X1442684Y1604672D02*
X1442543Y1604585D01*
G01X1443243Y1608029D02*
X1442772Y1607734D01*
G01X1442684Y1607822D02*
X1442543Y1607734D01*
G01X1443243Y1611179D02*
X1442772Y1610884D01*
G01X1442684Y1610972D02*
X1442543Y1610884D01*
G01X1443243Y1614329D02*
X1442772Y1614033D01*
G01X1442684Y1614121D02*
X1442543Y1614033D01*
G01X1443243Y1617478D02*
X1442772Y1617183D01*
G01X1442684Y1617271D02*
X1442543Y1617183D01*
G01X1443243Y1620628D02*
X1442772Y1620333D01*
G01X1442684Y1620420D02*
X1442543Y1620333D01*
G01X1443243Y1623777D02*
X1442772Y1623482D01*
G01X1442684Y1623570D02*
X1442543Y1623482D01*
G01X1443243Y1626927D02*
X1442772Y1626632D01*
G01X1442684Y1626720D02*
X1442543Y1626632D01*
G01X1443243Y1630077D02*
X1442772Y1629781D01*
G01X1442684Y1629869D02*
X1442543Y1629781D01*
G01X1443243Y1633226D02*
X1442772Y1632931D01*
G01X1442684Y1633019D02*
X1442543Y1632931D01*
G01X1443243Y1636376D02*
X1442772Y1636081D01*
G01X1442684Y1636168D02*
X1442543Y1636081D01*
G01X1443243Y1639525D02*
X1442772Y1639230D01*
G01X1442684Y1639318D02*
X1442543Y1639230D01*
G01X1443243Y1642675D02*
X1442772Y1642380D01*
G01X1442684Y1642468D02*
X1442543Y1642380D01*
G01X1443243Y1645825D02*
X1442772Y1645529D01*
G01X1442684Y1645617D02*
X1442543Y1645529D01*
G01X1469507Y1581711D02*
X1469278Y1581455D01*
G01X1469507Y1584860D02*
X1469278Y1584604D01*
G01X1469507Y1588010D02*
X1469278Y1587754D01*
G01X1469507Y1591159D02*
X1469278Y1590903D01*
G01X1469507Y1594309D02*
X1469278Y1594053D01*
G01X1469507Y1597459D02*
X1469278Y1597203D01*
G01X1469507Y1600608D02*
X1469278Y1600352D01*
G01X1469507Y1603758D02*
X1469278Y1603502D01*
G01X1469507Y1606907D02*
X1469278Y1606651D01*
G01X1469507Y1610057D02*
X1469278Y1609801D01*
G01X1469507Y1613207D02*
X1469278Y1612951D01*
G01X1469855Y1581711D02*
X1469636Y1581441D01*
G01X1469855Y1584860D02*
X1469636Y1584590D01*
G01X1469855Y1588010D02*
X1469636Y1587740D01*
G01X1469855Y1591159D02*
X1469636Y1590889D01*
G01X1469855Y1594309D02*
X1469636Y1594039D01*
G01X1469855Y1597459D02*
X1469636Y1597189D01*
G01X1469855Y1600608D02*
X1469636Y1600338D01*
G01X1469855Y1603758D02*
X1469636Y1603488D01*
G01X1469855Y1606907D02*
X1469636Y1606637D01*
G01X1469855Y1610057D02*
X1469636Y1609787D01*
G01X1469507Y1616356D02*
X1469278Y1616100D01*
G01X1469507Y1619506D02*
X1469278Y1619250D01*
G01X1469507Y1622655D02*
X1469278Y1622400D01*
G01X1469507Y1625805D02*
X1469278Y1625549D01*
G01X1469507Y1628955D02*
X1469278Y1628699D01*
G01X1469507Y1632104D02*
X1469278Y1631848D01*
G01X1469507Y1635254D02*
X1469278Y1634998D01*
G01X1469507Y1638403D02*
X1469278Y1638148D01*
G01X1469507Y1641553D02*
X1469278Y1641297D01*
G01X1469507Y1644703D02*
X1469278Y1644447D01*
G01X1469507Y1647852D02*
X1469278Y1647596D01*
G01X1469855Y1613207D02*
X1469636Y1612937D01*
G01X1469855Y1616356D02*
X1469636Y1616086D01*
G01X1469855Y1619506D02*
X1469636Y1619236D01*
G01X1469855Y1622655D02*
X1469636Y1622385D01*
G01X1469855Y1625805D02*
X1469636Y1625535D01*
G01X1469855Y1628955D02*
X1469636Y1628685D01*
G01X1469855Y1632104D02*
X1469636Y1631834D01*
G01X1469855Y1635254D02*
X1469636Y1634984D01*
G01X1469855Y1638403D02*
X1469636Y1638133D01*
G01X1469855Y1641553D02*
X1469636Y1641283D01*
G01X1469855Y1644703D02*
X1469636Y1644433D01*
G01X1469855Y1647852D02*
X1469636Y1647582D01*
G01X1439047Y1650882D02*
X1442543Y1650844D01*
G01X1437751Y1650897D02*
X1441007Y1650861D01*
G01X1438785Y1650882D02*
X1436420Y1650909D01*
G01X1441235Y1650861D02*
X1442772Y1650844D01*
G01X1441235Y1650861D02*
X1438785Y1650882D01*
G01X1437751Y1650897D02*
X1436420Y1650909D01*
G01X1439047Y1650882D02*
X1438785D01*
G01X1441235Y1650861D02*
X1441007D01*
G01X1441472Y1650451D02*
X1437452D01*
G01X1441472Y1649630D02*
X1437452D01*
G01X1441235Y1648663D02*
X1441007D01*
G01X1439047Y1648641D02*
X1438785D01*
G01X1440094Y1648653D02*
X1438785Y1648641D01*
G01X1441235Y1648663D02*
X1440094Y1648653D01*
G01X1437751Y1648627D02*
X1436420Y1648615D01*
G01X1442543Y1648679D02*
X1441007Y1648663D01*
G01X1442543Y1648679D02*
X1439047Y1648641D01*
G01X1441235Y1648663D02*
X1442772Y1648679D01*
G01X1439047Y1648641D02*
X1440094Y1648653D01*
G01X1438785Y1648641D02*
X1436420Y1648615D01*
G01X1437751Y1648627D02*
X1439047Y1648641D01*
G01X1437117Y1650615D02*
X1437452Y1650451D01*
G01X1436949Y1650779D02*
X1437117Y1650615D01*
G01X1436279Y1650779D02*
X1436781Y1650287D01*
G01Y1651107D02*
X1436949Y1650779D01*
G01X1436111Y1651271D02*
X1436279Y1650779D01*
G01X1441235Y1651812D02*
Y1650861D01*
G01X1441007Y1651812D02*
Y1650861D01*
G01X1437452Y1649630D02*
X1437117Y1649466D01*
G01X1439047Y1651791D02*
Y1650882D01*
G01X1438785Y1651791D02*
Y1650882D01*
G01X1437751Y1651770D02*
Y1650903D01*
G01X1436781Y1648974D02*
Y1648646D01*
G01Y1651599D02*
Y1651107D01*
G01X1436420Y1651765D02*
Y1650909D01*
G01X1436111Y1649302D02*
Y1648646D01*
G01Y1651927D02*
Y1651271D01*
G01X1437117Y1649466D02*
X1436949Y1649302D01*
G01X1436781Y1650287D02*
X1436279Y1649795D01*
G01X1436949Y1649302D02*
X1436781Y1648974D01*
G01X1436279Y1649795D02*
X1436111Y1649302D01*
G01X1439797Y1667019D02*
X1438792Y1666855D01*
G01X1438289Y1678010D02*
X1437452Y1677846D01*
G01X1438289Y1677190D02*
X1437452Y1677025D01*
G01X1438122Y1665543D02*
X1437284Y1665379D01*
G01X1438457Y1684571D02*
X1437787Y1684407D01*
G01X1438457Y1683751D02*
X1437787Y1683587D01*
G01X1439797Y1680306D02*
X1439127Y1680142D01*
G01X1438122Y1672104D02*
X1437452Y1671940D01*
G01X1438122Y1664722D02*
X1437452Y1664558D01*
G01X1438122Y1659637D02*
X1437452Y1659473D01*
G01X1440300Y1679650D02*
X1439127Y1679322D01*
G01X1439047Y1691827D02*
X1442543Y1691789D01*
G01X1437751Y1691842D02*
X1441007Y1691806D01*
G01X1439047Y1688678D02*
X1442543Y1688640D01*
G01X1437751Y1688692D02*
X1441007Y1688656D01*
G01X1439047Y1685528D02*
X1442543Y1685490D01*
G01X1437751Y1685542D02*
X1441007Y1685507D01*
G01X1439047Y1682378D02*
X1442543Y1682340D01*
G01X1437751Y1682393D02*
X1441007Y1682357D01*
G01X1439047Y1679229D02*
X1442543Y1679191D01*
G01X1437751Y1679243D02*
X1441007Y1679207D01*
G01X1439047Y1676079D02*
X1442543Y1676041D01*
G01X1437751Y1676094D02*
X1441007Y1676058D01*
G01X1439047Y1672930D02*
X1442543Y1672892D01*
G01X1437751Y1672944D02*
X1441007Y1672908D01*
G01X1439047Y1669780D02*
X1442543Y1669742D01*
G01X1437751Y1669794D02*
X1441007Y1669758D01*
G01X1439047Y1666630D02*
X1442543Y1666592D01*
G01X1437751Y1666645D02*
X1441007Y1666609D01*
G01X1438785Y1691827D02*
X1436420Y1691853D01*
G01X1438785Y1688678D02*
X1436420Y1688704D01*
G01X1438785Y1685528D02*
X1436420Y1685554D01*
G01X1438785Y1682378D02*
X1436420Y1682405D01*
G01X1438785Y1679229D02*
X1436420Y1679255D01*
G01X1438785Y1676079D02*
X1436420Y1676105D01*
G01X1438785Y1672930D02*
X1436420Y1672956D01*
G01X1438785Y1669780D02*
X1436420Y1669806D01*
G01X1438785Y1666630D02*
X1436420Y1666657D01*
G01X1441235Y1691806D02*
X1442772Y1691789D01*
G01X1441235Y1688656D02*
X1442772Y1688640D01*
G01X1441235Y1685507D02*
X1442772Y1685490D01*
G01X1441235Y1682357D02*
X1442772Y1682340D01*
G01X1441235Y1679207D02*
X1442772Y1679191D01*
G01X1441235Y1676058D02*
X1442772Y1676041D01*
G01X1441235Y1672908D02*
X1442772Y1672892D01*
G01X1441235Y1669758D02*
X1442772Y1669742D01*
G01X1441235Y1666609D02*
X1442772Y1666592D01*
G01X1441235Y1691806D02*
X1438785Y1691827D01*
G01X1437751Y1691842D02*
X1436420Y1691853D01*
G01X1441235Y1688656D02*
X1438785Y1688678D01*
G01X1437751Y1688692D02*
X1436420Y1688704D01*
G01X1441235Y1685507D02*
X1438785Y1685528D01*
G01X1437751Y1685542D02*
X1436420Y1685554D01*
G01X1441235Y1682357D02*
X1438785Y1682378D01*
G01X1437751Y1682393D02*
X1436420Y1682405D01*
G01X1441235Y1679207D02*
X1438785Y1679229D01*
G01X1437751Y1679243D02*
X1436420Y1679255D01*
G01X1441235Y1676058D02*
X1438785Y1676079D01*
G01X1437751Y1676094D02*
X1436420Y1676105D01*
G01X1441235Y1672908D02*
X1438785Y1672930D01*
G01X1437751Y1672944D02*
X1436420Y1672956D01*
G01X1441235Y1669758D02*
X1438785Y1669780D01*
G01X1437751Y1669794D02*
X1436420Y1669806D01*
G01X1441235Y1666609D02*
X1438785Y1666630D01*
G01X1437751Y1666645D02*
X1436420Y1666657D01*
G01X1441235Y1663459D02*
X1440094Y1663469D01*
G01X1449937Y1696218D02*
X1430449D01*
G01X1441235Y1692757D02*
X1441007D01*
G01X1439047Y1692735D02*
X1438785D01*
G01X1439047Y1691827D02*
X1438785D01*
G01X1441235Y1691806D02*
X1441007D01*
G01X1441235Y1689607D02*
X1441007D01*
G01X1439047Y1689586D02*
X1438785D01*
G01X1439047Y1688678D02*
X1438785D01*
G01X1441235Y1688656D02*
X1441007D01*
G01X1441472Y1686704D02*
X1433598D01*
G01X1441235Y1686458D02*
X1441007D01*
G01X1439047Y1686436D02*
X1438785D01*
G01X1441472Y1685884D02*
X1433598D01*
G01X1439047Y1685528D02*
X1438785D01*
G01X1441235Y1685507D02*
X1441007D01*
G01X1439127Y1684571D02*
X1438457D01*
G01X1439127Y1683751D02*
X1438457D01*
G01X1441235Y1683308D02*
X1441007D01*
G01X1439047Y1683287D02*
X1438785D01*
G01X1439047Y1682378D02*
X1438785D01*
G01X1441235Y1682357D02*
X1441007D01*
G01X1441235Y1680159D02*
X1441007D01*
G01X1439127Y1680142D02*
X1438457D01*
G01X1439047Y1680137D02*
X1438785D01*
G01X1439127Y1679322D02*
X1438457D01*
G01X1439047Y1679229D02*
X1438785D01*
G01X1441235Y1679207D02*
X1441007D01*
G01X1441472Y1678010D02*
X1438289D01*
G01X1441472Y1677190D02*
X1438289D01*
G01X1441235Y1677009D02*
X1441007D01*
G01X1439047Y1676987D02*
X1438785D01*
G01X1439047Y1676079D02*
X1438785D01*
G01X1441235Y1676058D02*
X1441007D01*
G01X1436949Y1674237D02*
X1436111D01*
G01X1441472D02*
X1437619D01*
G01X1441235Y1673859D02*
X1441007D01*
G01X1439047Y1673838D02*
X1438785D01*
G01X1441472Y1673417D02*
X1436111D01*
G01X1439047Y1672930D02*
X1438785D01*
G01X1441235Y1672908D02*
X1441007D01*
G01X1438792Y1672104D02*
X1438122D01*
G01Y1671284D02*
X1437787D01*
G01X1441235Y1670710D02*
X1441007D01*
G01X1439047Y1670688D02*
X1438785D01*
G01X1439047Y1669780D02*
X1438785D01*
G01X1441235Y1669758D02*
X1441007D01*
G01X1438122Y1667839D02*
X1437954D01*
G01X1439127Y1667675D02*
X1438792D01*
G01X1441235Y1667560D02*
X1441007D01*
G01X1439047Y1667539D02*
X1438785D01*
G01X1439047Y1666630D02*
X1438785D01*
G01X1441235Y1666609D02*
X1441007D01*
G01X1441472Y1665543D02*
X1438122D01*
G01X1441472Y1664722D02*
X1438122D01*
G01X1441235Y1664411D02*
X1441007D01*
G01X1439047Y1664389D02*
X1438785D01*
G01X1439047Y1663481D02*
X1438785D01*
G01X1441235Y1663459D02*
X1441007D01*
G01X1436949Y1661770D02*
X1433598D01*
G01X1441472D02*
X1437619D01*
G01X1441235Y1661261D02*
X1441007D01*
G01X1439047Y1661239D02*
X1438785D01*
G01X1441472Y1660949D02*
X1433598D01*
G01X1439047Y1660331D02*
X1438785D01*
G01X1441235Y1660310D02*
X1441007D01*
G01X1439462Y1659637D02*
X1438122D01*
G01X1439294Y1658817D02*
X1438289D01*
G01X1440094Y1692747D02*
X1438785Y1692735D01*
G01X1441235Y1692757D02*
X1440094Y1692747D01*
G01Y1689597D02*
X1438785Y1689586D01*
G01X1441235Y1689607D02*
X1440094Y1689597D01*
G01Y1686448D02*
X1438785Y1686436D01*
G01X1441235Y1686458D02*
X1440094Y1686448D01*
G01Y1683298D02*
X1438785Y1683287D01*
G01X1441235Y1683308D02*
X1440094Y1683298D01*
G01Y1680149D02*
X1438785Y1680137D01*
G01X1441235Y1680159D02*
X1440094Y1680149D01*
G01Y1676999D02*
X1438785Y1676987D01*
G01X1441235Y1677009D02*
X1440094Y1676999D01*
G01Y1673849D02*
X1438785Y1673838D01*
G01X1441235Y1673859D02*
X1440094Y1673849D01*
G01Y1670700D02*
X1438785Y1670688D01*
G01X1441235Y1670710D02*
X1440094Y1670700D01*
G01Y1667550D02*
X1438785Y1667539D01*
G01X1441235Y1667560D02*
X1440094Y1667550D01*
G01Y1664401D02*
X1438785Y1664389D01*
G01X1441235Y1664411D02*
X1440094Y1664401D01*
G01Y1661251D02*
X1438785Y1661239D01*
G01X1441235Y1661261D02*
X1440094Y1661251D01*
G01Y1658101D02*
X1438785Y1658090D01*
G01X1441235Y1658111D02*
X1440094Y1658101D01*
G01Y1654952D02*
X1438785Y1654940D01*
G01X1441235Y1654962D02*
X1440094Y1654952D01*
G01X1437751Y1692721D02*
X1436420Y1692709D01*
G01X1437751Y1689572D02*
X1436420Y1689560D01*
G01X1437751Y1686422D02*
X1436420Y1686410D01*
G01X1437751Y1683272D02*
X1436420Y1683261D01*
G01X1437751Y1680123D02*
X1436420Y1680111D01*
G01X1437751Y1676973D02*
X1436420Y1676961D01*
G01X1437751Y1673824D02*
X1436420Y1673812D01*
G01X1437751Y1670674D02*
X1436420Y1670662D01*
G01X1437751Y1667524D02*
X1436420Y1667513D01*
G01X1437751Y1664375D02*
X1436420Y1664363D01*
G01X1437751Y1661225D02*
X1436420Y1661213D01*
G01X1437751Y1658076D02*
X1436420Y1658064D01*
G01X1437751Y1654926D02*
X1436420Y1654914D01*
G01X1442543Y1692774D02*
X1441007Y1692757D01*
G01X1442543Y1692774D02*
X1439047Y1692736D01*
G01X1441235Y1692757D02*
X1442772Y1692774D01*
G01X1442543Y1689624D02*
X1441007Y1689607D01*
G01X1442543Y1689624D02*
X1439047Y1689586D01*
G01X1441235Y1689607D02*
X1442772Y1689624D01*
G01X1442543Y1686474D02*
X1441007Y1686458D01*
G01X1442543Y1686474D02*
X1439047Y1686436D01*
G01X1441235Y1686458D02*
X1442772Y1686474D01*
G01X1442543Y1683325D02*
X1441007Y1683308D01*
G01X1442543Y1683325D02*
X1439047Y1683287D01*
G01X1441235Y1683308D02*
X1442772Y1683325D01*
G01X1442543Y1680175D02*
X1441007Y1680159D01*
G01X1442543Y1680175D02*
X1439047Y1680137D01*
G01X1441235Y1680159D02*
X1442772Y1680175D01*
G01X1442543Y1677025D02*
X1441007Y1677009D01*
G01X1442543Y1677025D02*
X1439047Y1676988D01*
G01X1441235Y1677009D02*
X1442772Y1677025D01*
G01X1442543Y1673876D02*
X1441007Y1673859D01*
G01X1442543Y1673876D02*
X1439047Y1673838D01*
G01X1441235Y1673859D02*
X1442772Y1673876D01*
G01X1442543Y1670726D02*
X1441007Y1670710D01*
G01X1442543Y1670726D02*
X1439047Y1670688D01*
G01X1441235Y1670710D02*
X1442772Y1670726D01*
G01X1442543Y1667577D02*
X1441007Y1667560D01*
G01X1442543Y1667577D02*
X1439047Y1667539D01*
G01X1441235Y1667560D02*
X1442772Y1667577D01*
G01X1442543Y1664427D02*
X1441007Y1664411D01*
G01X1442543Y1664427D02*
X1439047Y1664389D01*
G01X1441235Y1664411D02*
X1442772Y1664427D01*
G01X1442543Y1661277D02*
X1441007Y1661261D01*
G01X1442543Y1661277D02*
X1439047Y1661239D01*
G01X1441235Y1661261D02*
X1442772Y1661277D01*
G01X1442543Y1658128D02*
X1441007Y1658111D01*
G01X1442543Y1658128D02*
X1439047Y1658090D01*
G01X1441235Y1658111D02*
X1442772Y1658128D01*
G01X1442543Y1654978D02*
X1441007Y1654962D01*
G01X1442543Y1654978D02*
X1439047Y1654940D01*
G01X1441235Y1654962D02*
X1442772Y1654978D01*
G01X1439047Y1692735D02*
X1440094Y1692747D01*
G01X1438785Y1692735D02*
X1436420Y1692709D01*
G01X1437751Y1692721D02*
X1439047Y1692735D01*
G01Y1689586D02*
X1440094Y1689597D01*
G01X1438785Y1689586D02*
X1436420Y1689560D01*
G01X1437751Y1689572D02*
X1439047Y1689586D01*
G01Y1686436D02*
X1440094Y1686448D01*
G01X1438785Y1686436D02*
X1436420Y1686410D01*
G01X1437751Y1686422D02*
X1439047Y1686436D01*
G01Y1683287D02*
X1440094Y1683298D01*
G01X1438785Y1683287D02*
X1436420Y1683261D01*
G01X1437751Y1683272D02*
X1439047Y1683287D01*
G01Y1680137D02*
X1440094Y1680149D01*
G01X1438785Y1680137D02*
X1436420Y1680111D01*
G01X1437751Y1680123D02*
X1439047Y1680137D01*
G01Y1676987D02*
X1440094Y1676999D01*
G01X1438785Y1676987D02*
X1436420Y1676961D01*
G01X1437751Y1676973D02*
X1439047Y1676987D01*
G01Y1673838D02*
X1440094Y1673849D01*
G01X1438785Y1673838D02*
X1436420Y1673812D01*
G01X1437751Y1673824D02*
X1439047Y1673838D01*
G01Y1670688D02*
X1440094Y1670700D01*
G01X1438785Y1670688D02*
X1436420Y1670662D01*
G01X1437751Y1670674D02*
X1439047Y1670688D01*
G01Y1667539D02*
X1440094Y1667550D01*
G01X1438785Y1667539D02*
X1436420Y1667513D01*
G01X1437751Y1667524D02*
X1439047Y1667539D01*
G01Y1664389D02*
X1440094Y1664401D01*
G01X1438785Y1664389D02*
X1436420Y1664363D01*
G01X1437751Y1664375D02*
X1439047Y1664389D01*
G01Y1661239D02*
X1440094Y1661251D01*
G01X1438785Y1661239D02*
X1436420Y1661213D01*
G01X1437751Y1661225D02*
X1439047Y1661239D01*
G01Y1658090D02*
X1440094Y1658101D01*
G01X1438785Y1658090D02*
X1436420Y1658064D01*
G01X1437751Y1658076D02*
X1439047Y1658090D01*
G01Y1654940D02*
X1440094Y1654952D01*
G01X1438785Y1654940D02*
X1436420Y1654914D01*
G01X1437751Y1654926D02*
X1439047Y1654940D01*
G01Y1663481D02*
X1442543Y1663443D01*
G01X1437751Y1663495D02*
X1441007Y1663459D01*
G01X1439047Y1660331D02*
X1442543Y1660293D01*
G01X1437751Y1660346D02*
X1441007Y1660310D01*
G01X1439047Y1657182D02*
X1442543Y1657144D01*
G01X1437751Y1657196D02*
X1441007Y1657160D01*
G01X1439047Y1654032D02*
X1442543Y1653994D01*
G01X1437751Y1654046D02*
X1441007Y1654010D01*
G01X1438785Y1663481D02*
X1436420Y1663507D01*
G01X1438785Y1660331D02*
X1436420Y1660357D01*
G01X1438785Y1657182D02*
X1436420Y1657208D01*
G01X1438785Y1654032D02*
X1436420Y1654058D01*
G01X1441235Y1663459D02*
X1442772Y1663443D01*
G01X1441235Y1660310D02*
X1442772Y1660293D01*
G01X1441235Y1657160D02*
X1442772Y1657144D01*
G01X1441235Y1654010D02*
X1442772Y1653994D01*
G01X1440094Y1663469D02*
X1438785Y1663481D01*
G01X1437751Y1663495D02*
X1436420Y1663507D01*
G01X1441235Y1660310D02*
X1438785Y1660331D01*
G01X1437751Y1660346D02*
X1436420Y1660357D01*
G01X1441235Y1657160D02*
X1438785Y1657182D01*
G01X1437751Y1657196D02*
X1436420Y1657208D01*
G01X1441235Y1654010D02*
X1438785Y1654032D01*
G01X1437751Y1654046D02*
X1436420Y1654058D01*
G01X1441235Y1658111D02*
X1441007D01*
G01X1439047Y1658090D02*
X1438785D01*
G01X1439047Y1657182D02*
X1438785D01*
G01X1441235Y1657160D02*
X1441007D01*
G01X1437117Y1655208D02*
X1436111D01*
G01X1439629D02*
X1437954D01*
G01X1444153D02*
X1440467D01*
G01X1441235Y1654962D02*
X1441007D01*
G01X1439047Y1654940D02*
X1438785D01*
G01X1444153Y1654388D02*
X1436111D01*
G01X1439047Y1654032D02*
X1438785D01*
G01X1441235Y1654010D02*
X1441007D01*
G01X1441472Y1653075D02*
X1437452D01*
G01X1441472Y1652255D02*
X1437452D01*
G01X1441235Y1651812D02*
X1441007D01*
G01X1439047Y1651791D02*
X1438785D01*
G01X1440094Y1651802D02*
X1438785Y1651791D01*
G01X1441235Y1651812D02*
X1440094Y1651802D01*
G01X1437751Y1651776D02*
X1436420Y1651765D01*
G01X1442543Y1651829D02*
X1441007Y1651812D01*
G01X1442543Y1651829D02*
X1439047Y1651791D01*
G01X1441235Y1651812D02*
X1442772Y1651829D01*
G01X1439047Y1651791D02*
X1440094Y1651802D01*
G01X1438785Y1651791D02*
X1436420Y1651765D01*
G01X1437751Y1651776D02*
X1439047Y1651791D01*
G01X1440300Y1684243D02*
X1439127Y1684571D01*
G01X1439797Y1683587D02*
X1439127Y1683751D01*
G01X1438457Y1680142D02*
X1437787Y1680306D01*
G01X1438457Y1679322D02*
X1437787Y1679486D01*
G01X1440467Y1671940D02*
X1439797Y1672104D01*
G01X1440132Y1659473D02*
X1439462Y1659637D01*
G01X1438792Y1666855D02*
X1437787Y1667019D01*
G01X1437284Y1679650D02*
X1437787Y1679486D01*
G01X1439797Y1671284D02*
X1440300Y1671120D01*
G01X1439797Y1658653D02*
X1439294Y1658817D01*
G01X1426512Y1698187D02*
X1430449Y1696218D01*
G01X1437619Y1668003D02*
X1437954Y1667839D01*
G01X1437117Y1667347D02*
X1437787Y1667019D01*
G01X1439797Y1658653D02*
X1440132Y1658489D01*
G01X1436781Y1655372D02*
X1437117Y1655208D01*
G01X1440300Y1684243D02*
X1440802Y1683915D01*
G01X1439797Y1683587D02*
X1440300Y1683259D01*
G01X1437284Y1680634D02*
X1437787Y1680306D01*
G01X1436781Y1679978D02*
X1437284Y1679650D01*
G01X1437452Y1655536D02*
X1437954Y1655208D01*
G01X1440132Y1659473D02*
X1440970Y1658817D01*
G01X1440802Y1683915D02*
X1441137Y1683587D01*
G01X1440300Y1683259D02*
X1440635Y1682931D01*
G01X1436949Y1680963D02*
X1437284Y1680634D01*
G01X1436446Y1680306D02*
X1436781Y1679978D01*
G01X1440467Y1671940D02*
X1440970Y1671448D01*
G01X1437284Y1674565D02*
X1437619Y1674237D01*
G01X1436614Y1674565D02*
X1436949Y1674237D01*
G01X1437117Y1668495D02*
X1437619Y1668003D01*
G01X1436781Y1667675D02*
X1437117Y1667347D01*
G01X1437284Y1662098D02*
X1437619Y1661770D01*
G01X1436614Y1662098D02*
X1436949Y1661770D01*
G01X1436446Y1655700D02*
X1436781Y1655372D01*
G01X1440300Y1671120D02*
X1440635Y1670628D01*
G01X1436949Y1675057D02*
X1437284Y1674565D01*
G01X1436279Y1675057D02*
X1436614Y1674565D01*
G01X1436446Y1668167D02*
X1436781Y1667675D01*
G01X1440970Y1658817D02*
X1441305Y1658325D01*
G01X1440132Y1658489D02*
X1440467Y1657997D01*
G01X1436949Y1662590D02*
X1437284Y1662098D01*
G01X1436279Y1662590D02*
X1436614Y1662098D01*
G01X1437117Y1656028D02*
X1437452Y1655536D01*
G01X1441137Y1683587D02*
X1441305Y1683259D01*
G01X1440970Y1671448D02*
X1441305Y1670792D01*
G01X1436279Y1680634D02*
X1436446Y1680306D01*
G01X1436949Y1668823D02*
X1437117Y1668495D01*
G01X1436279Y1656028D02*
X1436446Y1655700D01*
G01X1436279Y1668659D02*
X1436446Y1668167D01*
G01X1441305Y1683259D02*
X1441472Y1682603D01*
G01X1440635Y1682931D02*
X1440802Y1682275D01*
G01X1436781Y1681619D02*
X1436949Y1680963D01*
G01X1436111Y1681291D02*
X1436279Y1680634D01*
G01X1441305Y1658325D02*
X1441472Y1657669D01*
G01X1436781Y1675713D02*
X1436949Y1675057D01*
G01X1436111Y1675713D02*
X1436279Y1675057D01*
G01X1440467Y1657997D02*
X1440635Y1657340D01*
G01X1436781Y1669480D02*
X1436949Y1668823D01*
G01X1436781Y1663246D02*
X1436949Y1662590D01*
G01X1436111Y1663246D02*
X1436279Y1662590D01*
G01X1436949Y1656684D02*
X1437117Y1656028D01*
G01X1436111Y1656684D02*
X1436279Y1656028D01*
G01X1441305Y1670792D02*
X1441472Y1669644D01*
G01X1440635Y1670628D02*
X1440802Y1669480D01*
G01X1436111Y1669644D02*
X1436279Y1668659D01*
G01X1441235Y1654962D02*
Y1654010D01*
G01Y1658111D02*
Y1657160D01*
G01Y1664411D02*
Y1663459D01*
G01Y1661261D02*
Y1660310D01*
G01Y1667560D02*
Y1666609D01*
G01Y1673859D02*
Y1672908D01*
G01Y1670710D02*
Y1669758D01*
G01Y1677009D02*
Y1676058D01*
G01Y1683308D02*
Y1682357D01*
G01Y1680159D02*
Y1679207D01*
G01Y1686458D02*
Y1685507D01*
G01Y1692757D02*
Y1691806D01*
G01Y1689607D02*
Y1688656D01*
G01X1441007Y1654962D02*
Y1654010D01*
G01Y1658111D02*
Y1657160D01*
G01Y1664411D02*
Y1663459D01*
G01Y1661261D02*
Y1660310D01*
G01Y1667560D02*
Y1666609D01*
G01Y1673859D02*
Y1672908D01*
G01Y1670710D02*
Y1669758D01*
G01Y1677009D02*
Y1676058D01*
G01Y1683308D02*
Y1682357D01*
G01Y1680159D02*
Y1679207D01*
G01Y1686458D02*
Y1685507D01*
G01Y1692757D02*
Y1691806D01*
G01Y1689607D02*
Y1688656D01*
G01X1440802Y1682275D02*
Y1681619D01*
G01X1440635Y1657340D02*
Y1656684D01*
G01X1439797Y1672104D02*
Y1671284D01*
G01X1438289Y1658817D02*
X1437787Y1658653D01*
G01X1439629Y1667839D02*
X1439127Y1667675D01*
G01X1437452Y1677846D02*
X1436949Y1677682D01*
G01X1437787Y1684407D02*
X1437284Y1684243D01*
G01X1437452Y1653075D02*
X1436614Y1652747D01*
G01X1437452Y1652255D02*
X1437117Y1652091D01*
G01X1440802Y1655372D02*
X1440467Y1655208D01*
G01X1437452Y1659473D02*
X1437117Y1659309D01*
G01X1437284Y1665379D02*
X1436949Y1665214D01*
G01X1440467Y1667347D02*
X1439797Y1667019D01*
G01X1439965Y1668003D02*
X1439629Y1667839D01*
G01X1441472Y1669644D02*
X1441305Y1668659D01*
G01X1436949Y1670464D02*
X1436781Y1669480D01*
G01X1436279Y1670628D02*
X1436111Y1669644D01*
G01X1439047Y1654940D02*
Y1654032D01*
G01Y1658090D02*
Y1657182D01*
G01Y1664389D02*
Y1663481D01*
G01Y1661239D02*
Y1660331D01*
G01Y1667539D02*
Y1666630D01*
G01Y1673838D02*
Y1672930D01*
G01Y1670688D02*
Y1669780D01*
G01Y1676988D02*
Y1676079D01*
G01Y1683287D02*
Y1682378D01*
G01Y1680137D02*
Y1679229D01*
G01Y1686436D02*
Y1685528D01*
G01Y1692736D02*
Y1691827D01*
G01Y1689586D02*
Y1688678D01*
G01X1438792Y1672104D02*
Y1667675D01*
G01X1438785Y1654940D02*
Y1654032D01*
G01Y1658090D02*
Y1657182D01*
G01Y1664389D02*
Y1663481D01*
G01Y1661239D02*
Y1660331D01*
G01Y1667539D02*
Y1666630D01*
G01Y1673838D02*
Y1672930D01*
G01Y1670688D02*
Y1669780D01*
G01Y1676988D02*
Y1676079D01*
G01Y1683287D02*
Y1682378D01*
G01Y1680137D02*
Y1679229D01*
G01Y1686436D02*
Y1685528D01*
G01Y1692736D02*
Y1691827D01*
G01Y1689586D02*
Y1688678D01*
G01X1438122Y1671284D02*
Y1667839D01*
G01X1437751Y1654920D02*
Y1654052D01*
G01Y1658070D02*
Y1657202D01*
G01Y1664369D02*
Y1663501D01*
G01Y1661219D02*
Y1660351D01*
G01Y1667518D02*
Y1666651D01*
G01Y1673818D02*
Y1672950D01*
G01Y1670668D02*
Y1669800D01*
G01Y1676967D02*
Y1676099D01*
G01Y1683267D02*
Y1682399D01*
G01Y1680117D02*
Y1679249D01*
G01Y1686416D02*
Y1685548D01*
G01Y1692715D02*
Y1691847D01*
G01Y1689566D02*
Y1688698D01*
G01X1436949Y1657669D02*
Y1656684D01*
G01X1436781Y1682275D02*
Y1681619D01*
G01X1436420Y1654914D02*
Y1654058D01*
G01Y1658064D02*
Y1657208D01*
G01Y1664363D02*
Y1663507D01*
G01Y1661213D02*
Y1660357D01*
G01Y1667513D02*
Y1666657D01*
G01Y1673812D02*
Y1672956D01*
G01Y1670662D02*
Y1669806D01*
G01Y1676961D02*
Y1676105D01*
G01Y1683261D02*
Y1682405D01*
G01Y1680111D02*
Y1679255D01*
G01Y1686410D02*
Y1685554D01*
G01Y1692709D02*
Y1691853D01*
G01Y1689560D02*
Y1688704D01*
G01X1436111Y1655208D02*
Y1654388D01*
G01Y1657669D02*
Y1656684D01*
G01Y1663902D02*
Y1663246D01*
G01Y1674237D02*
Y1673417D01*
G01Y1676369D02*
Y1675713D01*
G01Y1682603D02*
Y1681291D01*
G01X1433598Y1661770D02*
Y1660949D01*
G01Y1686704D02*
Y1685884D01*
G01X1426512Y1703305D02*
Y1698187D01*
G01X1440132Y1655536D02*
X1439629Y1655208D01*
G01X1437787Y1658653D02*
X1437284Y1658325D01*
G01X1437787Y1671284D02*
X1437284Y1670956D01*
G01X1440802Y1679978D02*
X1440300Y1679650D01*
G01Y1680634D02*
X1439797Y1680306D01*
G01X1437787Y1683587D02*
X1437284Y1683259D01*
G01Y1684243D02*
X1436781Y1683915D01*
G01X1437452Y1671940D02*
X1436781Y1671448D01*
G01X1441137Y1655700D02*
X1440802Y1655372D01*
G01X1437117Y1652091D02*
X1436949Y1651927D01*
G01X1436614Y1652747D02*
X1436279Y1652419D01*
G01X1437117Y1659309D02*
X1436614Y1658817D01*
G01X1440802Y1667675D02*
X1440467Y1667347D01*
G01X1437452Y1664558D02*
X1437117Y1664230D01*
G01X1440467Y1668495D02*
X1439965Y1668003D01*
G01X1436949Y1665214D02*
X1436614Y1664886D01*
G01X1441137Y1680306D02*
X1440802Y1679978D01*
G01X1437452Y1677025D02*
X1437117Y1676697D01*
G01X1440635Y1680963D02*
X1440300Y1680634D01*
G01X1436949Y1677682D02*
X1436614Y1677354D01*
G01X1437284Y1683259D02*
X1436949Y1682931D01*
G01X1436781Y1683915D02*
X1436446Y1683587D01*
G01X1440467Y1656028D02*
X1440132Y1655536D01*
G01X1436614Y1658817D02*
X1436279Y1658325D01*
G01X1441137Y1668167D02*
X1440802Y1667675D01*
G01X1436614Y1664886D02*
X1436279Y1664394D01*
G01X1437284Y1670956D02*
X1436949Y1670464D01*
G01X1436614Y1677354D02*
X1436279Y1676861D01*
G01X1436781Y1671448D02*
X1436279Y1670628D01*
G01X1441305Y1656028D02*
X1441137Y1655700D01*
G01X1436949Y1651927D02*
X1436781Y1651599D01*
G01X1437284Y1658325D02*
X1436949Y1657669D01*
G01X1440635Y1668823D02*
X1440467Y1668495D01*
G01X1437117Y1664230D02*
X1436949Y1663902D01*
G01X1441305Y1680634D02*
X1441137Y1680306D01*
G01X1437117Y1676697D02*
X1436949Y1676369D01*
G01X1436446Y1683587D02*
X1436279Y1683259D01*
G01Y1652419D02*
X1436111Y1651927D01*
G01X1441305Y1668659D02*
X1441137Y1668167D01*
G01X1436279Y1664394D02*
X1436111Y1663902D01*
G01X1436279Y1676861D02*
X1436111Y1676369D01*
G01X1441472Y1656684D02*
X1441305Y1656028D01*
G01X1440635Y1656684D02*
X1440467Y1656028D01*
G01X1440802Y1669480D02*
X1440635Y1668823D01*
G01X1436279Y1658325D02*
X1436111Y1657669D01*
G01X1441472Y1681291D02*
X1441305Y1680634D01*
G01X1436949Y1663902D02*
X1436781Y1663246D01*
G01X1440802Y1681619D02*
X1440635Y1680963D01*
G01X1436949Y1676369D02*
X1436781Y1675713D01*
G01X1436949Y1682931D02*
X1436781Y1682275D01*
G01X1436279Y1683259D02*
X1436111Y1682603D01*
G01X1470921Y1651002D02*
X1469507D01*
G01X1442772Y1650844D02*
X1442543D01*
G01X1469631Y1650746D02*
X1457535D01*
G01X1444212Y1650549D02*
X1443073D01*
G01X1457732Y1650155D02*
X1457220D01*
G01X1457732Y1649368D02*
X1457220D01*
G01X1444212Y1648974D02*
X1443073D01*
G01X1469631Y1648777D02*
X1457535D01*
G01X1442772Y1648679D02*
X1442543D01*
G01X1470921Y1648522D02*
X1469507D01*
G01X1442684Y1650757D02*
X1443073Y1650549D01*
G01X1442772Y1650844D02*
X1443243Y1650549D01*
G01X1442543Y1650844D02*
X1442684Y1650757D01*
G01X1469278Y1648777D02*
X1469507Y1648522D01*
G01X1469636Y1648792D02*
X1469855Y1648522D01*
G01X1470921Y1651671D02*
Y1651002D01*
G01X1470574Y1651671D02*
Y1651002D01*
G01X1469631Y1651927D02*
Y1650746D01*
G01X1469278Y1651927D02*
Y1650746D01*
G01X1467296Y1651927D02*
Y1650746D01*
G01X1467186Y1651927D02*
Y1650746D01*
G01X1458405Y1651927D02*
Y1650746D01*
G01X1458295Y1651927D02*
Y1650746D01*
G01X1457929Y1651927D02*
Y1650746D01*
G01X1457732D02*
Y1650155D01*
G01Y1649368D02*
Y1648777D01*
G01X1457535Y1650746D02*
Y1650155D01*
G01Y1649368D02*
Y1648777D01*
G01X1444212Y1652124D02*
Y1650549D01*
G01X1442684Y1651916D02*
Y1650757D01*
G01X1441472Y1650451D02*
Y1649630D01*
G01X1443073Y1648974D02*
X1442684Y1648767D01*
G01X1443243Y1648974D02*
X1442772Y1648679D01*
G01X1442684Y1648767D02*
X1442543Y1648679D01*
G01X1469507Y1651002D02*
X1469278Y1650746D01*
G01X1469855Y1651002D02*
X1469636Y1650732D01*
G01X1469048Y1723384D02*
G03Y1714722I-17J-4331D01*
G01X1469081Y1714723D02*
G03Y1723383I-50J4330D01*
G01X1473362Y1719053D02*
G03I-4331J0D01*
G01X1479661Y1714722D02*
X1469031D01*
G01X1479661Y1703305D02*
X1461157D01*
G01X1457732Y1693463D02*
X1457220D01*
G01X1444212Y1693069D02*
X1443073D01*
G01X1469631Y1692872D02*
X1457535D01*
G01X1442772Y1692774D02*
X1442543D01*
G01X1470921Y1692616D02*
X1469507D01*
G01X1470921Y1691947D02*
X1469507D01*
G01X1442772Y1691789D02*
X1442543D01*
G01X1469631Y1691691D02*
X1457535D01*
G01X1444212Y1691494D02*
X1443073D01*
G01X1457732Y1691100D02*
X1457220D01*
G01X1457732Y1690313D02*
X1457220D01*
G01X1444212Y1689919D02*
X1443073D01*
G01X1469631Y1689722D02*
X1457535D01*
G01X1442772Y1689624D02*
X1442543D01*
G01X1470921Y1689466D02*
X1469507D01*
G01X1470921Y1688797D02*
X1469507D01*
G01X1442772Y1688640D02*
X1442543D01*
G01X1469631Y1688541D02*
X1457535D01*
G01X1444212Y1688344D02*
X1443073D01*
G01X1457732Y1687951D02*
X1457220D01*
G01X1457732Y1687163D02*
X1457220D01*
G01X1444212Y1686770D02*
X1443073D01*
G01X1469631Y1686573D02*
X1457535D01*
G01X1442772Y1686474D02*
X1442543D01*
G01X1470921Y1686317D02*
X1469507D01*
G01X1470921Y1685648D02*
X1469507D01*
G01X1442772Y1685490D02*
X1442543D01*
G01X1469631Y1685392D02*
X1457535D01*
G01X1444212Y1685195D02*
X1443073D01*
G01X1457732Y1684801D02*
X1457220D01*
G01X1457732Y1684014D02*
X1457220D01*
G01X1444212Y1683620D02*
X1443073D01*
G01X1469631Y1683423D02*
X1457535D01*
G01X1442772Y1683325D02*
X1442543D01*
G01X1470921Y1683167D02*
X1469507D01*
G01X1470921Y1682498D02*
X1469507D01*
G01X1442772Y1682340D02*
X1442543D01*
G01X1469631Y1682242D02*
X1457535D01*
G01X1444212Y1682045D02*
X1443073D01*
G01X1457732Y1681651D02*
X1457220D01*
G01X1457732Y1680864D02*
X1457220D01*
G01X1444212Y1680470D02*
X1443073D01*
G01X1469631Y1680274D02*
X1457535D01*
G01X1442772Y1680175D02*
X1442543D01*
G01X1470921Y1680018D02*
X1469507D01*
G01X1470921Y1679348D02*
X1469507D01*
G01X1442772Y1679191D02*
X1442543D01*
G01X1469631Y1679092D02*
X1457535D01*
G01X1444212Y1678896D02*
X1443073D01*
G01X1457732Y1678502D02*
X1457220D01*
G01X1457732Y1677714D02*
X1457220D01*
G01X1444212Y1677321D02*
X1443073D01*
G01X1469631Y1677124D02*
X1457535D01*
G01X1442772Y1677025D02*
X1442543D01*
G01X1470921Y1676868D02*
X1469507D01*
G01X1470921Y1676199D02*
X1469507D01*
G01X1442772Y1676041D02*
X1442543D01*
G01X1469631Y1675943D02*
X1457535D01*
G01X1444212Y1675746D02*
X1443073D01*
G01X1457732Y1675352D02*
X1457220D01*
G01X1457732Y1674565D02*
X1457220D01*
G01X1444212Y1674171D02*
X1443073D01*
G01X1469631Y1673974D02*
X1457535D01*
G01X1442772Y1673876D02*
X1442543D01*
G01X1470921Y1673718D02*
X1469507D01*
G01X1470921Y1673049D02*
X1469507D01*
G01X1442772Y1672892D02*
X1442543D01*
G01X1469631Y1672793D02*
X1457535D01*
G01X1444212Y1672596D02*
X1443073D01*
G01X1457732Y1672203D02*
X1457220D01*
G01X1457732Y1671415D02*
X1457220D01*
G01X1444212Y1671022D02*
X1443073D01*
G01X1469631Y1670825D02*
X1457535D01*
G01X1442772Y1670726D02*
X1442543D01*
G01X1470921Y1670569D02*
X1469507D01*
G01X1470921Y1669900D02*
X1469507D01*
G01X1442772Y1669742D02*
X1442543D01*
G01X1469631Y1669644D02*
X1457535D01*
G01X1444212Y1669447D02*
X1443073D01*
G01X1457732Y1669053D02*
X1457220D01*
G01X1457732Y1668266D02*
X1457220D01*
G01X1444212Y1667872D02*
X1443073D01*
G01X1469631Y1667675D02*
X1457535D01*
G01X1442772Y1667577D02*
X1442543D01*
G01X1470921Y1667419D02*
X1469507D01*
G01X1470921Y1666750D02*
X1469507D01*
G01X1442772Y1666592D02*
X1442543D01*
G01X1469631Y1666494D02*
X1457535D01*
G01X1444212Y1666297D02*
X1443073D01*
G01X1457732Y1665903D02*
X1457220D01*
G01X1457732Y1665116D02*
X1457220D01*
G01X1444212Y1664722D02*
X1443073D01*
G01X1469631Y1664525D02*
X1457535D01*
G01X1442772Y1664427D02*
X1442543D01*
G01X1470921Y1664270D02*
X1469507D01*
G01X1470921Y1663600D02*
X1469507D01*
G01X1442772Y1663443D02*
X1442543D01*
G01X1469631Y1663344D02*
X1457535D01*
G01X1444212Y1663148D02*
X1443073D01*
G01X1457732Y1662754D02*
X1457220D01*
G01X1457732Y1661966D02*
X1457220D01*
G01X1444212Y1661573D02*
X1443073D01*
G01X1469631Y1661376D02*
X1457535D01*
G01X1442772Y1661277D02*
X1442543D01*
G01X1470921Y1661120D02*
X1469507D01*
G01X1470921Y1660451D02*
X1469507D01*
G01X1442772Y1660293D02*
X1442543D01*
G01X1469631Y1660195D02*
X1457535D01*
G01X1444212Y1659998D02*
X1443073D01*
G01X1457732Y1659604D02*
X1457220D01*
G01X1457732Y1658817D02*
X1457220D01*
G01X1469038Y1714722D02*
X1448165Y1714329D01*
G01X1469113Y1714723D02*
X1448165Y1714329D01*
G01X1444212Y1658423D02*
X1443073D01*
G01X1469631Y1658226D02*
X1457535D01*
G01X1442772Y1658128D02*
X1442543D01*
G01X1470921Y1657970D02*
X1469507D01*
G01X1470921Y1657301D02*
X1469507D01*
G01X1442772Y1657144D02*
X1442543D01*
G01X1469631Y1657045D02*
X1457535D01*
G01X1444212Y1656848D02*
X1443073D01*
G01X1457732Y1656455D02*
X1457220D01*
G01X1457732Y1655667D02*
X1457220D01*
G01X1444212Y1655274D02*
X1443073D01*
G01X1469631Y1655077D02*
X1457535D01*
G01X1442772Y1654978D02*
X1442543D01*
G01X1470921Y1654821D02*
X1469507D01*
G01X1470921Y1654151D02*
X1469507D01*
G01X1442772Y1653994D02*
X1442543D01*
G01X1469631Y1653896D02*
X1457535D01*
G01X1444212Y1653699D02*
X1443073D01*
G01X1457732Y1653305D02*
X1457220D01*
G01X1457732Y1652518D02*
X1457220D01*
G01X1444212Y1652124D02*
X1443073D01*
G01X1469631Y1651927D02*
X1457535D01*
G01X1442772Y1651829D02*
X1442543D01*
G01X1470921Y1651671D02*
X1469507D01*
G01X1496457Y1665049D02*
X1493047Y1667018D01*
G01X1442684Y1691701D02*
X1443073Y1691494D01*
G01X1442684Y1688552D02*
X1443073Y1688344D01*
G01X1442684Y1685402D02*
X1443073Y1685195D01*
G01X1442684Y1682253D02*
X1443073Y1682045D01*
G01X1442684Y1679103D02*
X1443073Y1678896D01*
G01X1442684Y1675953D02*
X1443073Y1675746D01*
G01X1442684Y1672804D02*
X1443073Y1672596D01*
G01X1442684Y1669654D02*
X1443073Y1669447D01*
G01X1442684Y1666505D02*
X1443073Y1666297D01*
G01X1442684Y1663355D02*
X1443073Y1663148D01*
G01X1442684Y1660205D02*
X1443073Y1659998D01*
G01X1442684Y1657056D02*
X1443073Y1656848D01*
G01X1442684Y1653906D02*
X1443073Y1653699D01*
G01X1442772Y1691789D02*
X1443243Y1691494D01*
G01X1442543Y1691789D02*
X1442684Y1691701D01*
G01X1442772Y1688640D02*
X1443243Y1688344D01*
G01X1442543Y1688640D02*
X1442684Y1688552D01*
G01X1442772Y1685490D02*
X1443243Y1685195D01*
G01X1442543Y1685490D02*
X1442684Y1685402D01*
G01X1442772Y1682340D02*
X1443243Y1682045D01*
G01X1442543Y1682340D02*
X1442684Y1682253D01*
G01X1442772Y1679191D02*
X1443243Y1678896D01*
G01X1442543Y1679191D02*
X1442684Y1679103D01*
G01X1442772Y1676041D02*
X1443243Y1675746D01*
G01X1442543Y1676041D02*
X1442684Y1675953D01*
G01X1442772Y1672892D02*
X1443243Y1672596D01*
G01X1442543Y1672892D02*
X1442684Y1672804D01*
G01X1442772Y1669742D02*
X1443243Y1669447D01*
G01X1442543Y1669742D02*
X1442684Y1669654D01*
G01X1442772Y1666592D02*
X1443243Y1666297D01*
G01X1442543Y1666592D02*
X1442684Y1666505D01*
G01X1442772Y1663443D02*
X1443243Y1663148D01*
G01X1442543Y1663443D02*
X1442684Y1663355D01*
G01X1442772Y1660293D02*
X1443243Y1659998D01*
G01X1442543Y1660293D02*
X1442684Y1660205D01*
G01X1442772Y1657144D02*
X1443243Y1656848D01*
G01X1442543Y1657144D02*
X1442684Y1657056D01*
G01X1442772Y1653994D02*
X1443243Y1653699D01*
G01X1442543Y1653994D02*
X1442684Y1653906D01*
G01X1469636Y1692886D02*
X1469855Y1692616D01*
G01X1469636Y1689736D02*
X1469855Y1689466D01*
G01X1469636Y1686587D02*
X1469855Y1686317D01*
G01X1469636Y1683437D02*
X1469855Y1683167D01*
G01X1469636Y1680288D02*
X1469855Y1680018D01*
G01X1469636Y1677138D02*
X1469855Y1676868D01*
G01X1469636Y1673988D02*
X1469855Y1673718D01*
G01X1469636Y1670839D02*
X1469855Y1670569D01*
G01X1469636Y1667689D02*
X1469855Y1667419D01*
G01X1469636Y1664540D02*
X1469855Y1664270D01*
G01X1469636Y1661390D02*
X1469855Y1661120D01*
G01X1469636Y1658240D02*
X1469855Y1657970D01*
G01X1469636Y1655091D02*
X1469855Y1654821D01*
G01X1469636Y1651941D02*
X1469855Y1651671D01*
G01X1469278Y1692872D02*
X1469507Y1692616D01*
G01X1469278Y1689722D02*
X1469507Y1689466D01*
G01X1469278Y1686573D02*
X1469507Y1686317D01*
G01X1469278Y1683423D02*
X1469507Y1683167D01*
G01X1469278Y1680274D02*
X1469507Y1680018D01*
G01X1469278Y1677124D02*
X1469507Y1676868D01*
G01X1469278Y1673974D02*
X1469507Y1673718D01*
G01X1469278Y1670825D02*
X1469507Y1670569D01*
G01X1469278Y1667675D02*
X1469507Y1667419D01*
G01X1469278Y1664525D02*
X1469507Y1664270D01*
G01X1469278Y1661376D02*
X1469507Y1661120D01*
G01X1469278Y1658226D02*
X1469507Y1657970D01*
G01X1469278Y1655077D02*
X1469507Y1654821D01*
G01X1469278Y1651927D02*
X1469507Y1651671D01*
G01X1493047Y1667018D02*
Y1668750D01*
G01X1479661Y1732833D02*
Y1703305D01*
G01X1470921Y1654821D02*
Y1654151D01*
G01Y1657970D02*
Y1657301D01*
G01Y1664270D02*
Y1663600D01*
G01Y1661120D02*
Y1660451D01*
G01Y1667419D02*
Y1666750D01*
G01Y1673718D02*
Y1673049D01*
G01Y1670569D02*
Y1669900D01*
G01Y1676868D02*
Y1676199D01*
G01Y1683167D02*
Y1682498D01*
G01Y1680018D02*
Y1679348D01*
G01Y1686317D02*
Y1685648D01*
G01Y1692616D02*
Y1691947D01*
G01Y1689466D02*
Y1688797D01*
G01X1470574Y1654821D02*
Y1654151D01*
G01Y1657970D02*
Y1657301D01*
G01Y1664270D02*
Y1663600D01*
G01Y1661120D02*
Y1660451D01*
G01Y1667419D02*
Y1666750D01*
G01Y1673718D02*
Y1673049D01*
G01Y1670569D02*
Y1669900D01*
G01Y1676868D02*
Y1676199D01*
G01Y1683167D02*
Y1682498D01*
G01Y1680018D02*
Y1679348D01*
G01Y1686317D02*
Y1685648D01*
G01Y1692616D02*
Y1691947D01*
G01Y1689466D02*
Y1688797D01*
G01X1469631Y1655077D02*
Y1653896D01*
G01Y1658226D02*
Y1657045D01*
G01Y1664525D02*
Y1663344D01*
G01Y1661376D02*
Y1660195D01*
G01Y1667675D02*
Y1666494D01*
G01Y1673974D02*
Y1672793D01*
G01Y1670825D02*
Y1669644D01*
G01Y1677124D02*
Y1675943D01*
G01Y1683423D02*
Y1682242D01*
G01Y1680274D02*
Y1679092D01*
G01Y1686573D02*
Y1685392D01*
G01Y1692872D02*
Y1691691D01*
G01Y1689722D02*
Y1688541D01*
G01X1469278Y1655077D02*
Y1653896D01*
G01Y1658226D02*
Y1657045D01*
G01Y1664525D02*
Y1663344D01*
G01Y1661376D02*
Y1660195D01*
G01Y1667675D02*
Y1666494D01*
G01Y1673974D02*
Y1672793D01*
G01Y1670825D02*
Y1669644D01*
G01Y1677124D02*
Y1675943D01*
G01Y1683423D02*
Y1682242D01*
G01Y1680274D02*
Y1679092D01*
G01Y1686573D02*
Y1685392D01*
G01Y1692872D02*
Y1691691D01*
G01Y1689722D02*
Y1688541D01*
G01X1467296Y1655077D02*
Y1653896D01*
G01Y1658226D02*
Y1657045D01*
G01Y1664525D02*
Y1663344D01*
G01Y1661376D02*
Y1660195D01*
G01Y1667675D02*
Y1666494D01*
G01Y1673974D02*
Y1672793D01*
G01Y1670825D02*
Y1669644D01*
G01Y1677124D02*
Y1675943D01*
G01Y1683423D02*
Y1682242D01*
G01Y1680274D02*
Y1679092D01*
G01Y1686573D02*
Y1685392D01*
G01Y1692872D02*
Y1691691D01*
G01Y1689722D02*
Y1688541D01*
G01X1467186Y1655077D02*
Y1653896D01*
G01Y1658226D02*
Y1657045D01*
G01Y1664525D02*
Y1663344D01*
G01Y1661376D02*
Y1660195D01*
G01Y1667675D02*
Y1666494D01*
G01Y1673974D02*
Y1672793D01*
G01Y1670825D02*
Y1669644D01*
G01Y1677124D02*
Y1675943D01*
G01Y1683423D02*
Y1682242D01*
G01Y1680274D02*
Y1679092D01*
G01Y1686573D02*
Y1685392D01*
G01Y1692872D02*
Y1691691D01*
G01Y1689722D02*
Y1688541D01*
G01X1458405Y1655077D02*
Y1653896D01*
G01Y1658226D02*
Y1657045D01*
G01Y1664525D02*
Y1663344D01*
G01Y1661376D02*
Y1660195D01*
G01Y1667675D02*
Y1666494D01*
G01Y1673974D02*
Y1672793D01*
G01Y1670825D02*
Y1669644D01*
G01Y1677124D02*
Y1675943D01*
G01Y1683423D02*
Y1682242D01*
G01Y1680274D02*
Y1679092D01*
G01Y1686573D02*
Y1685392D01*
G01Y1692872D02*
Y1691691D01*
G01Y1689722D02*
Y1688541D01*
G01X1458295Y1655077D02*
Y1653896D01*
G01Y1658226D02*
Y1657045D01*
G01Y1664525D02*
Y1663344D01*
G01Y1661376D02*
Y1660195D01*
G01Y1667675D02*
Y1666494D01*
G01Y1673974D02*
Y1672793D01*
G01Y1670825D02*
Y1669644D01*
G01Y1677124D02*
Y1675943D01*
G01Y1683423D02*
Y1682242D01*
G01Y1680274D02*
Y1679092D01*
G01Y1686573D02*
Y1685392D01*
G01Y1692872D02*
Y1691691D01*
G01Y1689722D02*
Y1688541D01*
G01X1457929Y1655077D02*
Y1653896D01*
G01Y1658226D02*
Y1657045D01*
G01Y1664525D02*
Y1663344D01*
G01Y1661376D02*
Y1660195D01*
G01Y1667675D02*
Y1666494D01*
G01Y1673974D02*
Y1672793D01*
G01Y1670825D02*
Y1669644D01*
G01Y1677124D02*
Y1675943D01*
G01Y1683423D02*
Y1682242D01*
G01Y1680274D02*
Y1679092D01*
G01Y1686573D02*
Y1685392D01*
G01Y1692872D02*
Y1691691D01*
G01Y1689722D02*
Y1688541D01*
G01X1457732Y1653896D02*
Y1653305D01*
G01Y1655667D02*
Y1655077D01*
G01Y1652518D02*
Y1651927D01*
G01Y1660195D02*
Y1659604D01*
G01Y1657045D02*
Y1656455D01*
G01Y1658817D02*
Y1658226D01*
G01Y1663344D02*
Y1662754D01*
G01Y1665116D02*
Y1664525D01*
G01Y1661966D02*
Y1661376D01*
G01Y1669644D02*
Y1669053D01*
G01Y1666494D02*
Y1665903D01*
G01Y1668266D02*
Y1667675D01*
G01Y1672793D02*
Y1672203D01*
G01Y1674565D02*
Y1673974D01*
G01Y1671415D02*
Y1670825D01*
G01Y1679092D02*
Y1678502D01*
G01Y1675943D02*
Y1675352D01*
G01Y1677714D02*
Y1677124D01*
G01Y1682242D02*
Y1681651D01*
G01Y1680864D02*
Y1680274D01*
G01Y1688541D02*
Y1687951D01*
G01Y1685392D02*
Y1684801D01*
G01Y1687163D02*
Y1686573D01*
G01Y1684014D02*
Y1683423D01*
G01Y1691691D02*
Y1691100D01*
G01Y1690313D02*
Y1689722D01*
G01Y1693463D02*
Y1692872D01*
G01X1457535Y1653896D02*
Y1653305D01*
G01Y1655667D02*
Y1655077D01*
G01Y1652518D02*
Y1651927D01*
G01Y1660195D02*
Y1659604D01*
G01Y1657045D02*
Y1656455D01*
G01Y1658817D02*
Y1658226D01*
G01Y1663344D02*
Y1662754D01*
G01Y1665116D02*
Y1664525D01*
G01Y1661966D02*
Y1661376D01*
G01Y1669644D02*
Y1669053D01*
G01Y1666494D02*
Y1665903D01*
G01Y1668266D02*
Y1667675D01*
G01Y1672793D02*
Y1672203D01*
G01Y1674565D02*
Y1673974D01*
G01Y1671415D02*
Y1670825D01*
G01Y1679092D02*
Y1678502D01*
G01Y1675943D02*
Y1675352D01*
G01Y1677714D02*
Y1677124D01*
G01Y1682242D02*
Y1681651D01*
G01Y1680864D02*
Y1680274D01*
G01Y1688541D02*
Y1687951D01*
G01Y1685392D02*
Y1684801D01*
G01Y1687163D02*
Y1686573D01*
G01Y1684014D02*
Y1683423D01*
G01Y1691691D02*
Y1691100D01*
G01Y1690313D02*
Y1689722D01*
G01Y1693463D02*
Y1692872D01*
G01X1448165Y1732833D02*
Y1711966D01*
G01X1444212Y1655274D02*
Y1653699D01*
G01Y1658423D02*
Y1656848D01*
G01Y1664722D02*
Y1663148D01*
G01Y1661573D02*
Y1659998D01*
G01Y1667872D02*
Y1666297D01*
G01Y1674171D02*
Y1672596D01*
G01Y1671022D02*
Y1669447D01*
G01Y1677321D02*
Y1675746D01*
G01Y1683620D02*
Y1682045D01*
G01Y1680470D02*
Y1678896D01*
G01Y1686770D02*
Y1685195D01*
G01Y1693069D02*
Y1691494D01*
G01Y1689919D02*
Y1688344D01*
G01X1444153Y1655208D02*
Y1654388D01*
G01X1442684Y1655066D02*
Y1653906D01*
G01Y1658216D02*
Y1657056D01*
G01Y1664515D02*
Y1663355D01*
G01Y1661365D02*
Y1660205D01*
G01Y1667664D02*
Y1666505D01*
G01Y1673964D02*
Y1672804D01*
G01Y1670814D02*
Y1669654D01*
G01Y1677113D02*
Y1675953D01*
G01Y1683413D02*
Y1682253D01*
G01Y1680263D02*
Y1679103D01*
G01Y1686562D02*
Y1685402D01*
G01Y1692861D02*
Y1691701D01*
G01Y1689712D02*
Y1688552D01*
G01X1441472Y1653075D02*
Y1652255D01*
G01Y1657669D02*
Y1656684D01*
G01Y1661770D02*
Y1660949D01*
G01Y1665543D02*
Y1664722D01*
G01Y1674237D02*
Y1673417D01*
G01Y1678010D02*
Y1677190D01*
G01Y1682603D02*
Y1681291D01*
G01Y1686704D02*
Y1685884D01*
G01X1443073Y1652124D02*
X1442684Y1651916D01*
G01X1443073Y1655274D02*
X1442684Y1655066D01*
G01X1443073Y1658423D02*
X1442684Y1658216D01*
G01X1443073Y1661573D02*
X1442684Y1661365D01*
G01X1443073Y1664722D02*
X1442684Y1664515D01*
G01X1443073Y1667872D02*
X1442684Y1667664D01*
G01X1443073Y1671022D02*
X1442684Y1670814D01*
G01X1443073Y1674171D02*
X1442684Y1673964D01*
G01X1443073Y1677321D02*
X1442684Y1677113D01*
G01X1443073Y1680470D02*
X1442684Y1680263D01*
G01X1443073Y1683620D02*
X1442684Y1683413D01*
G01X1443073Y1686770D02*
X1442684Y1686562D01*
G01X1443073Y1689919D02*
X1442684Y1689712D01*
G01X1443073Y1693069D02*
X1442684Y1692861D01*
G01X1443243Y1652124D02*
X1442772Y1651829D01*
G01X1442684Y1651916D02*
X1442543Y1651829D01*
G01X1443243Y1655274D02*
X1442772Y1654978D01*
G01X1442684Y1655066D02*
X1442543Y1654978D01*
G01X1443243Y1658423D02*
X1442772Y1658128D01*
G01X1442684Y1658216D02*
X1442543Y1658128D01*
G01X1443243Y1661573D02*
X1442772Y1661277D01*
G01X1442684Y1661365D02*
X1442543Y1661277D01*
G01X1443243Y1664722D02*
X1442772Y1664427D01*
G01X1442684Y1664515D02*
X1442543Y1664427D01*
G01X1443243Y1667872D02*
X1442772Y1667577D01*
G01X1442684Y1667664D02*
X1442543Y1667577D01*
G01X1443243Y1671022D02*
X1442772Y1670726D01*
G01X1442684Y1670814D02*
X1442543Y1670726D01*
G01X1443243Y1674171D02*
X1442772Y1673876D01*
G01X1442684Y1673964D02*
X1442543Y1673876D01*
G01X1443243Y1677321D02*
X1442772Y1677025D01*
G01X1442684Y1677113D02*
X1442543Y1677025D01*
G01X1443243Y1680470D02*
X1442772Y1680175D01*
G01X1442684Y1680263D02*
X1442543Y1680175D01*
G01X1443243Y1683620D02*
X1442772Y1683325D01*
G01X1442684Y1683413D02*
X1442543Y1683325D01*
G01X1443243Y1686770D02*
X1442772Y1686474D01*
G01X1442684Y1686562D02*
X1442543Y1686474D01*
G01X1443243Y1689919D02*
X1442772Y1689624D01*
G01X1442684Y1689712D02*
X1442543Y1689624D01*
G01X1443243Y1693069D02*
X1442772Y1692774D01*
G01X1442684Y1692861D02*
X1442543Y1692774D01*
G01X1497767Y1672288D02*
X1493047Y1667647D01*
G01Y1668750D02*
X1497772Y1673396D01*
G01X1461157Y1703305D02*
X1457220Y1699368D01*
G01X1469507Y1654151D02*
X1469278Y1653896D01*
G01X1469507Y1657301D02*
X1469278Y1657045D01*
G01X1469507Y1660451D02*
X1469278Y1660195D01*
G01X1469507Y1663600D02*
X1469278Y1663344D01*
G01X1469507Y1666750D02*
X1469278Y1666494D01*
G01X1469507Y1669900D02*
X1469278Y1669644D01*
G01X1469507Y1673049D02*
X1469278Y1672793D01*
G01X1469507Y1676199D02*
X1469278Y1675943D01*
G01X1469507Y1679348D02*
X1469278Y1679092D01*
G01X1469507Y1682498D02*
X1469278Y1682242D01*
G01X1469507Y1685648D02*
X1469278Y1685392D01*
G01X1469507Y1688797D02*
X1469278Y1688541D01*
G01X1469507Y1691947D02*
X1469278Y1691691D01*
G01X1469855Y1654151D02*
X1469636Y1653881D01*
G01X1469855Y1657301D02*
X1469636Y1657031D01*
G01X1469855Y1660451D02*
X1469636Y1660181D01*
G01X1469855Y1663600D02*
X1469636Y1663330D01*
G01X1469855Y1666750D02*
X1469636Y1666480D01*
G01X1469855Y1669900D02*
X1469636Y1669629D01*
G01X1469855Y1673049D02*
X1469636Y1672779D01*
G01X1469855Y1676199D02*
X1469636Y1675929D01*
G01X1469855Y1679348D02*
X1469636Y1679078D01*
G01X1469855Y1682498D02*
X1469636Y1682228D01*
G01X1469855Y1685648D02*
X1469636Y1685378D01*
G01X1469855Y1688797D02*
X1469636Y1688527D01*
G01X1469855Y1691947D02*
X1469636Y1691677D01*
G01X1439047Y1791040D02*
X1442543Y1791002D01*
G01X1437751Y1791054D02*
X1441007Y1791018D01*
G01X1439047Y1787890D02*
X1442543Y1787852D01*
G01X1437751Y1787905D02*
X1441007Y1787869D01*
G01X1439047Y1784741D02*
X1442543Y1784703D01*
G01X1437751Y1784755D02*
X1441007Y1784719D01*
G01X1438785Y1791040D02*
X1436420Y1791066D01*
G01X1438785Y1787890D02*
X1436420Y1787916D01*
G01X1438785Y1784741D02*
X1436420Y1784767D01*
G01X1441235Y1791018D02*
X1442772Y1791002D01*
G01X1441235Y1787869D02*
X1442772Y1787852D01*
G01X1441235Y1784719D02*
X1442772Y1784703D01*
G01X1441235Y1791018D02*
X1438785Y1791040D01*
G01X1437751Y1791054D02*
X1436420Y1791066D01*
G01X1441235Y1787869D02*
X1438785Y1787890D01*
G01X1437751Y1787905D02*
X1436420Y1787916D01*
G01X1441235Y1784719D02*
X1438785Y1784741D01*
G01X1437751Y1784755D02*
X1436420Y1784767D01*
G01X1441235Y1791970D02*
X1441007D01*
G01X1439047Y1791948D02*
X1438785D01*
G01X1439047Y1791040D02*
X1438785D01*
G01X1441235Y1791018D02*
X1441007D01*
G01X1441235Y1788820D02*
X1441007D01*
G01X1439047Y1788798D02*
X1438785D01*
G01X1439047Y1787890D02*
X1438785D01*
G01X1441235Y1787869D02*
X1441007D01*
G01X1441235Y1785670D02*
X1441007D01*
G01X1439047Y1785649D02*
X1438785D01*
G01X1439047Y1784741D02*
X1438785D01*
G01X1441235Y1784719D02*
X1441007D01*
G01X1449937Y1781258D02*
X1430449D01*
G01X1440094Y1791960D02*
X1438785Y1791948D01*
G01X1441235Y1791970D02*
X1440094Y1791960D01*
G01Y1788810D02*
X1438785Y1788798D01*
G01X1441235Y1788820D02*
X1440094Y1788810D01*
G01Y1785660D02*
X1438785Y1785649D01*
G01X1441235Y1785670D02*
X1440094Y1785660D01*
G01X1437751Y1791934D02*
X1436420Y1791922D01*
G01X1437751Y1788784D02*
X1436420Y1788772D01*
G01X1437751Y1785635D02*
X1436420Y1785623D01*
G01X1442543Y1791986D02*
X1441007Y1791970D01*
G01X1442543Y1791986D02*
X1439047Y1791948D01*
G01X1441235Y1791970D02*
X1442772Y1791986D01*
G01X1442543Y1788837D02*
X1441007Y1788820D01*
G01X1442543Y1788837D02*
X1439047Y1788799D01*
G01X1441235Y1788820D02*
X1442772Y1788837D01*
G01X1442543Y1785687D02*
X1441007Y1785670D01*
G01X1442543Y1785687D02*
X1439047Y1785649D01*
G01X1441235Y1785670D02*
X1442772Y1785687D01*
G01X1439047Y1791948D02*
X1440094Y1791960D01*
G01X1438785Y1791948D02*
X1436420Y1791922D01*
G01X1437751Y1791934D02*
X1439047Y1791948D01*
G01Y1788798D02*
X1440094Y1788810D01*
G01X1438785Y1788798D02*
X1436420Y1788772D01*
G01X1437751Y1788784D02*
X1439047Y1788798D01*
G01Y1785649D02*
X1440094Y1785660D01*
G01X1438785Y1785649D02*
X1436420Y1785623D01*
G01X1437751Y1785635D02*
X1439047Y1785649D01*
G01X1426512Y1786770D02*
X1429239Y1785195D01*
G01X1441235Y1785670D02*
Y1784719D01*
G01Y1788820D02*
Y1787869D01*
G01Y1791970D02*
Y1791018D01*
G01X1441007Y1785670D02*
Y1784719D01*
G01Y1788820D02*
Y1787869D01*
G01Y1791970D02*
Y1791018D01*
G01X1439047Y1785649D02*
Y1784741D01*
G01Y1788799D02*
Y1787890D01*
G01Y1791948D02*
Y1791040D01*
G01X1438785Y1785649D02*
Y1784741D01*
G01Y1788799D02*
Y1787890D01*
G01Y1791948D02*
Y1791040D01*
G01X1437751Y1785629D02*
Y1784761D01*
G01Y1788778D02*
Y1787910D01*
G01Y1791928D02*
Y1791060D01*
G01X1436420Y1785623D02*
Y1784767D01*
G01Y1788772D02*
Y1787916D01*
G01Y1791922D02*
Y1791066D01*
G01X1430449Y1924565D02*
Y1783226D01*
G01X1426512Y1779289D02*
Y1774171D01*
G01Y2111573D02*
Y1783226D01*
G01X1430449Y1781258D02*
X1426512Y1779289D01*
G01X1429239Y1785195D02*
X1426512Y1783620D01*
G01X1469113Y1723383D02*
X1448165Y1723777D01*
G01D02*
X1469034Y1723384D01*
G01X1479661D02*
X1469031D01*
G01X1469048Y1762754D02*
G03Y1754092I-17J-4331D01*
G01X1469081Y1754093D02*
G03Y1762754I-50J4331D01*
G01X1473362Y1758423D02*
G03I-4331J0D01*
G01X1469113Y1762753D02*
X1448165Y1763148D01*
G01X1469038Y1762754D02*
X1448165Y1763148D01*
G01X1457732Y1793463D02*
X1457220D01*
G01X1457732Y1792675D02*
X1457220D01*
G01X1444212Y1792281D02*
X1443073D01*
G01X1469631Y1792085D02*
X1457535D01*
G01X1442772Y1791986D02*
X1442543D01*
G01X1470921Y1791829D02*
X1469507D01*
G01X1470921Y1791159D02*
X1469507D01*
G01X1442772Y1791002D02*
X1442543D01*
G01X1469631Y1790903D02*
X1457535D01*
G01X1444212Y1790707D02*
X1443073D01*
G01X1457732Y1790313D02*
X1457220D01*
G01X1457732Y1789525D02*
X1457220D01*
G01X1444212Y1789132D02*
X1443073D01*
G01X1469631Y1788935D02*
X1457535D01*
G01X1442772Y1788837D02*
X1442543D01*
G01X1470921Y1788679D02*
X1469507D01*
G01X1470921Y1788010D02*
X1469507D01*
G01X1442772Y1787852D02*
X1442543D01*
G01X1469631Y1787754D02*
X1457535D01*
G01X1444212Y1787557D02*
X1443073D01*
G01X1457732Y1787163D02*
X1457220D01*
G01X1457732Y1786376D02*
X1457220D01*
G01X1461157Y1786179D02*
X1471000D01*
G01X1444212Y1785982D02*
X1443073D01*
G01X1469631Y1785785D02*
X1457535D01*
G01X1442772Y1785687D02*
X1442543D01*
G01X1470921Y1785529D02*
X1469507D01*
G01X1470921Y1784860D02*
X1469507D01*
G01X1442772Y1784703D02*
X1442543D01*
G01X1469631Y1784604D02*
X1457535D01*
G01X1444212Y1784407D02*
X1443073D01*
G01X1474613Y1784289D02*
X1474975D01*
G01X1471000Y1784211D02*
X1461157D01*
G01X1473165Y1784024D02*
X1474929D01*
G01X1457732Y1784014D02*
X1457220D01*
G01X1475291Y1783758D02*
X1473165D01*
G01X1479661Y1774171D02*
X1461157D01*
G01X1479661Y1762754D02*
X1469031D01*
G01X1479661Y1754092D02*
X1469031D01*
G01X1479661Y1744644D02*
X1448165D01*
G01Y1753699D02*
X1469034Y1754092D01*
G01X1469113Y1754093D02*
X1448165Y1753699D01*
G01X1479661Y1732833D02*
X1448165D01*
G01X1473165Y1786415D02*
X1475291Y1785707D01*
G01X1473889Y1785928D02*
X1475110Y1785529D01*
G01X1473708Y1785972D02*
X1473165Y1786150D01*
G01X1442772Y1791002D02*
X1443243Y1790707D01*
G01X1442543Y1791002D02*
X1442684Y1790914D01*
G01X1442772Y1787852D02*
X1443243Y1787557D01*
G01X1442543Y1787852D02*
X1442684Y1787764D01*
G01Y1790914D02*
X1443073Y1790707D01*
G01X1442684Y1787764D02*
X1443073Y1787557D01*
G01X1442684Y1784615D02*
X1443073Y1784407D01*
G01X1442772Y1784703D02*
X1443243Y1784407D01*
G01X1442543Y1784703D02*
X1442684Y1784615D01*
G01X1474975Y1784289D02*
X1475291Y1784024D01*
G01X1474929D02*
X1474613Y1784289D01*
G01X1469636Y1792099D02*
X1469855Y1791829D01*
G01X1469636Y1788949D02*
X1469855Y1788679D01*
G01X1469636Y1785799D02*
X1469855Y1785529D01*
G01X1469278Y1792085D02*
X1469507Y1791829D01*
G01X1469278Y1788935D02*
X1469507Y1788679D01*
G01X1469278Y1785785D02*
X1469507Y1785529D01*
G01X1457220Y1778108D02*
X1461157Y1774171D01*
G01X1479661D02*
Y1744644D01*
G01X1475291Y1784024D02*
Y1783758D01*
G01Y1785707D02*
Y1785352D01*
G01X1473889Y1785131D02*
Y1785928D01*
G01X1473708Y1785087D02*
Y1785972D01*
G01X1473165Y1783758D02*
Y1784024D01*
G01Y1784644D02*
Y1784909D01*
G01Y1786150D02*
Y1786415D01*
G01X1471000Y1786179D02*
Y1784211D01*
G01X1470921Y1785529D02*
Y1784860D01*
G01Y1788679D02*
Y1788010D01*
G01Y1791829D02*
Y1791159D01*
G01X1470574Y1785529D02*
Y1784860D01*
G01Y1788679D02*
Y1788010D01*
G01Y1791829D02*
Y1791159D01*
G01X1469631Y1785785D02*
Y1784604D01*
G01Y1788935D02*
Y1787754D01*
G01Y1792085D02*
Y1790903D01*
G01X1469278Y1785785D02*
Y1784604D01*
G01Y1788935D02*
Y1787754D01*
G01Y1792085D02*
Y1790903D01*
G01X1467296Y1785785D02*
Y1784604D01*
G01Y1788935D02*
Y1787754D01*
G01Y1792085D02*
Y1790903D01*
G01X1467186Y1785785D02*
Y1784604D01*
G01Y1788935D02*
Y1787754D01*
G01Y1792085D02*
Y1790903D01*
G01X1461157Y1784211D02*
Y1786179D01*
G01X1458405Y1785785D02*
Y1784604D01*
G01Y1788935D02*
Y1787754D01*
G01Y1792085D02*
Y1790903D01*
G01X1458295Y1785785D02*
Y1784604D01*
G01Y1788935D02*
Y1787754D01*
G01Y1792085D02*
Y1790903D01*
G01X1457929Y1785785D02*
Y1784604D01*
G01Y1788935D02*
Y1787754D01*
G01Y1792085D02*
Y1790903D01*
G01X1457732Y1784604D02*
Y1784014D01*
G01Y1786376D02*
Y1785785D01*
G01Y1790903D02*
Y1790313D01*
G01Y1787754D02*
Y1787163D01*
G01Y1789525D02*
Y1788935D01*
G01Y1794053D02*
Y1793463D01*
G01Y1792675D02*
Y1792085D01*
G01X1457535Y1784604D02*
Y1784014D01*
G01Y1786376D02*
Y1785785D01*
G01Y1790903D02*
Y1790313D01*
G01Y1787754D02*
Y1787163D01*
G01Y1789525D02*
Y1788935D01*
G01Y1794053D02*
Y1793463D01*
G01Y1792675D02*
Y1792085D01*
G01X1457220Y2150155D02*
Y1744644D01*
G01X1449937Y1924565D02*
Y1781258D01*
G01X1448165Y1768266D02*
Y1744644D01*
G01X1444212Y1785982D02*
Y1784407D01*
G01Y1789132D02*
Y1787557D01*
G01Y1792281D02*
Y1790707D01*
G01X1442684Y1785775D02*
Y1784615D01*
G01Y1788924D02*
Y1787764D01*
G01Y1792074D02*
Y1790914D01*
G01X1475110Y1785529D02*
X1473889Y1785131D01*
G01X1473165Y1784909D02*
X1473708Y1785087D01*
G01X1475291Y1785352D02*
X1473165Y1784644D01*
G01X1443073Y1785982D02*
X1442684Y1785775D01*
G01X1443073Y1789132D02*
X1442684Y1788924D01*
G01X1443073Y1792281D02*
X1442684Y1792074D01*
G01X1443243Y1785982D02*
X1442772Y1785687D01*
G01X1442684Y1785775D02*
X1442543Y1785687D01*
G01X1443243Y1789132D02*
X1442772Y1788837D01*
G01X1442684Y1788924D02*
X1442543Y1788837D01*
G01X1443243Y1792281D02*
X1442772Y1791986D01*
G01X1442684Y1792074D02*
X1442543Y1791986D01*
G01X1469507Y1784860D02*
X1469278Y1784604D01*
G01X1469507Y1788010D02*
X1469278Y1787754D01*
G01X1469507Y1791159D02*
X1469278Y1790903D01*
G01X1469855Y1784860D02*
X1469636Y1784590D01*
G01X1469855Y1788010D02*
X1469636Y1787740D01*
G01X1469855Y1791159D02*
X1469636Y1790889D01*
G01X1439047Y1794189D02*
X1442543Y1794151D01*
G01X1437751Y1794204D02*
X1441007Y1794168D01*
G01X1438785Y1794190D02*
X1436420Y1794216D01*
G01X1441235Y1794168D02*
X1442772Y1794151D01*
G01X1441235Y1794168D02*
X1438785Y1794190D01*
G01X1437751Y1794204D02*
X1436420Y1794216D01*
G01X1441235Y1795119D02*
X1441007D01*
G01X1439047Y1795098D02*
X1438785D01*
G01X1439047Y1794190D02*
X1438785D01*
G01X1441235Y1794168D02*
X1441007D01*
G01X1440094Y1795109D02*
X1438785Y1795098D01*
G01X1441235Y1795119D02*
X1440094Y1795109D01*
G01X1437751Y1795083D02*
X1436420Y1795072D01*
G01X1442543Y1795136D02*
X1441007Y1795119D01*
G01X1442543Y1795136D02*
X1439047Y1795098D01*
G01X1441235Y1795119D02*
X1442772Y1795136D01*
G01X1439047Y1795098D02*
X1440094Y1795109D01*
G01X1438785Y1795098D02*
X1436420Y1795072D01*
G01X1437751Y1795083D02*
X1439047Y1795098D01*
G01X1441235Y1795119D02*
Y1794168D01*
G01X1441007Y1795119D02*
Y1794168D01*
G01X1439047Y1795098D02*
Y1794189D01*
G01X1438785Y1795098D02*
Y1794190D01*
G01X1437751Y1795078D02*
Y1794210D01*
G01X1436420Y1795072D02*
Y1794216D01*
G01X1439047Y1863481D02*
X1442543Y1863443D01*
G01X1437751Y1863495D02*
X1441007Y1863459D01*
G01X1439047Y1860331D02*
X1442543Y1860293D01*
G01X1437751Y1860346D02*
X1441007Y1860310D01*
G01X1439047Y1857182D02*
X1442543Y1857144D01*
G01X1437751Y1857196D02*
X1441007Y1857160D01*
G01X1439047Y1854032D02*
X1442543Y1853994D01*
G01X1437751Y1854046D02*
X1441007Y1854010D01*
G01X1439047Y1850882D02*
X1442543Y1850844D01*
G01X1437751Y1850897D02*
X1441007Y1850861D01*
G01X1439047Y1847733D02*
X1442543Y1847695D01*
G01X1437751Y1847747D02*
X1441007Y1847711D01*
G01X1439047Y1844583D02*
X1442543Y1844545D01*
G01X1437751Y1844597D02*
X1441007Y1844562D01*
G01X1439047Y1841434D02*
X1442543Y1841396D01*
G01X1437751Y1841448D02*
X1441007Y1841412D01*
G01X1439047Y1838284D02*
X1442543Y1838246D01*
G01X1437751Y1838298D02*
X1441007Y1838262D01*
G01X1439047Y1835134D02*
X1442543Y1835096D01*
G01X1437751Y1835149D02*
X1441007Y1835113D01*
G01X1439047Y1831985D02*
X1442543Y1831947D01*
G01X1437751Y1831999D02*
X1441007Y1831963D01*
G01X1439047Y1828835D02*
X1442543Y1828797D01*
G01X1437751Y1828849D02*
X1441007Y1828814D01*
G01X1439047Y1825686D02*
X1442543Y1825648D01*
G01X1437751Y1825700D02*
X1441007Y1825664D01*
G01X1439047Y1822536D02*
X1442543Y1822498D01*
G01X1437751Y1822550D02*
X1441007Y1822514D01*
G01X1439047Y1819386D02*
X1442543Y1819348D01*
G01X1437751Y1819401D02*
X1441007Y1819365D01*
G01X1438785Y1863481D02*
X1436420Y1863507D01*
G01X1438785Y1860331D02*
X1436420Y1860357D01*
G01X1438785Y1857182D02*
X1436420Y1857208D01*
G01X1438785Y1854032D02*
X1436420Y1854058D01*
G01X1438785Y1850882D02*
X1436420Y1850909D01*
G01X1438785Y1847733D02*
X1436420Y1847759D01*
G01X1438785Y1844583D02*
X1436420Y1844609D01*
G01X1438785Y1841434D02*
X1436420Y1841460D01*
G01X1438785Y1838284D02*
X1436420Y1838310D01*
G01X1438785Y1835134D02*
X1436420Y1835160D01*
G01X1438785Y1831985D02*
X1436420Y1832011D01*
G01X1438785Y1828835D02*
X1436420Y1828861D01*
G01X1438785Y1825686D02*
X1436420Y1825712D01*
G01X1438785Y1822536D02*
X1436420Y1822562D01*
G01X1438785Y1819386D02*
X1436420Y1819412D01*
G01X1441235Y1863459D02*
X1442772Y1863443D01*
G01X1441235Y1860310D02*
X1442772Y1860293D01*
G01X1441235Y1857160D02*
X1442772Y1857144D01*
G01X1441235Y1854010D02*
X1442772Y1853994D01*
G01X1441235Y1850861D02*
X1442772Y1850844D01*
G01X1441235Y1847711D02*
X1442772Y1847695D01*
G01X1441235Y1844562D02*
X1442772Y1844545D01*
G01X1441235Y1841412D02*
X1442772Y1841396D01*
G01X1441235Y1838262D02*
X1442772Y1838246D01*
G01X1441235Y1835113D02*
X1442772Y1835096D01*
G01X1441235Y1831963D02*
X1442772Y1831947D01*
G01X1441235Y1828814D02*
X1442772Y1828797D01*
G01X1441235Y1825664D02*
X1442772Y1825648D01*
G01X1441235Y1822514D02*
X1442772Y1822498D01*
G01X1441235Y1819365D02*
X1442772Y1819348D01*
G01X1441235Y1863459D02*
X1438785Y1863481D01*
G01X1437751Y1863495D02*
X1436420Y1863507D01*
G01X1441235Y1860310D02*
X1438785Y1860331D01*
G01X1437751Y1860346D02*
X1436420Y1860357D01*
G01X1441235Y1857160D02*
X1438785Y1857182D01*
G01X1437751Y1857196D02*
X1436420Y1857208D01*
G01X1441235Y1854010D02*
X1438785Y1854032D01*
G01X1437751Y1854046D02*
X1436420Y1854058D01*
G01X1441235Y1850861D02*
X1438785Y1850882D01*
G01X1437751Y1850897D02*
X1436420Y1850909D01*
G01X1441235Y1847711D02*
X1438785Y1847733D01*
G01X1437751Y1847747D02*
X1436420Y1847759D01*
G01X1441235Y1844562D02*
X1438785Y1844583D01*
G01X1437751Y1844597D02*
X1436420Y1844609D01*
G01X1441235Y1841412D02*
X1438785Y1841434D01*
G01X1437751Y1841448D02*
X1436420Y1841460D01*
G01X1441235Y1838262D02*
X1438785Y1838284D01*
G01X1437751Y1838298D02*
X1436420Y1838310D01*
G01X1441235Y1835113D02*
X1438785Y1835134D01*
G01X1437751Y1835149D02*
X1436420Y1835160D01*
G01X1441235Y1831963D02*
X1438785Y1831985D01*
G01X1437751Y1831999D02*
X1436420Y1832011D01*
G01X1441235Y1828814D02*
X1438785Y1828835D01*
G01X1437751Y1828849D02*
X1436420Y1828861D01*
G01X1441235Y1825664D02*
X1438785Y1825686D01*
G01X1437751Y1825700D02*
X1436420Y1825712D01*
G01X1441235Y1822514D02*
X1438785Y1822536D01*
G01X1437751Y1822550D02*
X1436420Y1822562D01*
G01X1441235Y1819365D02*
X1438785Y1819386D01*
G01X1437751Y1819401D02*
X1436420Y1819412D01*
G01X1441235Y1864411D02*
X1441007D01*
G01X1439047Y1864389D02*
X1438785D01*
G01X1439047Y1863481D02*
X1438785D01*
G01X1441235Y1863459D02*
X1441007D01*
G01X1441235Y1861261D02*
X1441007D01*
G01X1439047Y1861239D02*
X1438785D01*
G01X1439047Y1860331D02*
X1438785D01*
G01X1441235Y1860310D02*
X1441007D01*
G01X1441235Y1858111D02*
X1441007D01*
G01X1439047Y1858090D02*
X1438785D01*
G01X1439047Y1857182D02*
X1438785D01*
G01X1441235Y1857160D02*
X1441007D01*
G01X1441235Y1854962D02*
X1441007D01*
G01X1439047Y1854940D02*
X1438785D01*
G01X1439047Y1854032D02*
X1438785D01*
G01X1441235Y1854010D02*
X1441007D01*
G01X1441235Y1851812D02*
X1441007D01*
G01X1439047Y1851791D02*
X1438785D01*
G01X1439047Y1850882D02*
X1438785D01*
G01X1441235Y1850861D02*
X1441007D01*
G01X1441235Y1848663D02*
X1441007D01*
G01X1439047Y1848641D02*
X1438785D01*
G01X1439047Y1847733D02*
X1438785D01*
G01X1441235Y1847711D02*
X1441007D01*
G01X1441235Y1845513D02*
X1441007D01*
G01X1439047Y1845491D02*
X1438785D01*
G01X1439047Y1844583D02*
X1438785D01*
G01X1441235Y1844562D02*
X1441007D01*
G01X1441235Y1842363D02*
X1441007D01*
G01X1439047Y1842342D02*
X1438785D01*
G01X1439047Y1841434D02*
X1438785D01*
G01X1441235Y1841412D02*
X1441007D01*
G01X1441235Y1839214D02*
X1441007D01*
G01X1439047Y1839192D02*
X1438785D01*
G01X1439047Y1838284D02*
X1438785D01*
G01X1441235Y1838262D02*
X1441007D01*
G01X1441235Y1836064D02*
X1441007D01*
G01X1439047Y1836043D02*
X1438785D01*
G01X1439047Y1835134D02*
X1438785D01*
G01X1441235Y1835113D02*
X1441007D01*
G01X1441235Y1832915D02*
X1441007D01*
G01X1439047Y1832893D02*
X1438785D01*
G01X1439047Y1831985D02*
X1438785D01*
G01X1441235Y1831963D02*
X1441007D01*
G01X1441235Y1829765D02*
X1441007D01*
G01X1439047Y1829743D02*
X1438785D01*
G01X1439047Y1828835D02*
X1438785D01*
G01X1441235Y1828814D02*
X1441007D01*
G01X1441235Y1826615D02*
X1441007D01*
G01X1439047Y1826594D02*
X1438785D01*
G01X1439047Y1825686D02*
X1438785D01*
G01X1441235Y1825664D02*
X1441007D01*
G01X1441235Y1823466D02*
X1441007D01*
G01X1438785Y1823444D02*
X1439047D01*
G01Y1822536D02*
X1438785D01*
G01X1441235Y1822514D02*
X1441007D01*
G01X1441235Y1820316D02*
X1441007D01*
G01X1439047Y1820295D02*
X1438785D01*
G01X1439047Y1819386D02*
X1438785D01*
G01X1441235Y1819365D02*
X1441007D01*
G01X1441235Y1817167D02*
X1441007D01*
G01X1439047Y1817145D02*
X1438785D01*
G01X1439047Y1816237D02*
X1438785D01*
G01X1441235Y1816215D02*
X1441007D01*
G01X1441235Y1814017D02*
X1441007D01*
G01X1439047Y1813995D02*
X1438785D01*
G01X1439047Y1813087D02*
X1438785D01*
G01X1441235Y1813066D02*
X1441007D01*
G01X1440094Y1864401D02*
X1438785Y1864389D01*
G01X1441235Y1864411D02*
X1440094Y1864401D01*
G01Y1861251D02*
X1438785Y1861239D01*
G01X1441235Y1861261D02*
X1440094Y1861251D01*
G01X1438785Y1858090D02*
X1440094Y1858101D01*
G01X1441235Y1858111D02*
X1440094Y1858101D01*
G01Y1854952D02*
X1438785Y1854940D01*
G01X1441235Y1854962D02*
X1440094Y1854952D01*
G01Y1851802D02*
X1438785Y1851791D01*
G01X1441235Y1851812D02*
X1440094Y1851802D01*
G01Y1848653D02*
X1438785Y1848641D01*
G01X1441235Y1848663D02*
X1440094Y1848653D01*
G01Y1845503D02*
X1438785Y1845491D01*
G01X1441235Y1845513D02*
X1440094Y1845503D01*
G01Y1842353D02*
X1438785Y1842342D01*
G01X1441235Y1842363D02*
X1440094Y1842353D01*
G01Y1839204D02*
X1438785Y1839192D01*
G01X1441235Y1839214D02*
X1440094Y1839204D01*
G01Y1836054D02*
X1438785Y1836043D01*
G01X1441235Y1836064D02*
X1440094Y1836054D01*
G01Y1832905D02*
X1438785Y1832893D01*
G01X1441235Y1832915D02*
X1440094Y1832905D01*
G01Y1829755D02*
X1438785Y1829743D01*
G01X1441235Y1829765D02*
X1440094Y1829755D01*
G01Y1826605D02*
X1438785Y1826594D01*
G01X1441235Y1826615D02*
X1440094Y1826605D01*
G01Y1823456D02*
X1438785Y1823444D01*
G01X1441235Y1823466D02*
X1440094Y1823456D01*
G01Y1820306D02*
X1438785Y1820295D01*
G01X1441235Y1820316D02*
X1440094Y1820306D01*
G01Y1817157D02*
X1438785Y1817145D01*
G01X1441235Y1817167D02*
X1440094Y1817157D01*
G01Y1814007D02*
X1438785Y1813995D01*
G01X1441235Y1814017D02*
X1440094Y1814007D01*
G01Y1810857D02*
X1438785Y1810846D01*
G01X1441235Y1810867D02*
X1440094Y1810857D01*
G01X1437751Y1864375D02*
X1436420Y1864363D01*
G01X1437751Y1861225D02*
X1436420Y1861213D01*
G01X1437751Y1858076D02*
X1436420Y1858064D01*
G01X1437751Y1854926D02*
X1436420Y1854914D01*
G01X1437751Y1851776D02*
X1436420Y1851765D01*
G01X1437751Y1848627D02*
X1436420Y1848615D01*
G01X1437751Y1845477D02*
X1436420Y1845465D01*
G01X1437751Y1842328D02*
X1436420Y1842316D01*
G01X1437751Y1839178D02*
X1436420Y1839166D01*
G01X1437751Y1836028D02*
X1436420Y1836017D01*
G01X1437751Y1832879D02*
X1436420Y1832867D01*
G01X1437751Y1829729D02*
X1436420Y1829717D01*
G01X1437751Y1826579D02*
X1436420Y1826568D01*
G01X1437751Y1823430D02*
X1436420Y1823418D01*
G01X1437751Y1820280D02*
X1436420Y1820268D01*
G01X1437751Y1817131D02*
X1436420Y1817119D01*
G01X1437751Y1813981D02*
X1436420Y1813969D01*
G01X1437751Y1810831D02*
X1436420Y1810820D01*
G01X1442543Y1864427D02*
X1441007Y1864411D01*
G01X1442543Y1864427D02*
X1439047Y1864389D01*
G01X1441235Y1864411D02*
X1442772Y1864427D01*
G01X1442543Y1861277D02*
X1441007Y1861261D01*
G01X1442543Y1861277D02*
X1439047Y1861239D01*
G01X1441235Y1861261D02*
X1442772Y1861277D01*
G01X1442543Y1858128D02*
X1441007Y1858111D01*
G01X1442543Y1858128D02*
X1439047Y1858090D01*
G01X1441235Y1858111D02*
X1442772Y1858128D01*
G01X1442543Y1854978D02*
X1441007Y1854962D01*
G01X1442543Y1854978D02*
X1439047Y1854940D01*
G01X1441235Y1854962D02*
X1442772Y1854978D01*
G01X1442543Y1851829D02*
X1441007Y1851812D01*
G01X1442543Y1851829D02*
X1439047Y1851791D01*
G01X1441235Y1851812D02*
X1442772Y1851829D01*
G01X1442543Y1848679D02*
X1441007Y1848663D01*
G01X1442543Y1848679D02*
X1439047Y1848641D01*
G01X1441235Y1848663D02*
X1442772Y1848679D01*
G01X1442543Y1845529D02*
X1441007Y1845513D01*
G01X1442543Y1845529D02*
X1439047Y1845491D01*
G01X1441235Y1845513D02*
X1442772Y1845529D01*
G01X1442543Y1842380D02*
X1441007Y1842363D01*
G01X1442543Y1842380D02*
X1439047Y1842342D01*
G01X1441235Y1842363D02*
X1442772Y1842380D01*
G01X1442543Y1839230D02*
X1441007Y1839214D01*
G01X1442543Y1839230D02*
X1439047Y1839192D01*
G01X1441235Y1839214D02*
X1442772Y1839230D01*
G01X1442543Y1836081D02*
X1441007Y1836064D01*
G01X1442543Y1836081D02*
X1439047Y1836043D01*
G01X1441235Y1836064D02*
X1442772Y1836081D01*
G01X1442543Y1832931D02*
X1441007Y1832915D01*
G01X1442543Y1832931D02*
X1439047Y1832893D01*
G01X1441235Y1832915D02*
X1442772Y1832931D01*
G01X1442543Y1829781D02*
X1441007Y1829765D01*
G01X1442543Y1829781D02*
X1439047Y1829743D01*
G01X1441235Y1829765D02*
X1442772Y1829781D01*
G01X1442543Y1826632D02*
X1441007Y1826615D01*
G01X1442543Y1826632D02*
X1439047Y1826594D01*
G01X1441235Y1826615D02*
X1442772Y1826632D01*
G01X1442543Y1823482D02*
X1441007Y1823466D01*
G01X1442543Y1823482D02*
X1439047Y1823444D01*
G01X1441235Y1823466D02*
X1442772Y1823482D01*
G01X1442543Y1820333D02*
X1441007Y1820316D01*
G01X1442543Y1820333D02*
X1439047Y1820295D01*
G01X1441235Y1820316D02*
X1442772Y1820333D01*
G01X1442543Y1817183D02*
X1441007Y1817167D01*
G01X1442543Y1817183D02*
X1439047Y1817145D01*
G01X1441235Y1817167D02*
X1442772Y1817183D01*
G01X1442543Y1814033D02*
X1441007Y1814017D01*
G01X1442543Y1814033D02*
X1439047Y1813995D01*
G01X1441235Y1814017D02*
X1442772Y1814033D01*
G01X1442543Y1810884D02*
X1441007Y1810867D01*
G01X1442543Y1810884D02*
X1439047Y1810846D01*
G01X1441235Y1810867D02*
X1442772Y1810884D01*
G01X1442543Y1807734D02*
X1441007Y1807718D01*
G01X1442543Y1807734D02*
X1439047Y1807696D01*
G01X1441235Y1807718D02*
X1442772Y1807734D01*
G01X1439047Y1864389D02*
X1440094Y1864401D01*
G01X1438785Y1864389D02*
X1436420Y1864363D01*
G01X1437751Y1864375D02*
X1439047Y1864389D01*
G01Y1861239D02*
X1440094Y1861251D01*
G01X1438785Y1861239D02*
X1436420Y1861213D01*
G01X1437751Y1861225D02*
X1439047Y1861239D01*
G01Y1858090D02*
X1440094Y1858101D01*
G01X1438785Y1858090D02*
X1436420Y1858064D01*
G01X1437751Y1858076D02*
X1439047Y1858090D01*
G01Y1854940D02*
X1440094Y1854952D01*
G01X1438785Y1854940D02*
X1436420Y1854914D01*
G01X1437751Y1854926D02*
X1439047Y1854940D01*
G01Y1851791D02*
X1440094Y1851802D01*
G01X1438785Y1851791D02*
X1436420Y1851765D01*
G01X1437751Y1851776D02*
X1439047Y1851791D01*
G01Y1848641D02*
X1440094Y1848653D01*
G01X1438785Y1848641D02*
X1436420Y1848615D01*
G01X1437751Y1848627D02*
X1439047Y1848641D01*
G01Y1845491D02*
X1440094Y1845503D01*
G01X1438785Y1845491D02*
X1436420Y1845465D01*
G01X1437751Y1845477D02*
X1439047Y1845491D01*
G01Y1842342D02*
X1440094Y1842353D01*
G01X1438785Y1842342D02*
X1436420Y1842316D01*
G01X1437751Y1842328D02*
X1439047Y1842342D01*
G01Y1839192D02*
X1440094Y1839204D01*
G01X1438785Y1839192D02*
X1436420Y1839166D01*
G01X1437751Y1839178D02*
X1439047Y1839192D01*
G01Y1836043D02*
X1440094Y1836054D01*
G01X1438785Y1836043D02*
X1436420Y1836017D01*
G01X1437751Y1836028D02*
X1439047Y1836043D01*
G01Y1832893D02*
X1440094Y1832905D01*
G01X1438785Y1832893D02*
X1436420Y1832867D01*
G01X1437751Y1832879D02*
X1439047Y1832893D01*
G01Y1829743D02*
X1440094Y1829755D01*
G01X1438785Y1829743D02*
X1436420Y1829717D01*
G01X1437751Y1829729D02*
X1439047Y1829743D01*
G01Y1826594D02*
X1440094Y1826605D01*
G01X1438785Y1826594D02*
X1436420Y1826568D01*
G01X1437751Y1826579D02*
X1439047Y1826594D01*
G01Y1823444D02*
X1440094Y1823456D01*
G01X1438785Y1823444D02*
X1436420Y1823418D01*
G01X1437751Y1823430D02*
X1439047Y1823444D01*
G01Y1820295D02*
X1440094Y1820306D01*
G01X1438785Y1820295D02*
X1436420Y1820268D01*
G01X1437751Y1820280D02*
X1439047Y1820295D01*
G01Y1817145D02*
X1440094Y1817157D01*
G01X1438785Y1817145D02*
X1436420Y1817119D01*
G01X1437751Y1817131D02*
X1439047Y1817145D01*
G01Y1813995D02*
X1440094Y1814007D01*
G01X1438785Y1813995D02*
X1436420Y1813969D01*
G01X1437751Y1813981D02*
X1439047Y1813995D01*
G01Y1810846D02*
X1440094Y1810857D01*
G01X1438785Y1810846D02*
X1436420Y1810820D01*
G01X1437751Y1810831D02*
X1439047Y1810846D01*
G01Y1807696D02*
X1440094Y1807708D01*
G01X1438785Y1807696D02*
X1436420Y1807670D01*
G01X1437751Y1807682D02*
X1439047Y1807696D01*
G01Y1816237D02*
X1442543Y1816199D01*
G01X1437751Y1816251D02*
X1441007Y1816215D01*
G01X1439047Y1813087D02*
X1442543Y1813049D01*
G01X1437751Y1813101D02*
X1441007Y1813066D01*
G01X1439047Y1809937D02*
X1442543Y1809900D01*
G01X1437751Y1809952D02*
X1441007Y1809916D01*
G01X1439047Y1806788D02*
X1442543Y1806750D01*
G01X1437751Y1806802D02*
X1441007Y1806766D01*
G01X1439047Y1803638D02*
X1442543Y1803600D01*
G01X1437751Y1803653D02*
X1441007Y1803617D01*
G01X1439047Y1800489D02*
X1442543Y1800451D01*
G01X1437751Y1800503D02*
X1441007Y1800467D01*
G01X1439047Y1797339D02*
X1442543Y1797301D01*
G01X1437751Y1797353D02*
X1441007Y1797318D01*
G01X1438785Y1816237D02*
X1436420Y1816263D01*
G01X1438785Y1813087D02*
X1436420Y1813113D01*
G01X1438785Y1809938D02*
X1436420Y1809964D01*
G01X1438785Y1806788D02*
X1436420Y1806814D01*
G01X1438785Y1803638D02*
X1436420Y1803664D01*
G01X1438785Y1800489D02*
X1436420Y1800515D01*
G01X1438785Y1797339D02*
X1436420Y1797365D01*
G01X1441235Y1816215D02*
X1442772Y1816199D01*
G01X1441235Y1813066D02*
X1442772Y1813049D01*
G01X1441235Y1809916D02*
X1442772Y1809900D01*
G01X1441235Y1806766D02*
X1442772Y1806750D01*
G01X1441235Y1803617D02*
X1442772Y1803600D01*
G01X1441235Y1800467D02*
X1442772Y1800451D01*
G01X1441235Y1797318D02*
X1442772Y1797301D01*
G01X1441235Y1816215D02*
X1438785Y1816237D01*
G01X1437751Y1816251D02*
X1436420Y1816263D01*
G01X1441235Y1813066D02*
X1438785Y1813087D01*
G01X1437751Y1813101D02*
X1436420Y1813113D01*
G01X1441235Y1809916D02*
X1438785Y1809938D01*
G01X1437751Y1809952D02*
X1436420Y1809964D01*
G01X1441235Y1806766D02*
X1438785Y1806788D01*
G01X1437751Y1806802D02*
X1436420Y1806814D01*
G01X1441235Y1803617D02*
X1438785Y1803638D01*
G01X1437751Y1803653D02*
X1436420Y1803664D01*
G01X1441235Y1800467D02*
X1438785Y1800489D01*
G01X1437751Y1800503D02*
X1436420Y1800515D01*
G01X1441235Y1797318D02*
X1438785Y1797339D01*
G01X1437751Y1797353D02*
X1436420Y1797365D01*
G01X1441235Y1810867D02*
X1441007D01*
G01X1439047Y1810846D02*
X1438785D01*
G01X1439047Y1809938D02*
X1438785D01*
G01X1441235Y1809916D02*
X1441007D01*
G01X1441235Y1807718D02*
X1441007D01*
G01X1439047Y1807696D02*
X1438785D01*
G01X1439047Y1806788D02*
X1438785D01*
G01X1441235Y1806766D02*
X1441007D01*
G01X1441235Y1804568D02*
X1441007D01*
G01X1439047Y1804547D02*
X1438785D01*
G01X1439047Y1803638D02*
X1438785D01*
G01X1441235Y1803617D02*
X1441007D01*
G01X1441235Y1801418D02*
X1441007D01*
G01X1439047Y1801397D02*
X1438785D01*
G01X1439047Y1800489D02*
X1438785D01*
G01X1441235Y1800467D02*
X1441007D01*
G01X1441235Y1798269D02*
X1441007D01*
G01X1439047Y1798247D02*
X1438785D01*
G01X1439047Y1797339D02*
X1438785D01*
G01X1441235Y1797318D02*
X1441007D01*
G01X1440094Y1807708D02*
X1438785Y1807696D01*
G01X1441235Y1807718D02*
X1440094Y1807708D01*
G01Y1804558D02*
X1438785Y1804547D01*
G01X1441235Y1804568D02*
X1440094Y1804558D01*
G01Y1801408D02*
X1438785Y1801397D01*
G01X1441235Y1801418D02*
X1440094Y1801408D01*
G01Y1798259D02*
X1438785Y1798247D01*
G01X1441235Y1798269D02*
X1440094Y1798259D01*
G01X1437751Y1807682D02*
X1436420Y1807670D01*
G01X1437751Y1804532D02*
X1436420Y1804520D01*
G01X1437751Y1801383D02*
X1436420Y1801371D01*
G01X1437751Y1798233D02*
X1436420Y1798221D01*
G01X1442543Y1804585D02*
X1441007Y1804568D01*
G01X1442543Y1804585D02*
X1439047Y1804547D01*
G01X1441235Y1804568D02*
X1442772Y1804585D01*
G01X1442543Y1801435D02*
X1441007Y1801418D01*
G01X1442543Y1801435D02*
X1439047Y1801397D01*
G01X1441235Y1801418D02*
X1442772Y1801435D01*
G01X1442543Y1798285D02*
X1441007Y1798269D01*
G01X1442543Y1798285D02*
X1439047Y1798247D01*
G01X1441235Y1798269D02*
X1442772Y1798285D01*
G01X1439047Y1804547D02*
X1440094Y1804558D01*
G01X1438785Y1804547D02*
X1436420Y1804520D01*
G01X1437751Y1804532D02*
X1439047Y1804547D01*
G01Y1801397D02*
X1440094Y1801408D01*
G01X1438785Y1801397D02*
X1436420Y1801371D01*
G01X1437751Y1801383D02*
X1439047Y1801397D01*
G01Y1798247D02*
X1440094Y1798259D01*
G01X1438785Y1798247D02*
X1436420Y1798221D01*
G01X1437751Y1798233D02*
X1439047Y1798247D01*
G01X1441235Y1798269D02*
Y1797318D01*
G01Y1804568D02*
Y1803617D01*
G01Y1801418D02*
Y1800467D01*
G01Y1807718D02*
Y1806766D01*
G01Y1814017D02*
Y1813066D01*
G01Y1810867D02*
Y1809916D01*
G01Y1817166D02*
Y1816215D01*
G01Y1823466D02*
Y1822514D01*
G01Y1820316D02*
Y1819365D01*
G01Y1826615D02*
Y1825664D01*
G01Y1832914D02*
Y1831963D01*
G01Y1829765D02*
Y1828814D01*
G01Y1836064D02*
Y1835113D01*
G01Y1842363D02*
Y1841412D01*
G01Y1839214D02*
Y1838262D01*
G01Y1845513D02*
Y1844562D01*
G01Y1851812D02*
Y1850861D01*
G01Y1848663D02*
Y1847711D01*
G01Y1854962D02*
Y1854010D01*
G01Y1861261D02*
Y1860310D01*
G01Y1858111D02*
Y1857160D01*
G01Y1864411D02*
Y1863459D01*
G01X1441007Y1798269D02*
Y1797318D01*
G01Y1804568D02*
Y1803617D01*
G01Y1801418D02*
Y1800467D01*
G01Y1807718D02*
Y1806766D01*
G01Y1814017D02*
Y1813066D01*
G01Y1810867D02*
Y1809916D01*
G01Y1817167D02*
Y1816215D01*
G01Y1823466D02*
Y1822514D01*
G01Y1820316D02*
Y1819365D01*
G01Y1826615D02*
Y1825664D01*
G01Y1832915D02*
Y1831963D01*
G01Y1829765D02*
Y1828814D01*
G01Y1836064D02*
Y1835113D01*
G01Y1842363D02*
Y1841412D01*
G01Y1839214D02*
Y1838262D01*
G01Y1845513D02*
Y1844562D01*
G01Y1851812D02*
Y1850861D01*
G01Y1848663D02*
Y1847711D01*
G01Y1854962D02*
Y1854010D01*
G01Y1861261D02*
Y1860310D01*
G01Y1858111D02*
Y1857160D01*
G01Y1864411D02*
Y1863459D01*
G01X1439047Y1798247D02*
Y1797339D01*
G01Y1804547D02*
Y1803638D01*
G01Y1801397D02*
Y1800489D01*
G01Y1807696D02*
Y1806788D01*
G01Y1813995D02*
Y1813087D01*
G01Y1810846D02*
Y1809937D01*
G01Y1817145D02*
Y1816237D01*
G01Y1823444D02*
Y1822536D01*
G01Y1820295D02*
Y1819386D01*
G01Y1826594D02*
Y1825686D01*
G01Y1832893D02*
Y1831985D01*
G01Y1829743D02*
Y1828835D01*
G01Y1836043D02*
Y1835134D01*
G01Y1842342D02*
Y1841434D01*
G01Y1839192D02*
Y1838284D01*
G01Y1845491D02*
Y1844583D01*
G01Y1851791D02*
Y1850882D01*
G01Y1848641D02*
Y1847733D01*
G01Y1854940D02*
Y1854032D01*
G01Y1861239D02*
Y1860331D01*
G01Y1858090D02*
Y1857182D01*
G01Y1864389D02*
Y1863481D01*
G01X1438785Y1798247D02*
Y1797339D01*
G01Y1804547D02*
Y1803638D01*
G01Y1801397D02*
Y1800489D01*
G01Y1807696D02*
Y1806788D01*
G01Y1813995D02*
Y1813087D01*
G01Y1810846D02*
Y1809938D01*
G01Y1817145D02*
Y1816237D01*
G01Y1823444D02*
Y1822536D01*
G01Y1820295D02*
Y1819386D01*
G01Y1826594D02*
Y1825686D01*
G01Y1832893D02*
Y1831985D01*
G01Y1829743D02*
Y1828835D01*
G01Y1836043D02*
Y1835134D01*
G01Y1842342D02*
Y1841434D01*
G01Y1839192D02*
Y1838284D01*
G01Y1845491D02*
Y1844583D01*
G01Y1851791D02*
Y1850882D01*
G01Y1848641D02*
Y1847733D01*
G01Y1854940D02*
Y1854032D01*
G01Y1861239D02*
Y1860331D01*
G01Y1858090D02*
Y1857182D01*
G01Y1864389D02*
Y1863481D01*
G01X1437751Y1798227D02*
Y1797359D01*
G01Y1804526D02*
Y1803659D01*
G01Y1801377D02*
Y1800509D01*
G01Y1807676D02*
Y1806808D01*
G01Y1813975D02*
Y1813107D01*
G01Y1810826D02*
Y1809958D01*
G01Y1817125D02*
Y1816257D01*
G01Y1823424D02*
Y1822556D01*
G01Y1820274D02*
Y1819407D01*
G01Y1826574D02*
Y1825706D01*
G01Y1832873D02*
Y1832005D01*
G01Y1829723D02*
Y1828855D01*
G01Y1836022D02*
Y1835155D01*
G01Y1842322D02*
Y1841454D01*
G01Y1839172D02*
Y1838304D01*
G01Y1845471D02*
Y1844603D01*
G01Y1851770D02*
Y1850903D01*
G01Y1848621D02*
Y1847753D01*
G01Y1854920D02*
Y1854052D01*
G01Y1861219D02*
Y1860351D01*
G01Y1858070D02*
Y1857202D01*
G01Y1864369D02*
Y1863501D01*
G01X1436420Y1798221D02*
Y1797365D01*
G01Y1804520D02*
Y1803664D01*
G01Y1801371D02*
Y1800515D01*
G01Y1807670D02*
Y1806814D01*
G01Y1813969D02*
Y1813113D01*
G01Y1810820D02*
Y1809964D01*
G01Y1817119D02*
Y1816263D01*
G01Y1823418D02*
Y1822562D01*
G01Y1820268D02*
Y1819412D01*
G01Y1826568D02*
Y1825712D01*
G01Y1832867D02*
Y1832011D01*
G01Y1829717D02*
Y1828861D01*
G01Y1836017D02*
Y1835160D01*
G01Y1842316D02*
Y1841460D01*
G01Y1839166D02*
Y1838310D01*
G01Y1845465D02*
Y1844609D01*
G01Y1851765D02*
Y1850909D01*
G01Y1848615D02*
Y1847759D01*
G01Y1854914D02*
Y1854058D01*
G01Y1861213D02*
Y1860357D01*
G01Y1858064D02*
Y1857208D01*
G01Y1864363D02*
Y1863507D01*
G01X1444212Y1797006D02*
X1443073D01*
G01X1457732Y1796612D02*
X1457220D01*
G01X1457732Y1795825D02*
X1457220D01*
G01X1444212Y1795431D02*
X1443073D01*
G01X1469631Y1795234D02*
X1457535D01*
G01X1442772Y1795136D02*
X1442543D01*
G01X1470921Y1794978D02*
X1469507D01*
G01X1470921Y1794309D02*
X1469507D01*
G01X1442772Y1794151D02*
X1442543D01*
G01X1469631Y1794053D02*
X1457535D01*
G01X1444212Y1793856D02*
X1443073D01*
G01X1442772Y1797301D02*
X1443243Y1797006D01*
G01X1442772Y1794151D02*
X1443243Y1793856D01*
G01X1442543Y1794151D02*
X1442684Y1794064D01*
G01Y1797213D02*
X1443073Y1797006D01*
G01X1442684Y1794064D02*
X1443073Y1793856D01*
G01X1469636Y1795248D02*
X1469855Y1794978D01*
G01X1469278Y1795234D02*
X1469507Y1794978D01*
G01X1470921D02*
Y1794309D01*
G01X1470574Y1794978D02*
Y1794309D01*
G01X1469631Y1795234D02*
Y1794053D01*
G01X1469278Y1795234D02*
Y1794053D01*
G01X1467296Y1795234D02*
Y1794053D01*
G01X1467186Y1795234D02*
Y1794053D01*
G01X1458405Y1795234D02*
Y1794053D01*
G01X1458295Y1795234D02*
Y1794053D01*
G01X1457929Y1795234D02*
Y1794053D01*
G01X1457732Y1795825D02*
Y1795234D01*
G01Y1797203D02*
Y1796612D01*
G01X1457535Y1795825D02*
Y1795234D01*
G01Y1797203D02*
Y1796612D01*
G01X1444212Y1795431D02*
Y1793856D01*
G01Y1798581D02*
Y1797006D01*
G01X1442684Y1795224D02*
Y1794064D01*
G01X1443073Y1795431D02*
X1442684Y1795224D01*
G01X1443243Y1795431D02*
X1442772Y1795136D01*
G01X1442684Y1795224D02*
X1442543Y1795136D01*
G01X1469507Y1794309D02*
X1469278Y1794053D01*
G01X1469855Y1794309D02*
X1469636Y1794039D01*
G01X1444212Y1866297D02*
X1443073D01*
G01X1457732Y1865903D02*
X1457220D01*
G01X1457732Y1865116D02*
X1457220D01*
G01X1444212Y1864722D02*
X1443073D01*
G01X1469631Y1864525D02*
X1457535D01*
G01X1442772Y1864427D02*
X1442543D01*
G01X1470921Y1864270D02*
X1469507D01*
G01X1470921Y1863600D02*
X1469507D01*
G01X1442772Y1863443D02*
X1442543D01*
G01X1469631Y1863344D02*
X1457535D01*
G01X1444212Y1863148D02*
X1443073D01*
G01X1457732Y1862754D02*
X1457220D01*
G01X1457732Y1861966D02*
X1457220D01*
G01X1444212Y1861573D02*
X1443073D01*
G01X1469631Y1861376D02*
X1457535D01*
G01X1442772Y1861277D02*
X1442543D01*
G01X1470921Y1861120D02*
X1469507D01*
G01X1470921Y1860451D02*
X1469507D01*
G01X1442772Y1860293D02*
X1442543D01*
G01X1469631Y1860195D02*
X1457535D01*
G01X1444212Y1859998D02*
X1443073D01*
G01X1457732Y1859604D02*
X1457220D01*
G01X1457732Y1858817D02*
X1457220D01*
G01X1444212Y1858423D02*
X1443073D01*
G01X1469631Y1858226D02*
X1457535D01*
G01X1442772Y1858128D02*
X1442543D01*
G01X1470921Y1857970D02*
X1469507D01*
G01X1470921Y1857301D02*
X1469507D01*
G01X1442772Y1857144D02*
X1442543D01*
G01X1469631Y1857045D02*
X1457535D01*
G01X1444212Y1856848D02*
X1443073D01*
G01X1457732Y1856455D02*
X1457220D01*
G01X1457732Y1855667D02*
X1457220D01*
G01X1444212Y1855274D02*
X1443073D01*
G01X1469631Y1855077D02*
X1457535D01*
G01X1442772Y1854978D02*
X1442543D01*
G01X1470921Y1854821D02*
X1469507D01*
G01X1470921Y1854151D02*
X1469507D01*
G01X1442772Y1853994D02*
X1442543D01*
G01X1469631Y1853896D02*
X1457535D01*
G01X1444212Y1853699D02*
X1443073D01*
G01X1457732Y1853305D02*
X1457220D01*
G01X1457732Y1852518D02*
X1457220D01*
G01X1444212Y1852124D02*
X1443073D01*
G01X1469631Y1851927D02*
X1457535D01*
G01X1442772Y1851829D02*
X1442543D01*
G01X1470921Y1851671D02*
X1469507D01*
G01X1470921Y1851002D02*
X1469507D01*
G01X1442772Y1850844D02*
X1442543D01*
G01X1469631Y1850746D02*
X1457535D01*
G01X1444212Y1850549D02*
X1443073D01*
G01X1457732Y1850155D02*
X1457220D01*
G01X1457732Y1849368D02*
X1457220D01*
G01X1444212Y1848974D02*
X1443073D01*
G01X1469631Y1848777D02*
X1457535D01*
G01X1442772Y1848679D02*
X1442543D01*
G01X1470921Y1848522D02*
X1469507D01*
G01X1470921Y1847852D02*
X1469507D01*
G01X1442772Y1847695D02*
X1442543D01*
G01X1469631Y1847596D02*
X1457535D01*
G01X1444212Y1847400D02*
X1443073D01*
G01X1457732Y1847006D02*
X1457220D01*
G01X1457732Y1846218D02*
X1457220D01*
G01X1444212Y1845825D02*
X1443073D01*
G01X1469631Y1845628D02*
X1457535D01*
G01X1442772Y1845529D02*
X1442543D01*
G01X1470921Y1845372D02*
X1469507D01*
G01X1470921Y1844703D02*
X1469507D01*
G01X1442772Y1844545D02*
X1442543D01*
G01X1469631Y1844447D02*
X1457535D01*
G01X1444212Y1844250D02*
X1443073D01*
G01X1457732Y1843856D02*
X1457220D01*
G01X1457732Y1843069D02*
X1457220D01*
G01X1444212Y1842675D02*
X1443073D01*
G01X1469631Y1842478D02*
X1457535D01*
G01X1442772Y1842380D02*
X1442543D01*
G01X1470921Y1842222D02*
X1469507D01*
G01X1470921Y1841553D02*
X1469507D01*
G01X1442772Y1841396D02*
X1442543D01*
G01X1469631Y1841297D02*
X1457535D01*
G01X1444212Y1841100D02*
X1443073D01*
G01X1457732Y1840707D02*
X1457220D01*
G01X1457732Y1839919D02*
X1457220D01*
G01X1444212Y1839525D02*
X1443073D01*
G01X1469631Y1839329D02*
X1457535D01*
G01X1442772Y1839230D02*
X1442543D01*
G01X1470921Y1839073D02*
X1469507D01*
G01X1470921Y1838403D02*
X1469507D01*
G01X1442772Y1838246D02*
X1442543D01*
G01X1469631Y1838148D02*
X1457535D01*
G01X1444212Y1837951D02*
X1443073D01*
G01X1457732Y1837557D02*
X1457220D01*
G01X1457732Y1836770D02*
X1457220D01*
G01X1444212Y1836376D02*
X1443073D01*
G01X1469631Y1836179D02*
X1457535D01*
G01X1442772Y1836081D02*
X1442543D01*
G01X1470921Y1835923D02*
X1469507D01*
G01X1470921Y1835254D02*
X1469507D01*
G01X1442772Y1835096D02*
X1442543D01*
G01X1469631Y1834998D02*
X1457535D01*
G01X1444212Y1834801D02*
X1443073D01*
G01X1457732Y1834407D02*
X1457220D01*
G01X1457732Y1833620D02*
X1457220D01*
G01X1444212Y1833226D02*
X1443073D01*
G01X1469631Y1833029D02*
X1457535D01*
G01X1442772Y1832931D02*
X1442543D01*
G01X1470921Y1832774D02*
X1469507D01*
G01X1470921Y1832104D02*
X1469507D01*
G01X1442772Y1831947D02*
X1442543D01*
G01X1469631Y1831848D02*
X1457535D01*
G01X1444212Y1831651D02*
X1443073D01*
G01X1457732Y1831258D02*
X1457220D01*
G01X1457732Y1830470D02*
X1457220D01*
G01X1444212Y1830077D02*
X1443073D01*
G01X1469631Y1829880D02*
X1457535D01*
G01X1442772Y1829781D02*
X1442543D01*
G01X1470921Y1829624D02*
X1469507D01*
G01X1470921Y1828955D02*
X1469507D01*
G01X1442772Y1828797D02*
X1442543D01*
G01X1469631Y1828699D02*
X1457535D01*
G01X1444212Y1828502D02*
X1443073D01*
G01X1457732Y1828108D02*
X1457220D01*
G01X1457732Y1827321D02*
X1457220D01*
G01X1444212Y1826927D02*
X1443073D01*
G01X1469631Y1826730D02*
X1457535D01*
G01X1442772Y1826632D02*
X1442543D01*
G01X1470921Y1826474D02*
X1469507D01*
G01X1470921Y1825805D02*
X1469507D01*
G01X1442772Y1825648D02*
X1442543D01*
G01X1469631Y1825549D02*
X1457535D01*
G01X1444212Y1825352D02*
X1443073D01*
G01X1457732Y1824959D02*
X1457220D01*
G01X1457732Y1824171D02*
X1457220D01*
G01X1444212Y1823777D02*
X1443073D01*
G01X1469631Y1823581D02*
X1457535D01*
G01X1442772Y1823482D02*
X1442543D01*
G01X1470921Y1823325D02*
X1469507D01*
G01X1470921Y1822655D02*
X1469507D01*
G01X1442772Y1822498D02*
X1442543D01*
G01X1469631Y1822400D02*
X1457535D01*
G01X1444212Y1822203D02*
X1443073D01*
G01X1457732Y1821809D02*
X1457220D01*
G01X1457732Y1821022D02*
X1457220D01*
G01X1444212Y1820628D02*
X1443073D01*
G01X1469631Y1820431D02*
X1457535D01*
G01X1442772Y1820333D02*
X1442543D01*
G01X1470921Y1820175D02*
X1469507D01*
G01X1470921Y1819506D02*
X1469507D01*
G01X1442772Y1819348D02*
X1442543D01*
G01X1469631Y1819250D02*
X1457535D01*
G01X1444212Y1819053D02*
X1443073D01*
G01X1457732Y1818659D02*
X1457220D01*
G01X1457732Y1817872D02*
X1457220D01*
G01X1444212Y1817478D02*
X1443073D01*
G01X1469631Y1817281D02*
X1457535D01*
G01X1442772Y1817183D02*
X1442543D01*
G01X1470921Y1817025D02*
X1469507D01*
G01X1470921Y1816356D02*
X1469507D01*
G01X1442772Y1816199D02*
X1442543D01*
G01X1469631Y1816100D02*
X1457535D01*
G01X1444212Y1815903D02*
X1443073D01*
G01X1457732Y1815510D02*
X1457220D01*
G01X1457732Y1814722D02*
X1457220D01*
G01X1444212Y1814329D02*
X1443073D01*
G01X1469631Y1814132D02*
X1457535D01*
G01X1442772Y1814033D02*
X1442543D01*
G01X1470921Y1813876D02*
X1469507D01*
G01X1470921Y1813207D02*
X1469507D01*
G01X1442772Y1813049D02*
X1442543D01*
G01X1469631Y1812951D02*
X1457535D01*
G01X1444212Y1812754D02*
X1443073D01*
G01X1457732Y1812360D02*
X1457220D01*
G01X1457732Y1811573D02*
X1457220D01*
G01X1444212Y1811179D02*
X1443073D01*
G01X1469631Y1810982D02*
X1457535D01*
G01X1442772Y1810884D02*
X1442543D01*
G01X1470921Y1810726D02*
X1469507D01*
G01X1470921Y1810057D02*
X1469507D01*
G01X1442772Y1809900D02*
X1442543D01*
G01X1469631Y1809801D02*
X1457535D01*
G01X1444212Y1809604D02*
X1443073D01*
G01X1457732Y1809211D02*
X1457220D01*
G01X1457732Y1808423D02*
X1457220D01*
G01X1444212Y1808029D02*
X1443073D01*
G01X1469631Y1807833D02*
X1457535D01*
G01X1442772Y1807734D02*
X1442543D01*
G01X1470921Y1807577D02*
X1469507D01*
G01X1470921Y1806907D02*
X1469507D01*
G01X1442772Y1806750D02*
X1442543D01*
G01X1469631Y1806651D02*
X1457535D01*
G01X1444212Y1806455D02*
X1443073D01*
G01X1457732Y1806061D02*
X1457220D01*
G01X1457732Y1805274D02*
X1457220D01*
G01X1444212Y1804880D02*
X1443073D01*
G01X1469631Y1804683D02*
X1457535D01*
G01X1442772Y1804585D02*
X1442543D01*
G01X1470921Y1804427D02*
X1469507D01*
G01X1470921Y1803758D02*
X1469507D01*
G01X1442772Y1803600D02*
X1442543D01*
G01X1469631Y1803502D02*
X1457535D01*
G01X1444212Y1803305D02*
X1443073D01*
G01X1457732Y1802911D02*
X1457220D01*
G01X1457732Y1802124D02*
X1457220D01*
G01X1444212Y1801730D02*
X1443073D01*
G01X1469631Y1801533D02*
X1457535D01*
G01X1442772Y1801435D02*
X1442543D01*
G01X1470921Y1801277D02*
X1469507D01*
G01X1470921Y1800608D02*
X1469507D01*
G01X1442772Y1800451D02*
X1442543D01*
G01X1469631Y1800352D02*
X1457535D01*
G01X1444212Y1800155D02*
X1443073D01*
G01X1457732Y1799762D02*
X1457220D01*
G01X1457732Y1798974D02*
X1457220D01*
G01X1444212Y1798581D02*
X1443073D01*
G01X1469631Y1798384D02*
X1457535D01*
G01X1442772Y1798285D02*
X1442543D01*
G01X1470921Y1798128D02*
X1469507D01*
G01X1470921Y1797459D02*
X1469507D01*
G01X1442772Y1797301D02*
X1442543D01*
G01X1469631Y1797203D02*
X1457535D01*
G01X1442684Y1866505D02*
X1443073Y1866297D01*
G01X1442684Y1863355D02*
X1443073Y1863148D01*
G01X1442684Y1860205D02*
X1443073Y1859998D01*
G01X1442684Y1857056D02*
X1443073Y1856848D01*
G01X1442684Y1853906D02*
X1443073Y1853699D01*
G01X1442684Y1850757D02*
X1443073Y1850549D01*
G01X1442684Y1847607D02*
X1443073Y1847400D01*
G01X1442684Y1844457D02*
X1443073Y1844250D01*
G01X1442684Y1841308D02*
X1443073Y1841100D01*
G01X1442684Y1838158D02*
X1443073Y1837951D01*
G01X1442684Y1835009D02*
X1443073Y1834801D01*
G01X1442684Y1831859D02*
X1443073Y1831651D01*
G01X1442684Y1828709D02*
X1443073Y1828502D01*
G01X1442684Y1825560D02*
X1443073Y1825352D01*
G01X1442684Y1822410D02*
X1443073Y1822203D01*
G01X1442684Y1819261D02*
X1443073Y1819053D01*
G01X1442772Y1866592D02*
X1443243Y1866297D01*
G01X1442543Y1866592D02*
X1442684Y1866505D01*
G01X1442772Y1863443D02*
X1443243Y1863148D01*
G01X1442543Y1863443D02*
X1442684Y1863355D01*
G01X1442772Y1860293D02*
X1443243Y1859998D01*
G01X1442543Y1860293D02*
X1442684Y1860205D01*
G01X1442772Y1857144D02*
X1443243Y1856848D01*
G01X1442543Y1857144D02*
X1442684Y1857056D01*
G01X1442772Y1853994D02*
X1443243Y1853699D01*
G01X1442543Y1853994D02*
X1442684Y1853906D01*
G01X1442772Y1850844D02*
X1443243Y1850549D01*
G01X1442543Y1850844D02*
X1442684Y1850757D01*
G01X1442772Y1847695D02*
X1443243Y1847400D01*
G01X1442543Y1847695D02*
X1442684Y1847607D01*
G01X1442772Y1844545D02*
X1443243Y1844250D01*
G01X1442543Y1844545D02*
X1442684Y1844457D01*
G01X1442772Y1841396D02*
X1443243Y1841100D01*
G01X1442543Y1841396D02*
X1442684Y1841308D01*
G01X1442772Y1838246D02*
X1443243Y1837951D01*
G01X1442543Y1838246D02*
X1442684Y1838158D01*
G01X1442772Y1835096D02*
X1443243Y1834801D01*
G01X1442543Y1835096D02*
X1442684Y1835009D01*
G01X1442772Y1831947D02*
X1443243Y1831651D01*
G01X1442543Y1831947D02*
X1442684Y1831859D01*
G01X1442772Y1828797D02*
X1443243Y1828502D01*
G01X1442543Y1828797D02*
X1442684Y1828709D01*
G01X1442772Y1825648D02*
X1443243Y1825352D01*
G01X1442543Y1825648D02*
X1442684Y1825560D01*
G01X1442772Y1822498D02*
X1443243Y1822203D01*
G01X1442543Y1822498D02*
X1442684Y1822410D01*
G01X1442772Y1819348D02*
X1443243Y1819053D01*
G01X1442543Y1819348D02*
X1442684Y1819261D01*
G01X1442772Y1816199D02*
X1443243Y1815903D01*
G01X1442543Y1816199D02*
X1442684Y1816111D01*
G01X1442772Y1813049D02*
X1443243Y1812754D01*
G01X1442543Y1813049D02*
X1442684Y1812961D01*
G01X1442772Y1809900D02*
X1443243Y1809604D01*
G01X1442543Y1809900D02*
X1442684Y1809812D01*
G01X1442772Y1806750D02*
X1443243Y1806455D01*
G01X1442543Y1806750D02*
X1442684Y1806662D01*
G01X1442772Y1803600D02*
X1443243Y1803305D01*
G01X1442543Y1803600D02*
X1442684Y1803512D01*
G01X1442772Y1800451D02*
X1443243Y1800155D01*
G01X1442543Y1800451D02*
X1442684Y1800363D01*
G01X1442543Y1797301D02*
X1442684Y1797213D01*
G01Y1816111D02*
X1443073Y1815903D01*
G01X1442684Y1812961D02*
X1443073Y1812754D01*
G01X1442684Y1809812D02*
X1443073Y1809604D01*
G01X1442684Y1806662D02*
X1443073Y1806455D01*
G01X1442684Y1803512D02*
X1443073Y1803305D01*
G01X1442684Y1800363D02*
X1443073Y1800155D01*
G01X1469278Y1864525D02*
X1469507Y1864270D01*
G01X1469278Y1861376D02*
X1469507Y1861120D01*
G01X1469278Y1858226D02*
X1469507Y1857970D01*
G01X1469278Y1855077D02*
X1469507Y1854821D01*
G01X1469278Y1851927D02*
X1469507Y1851671D01*
G01X1469278Y1848777D02*
X1469507Y1848522D01*
G01X1469278Y1845628D02*
X1469507Y1845372D01*
G01X1469278Y1842478D02*
X1469507Y1842222D01*
G01X1469278Y1839329D02*
X1469507Y1839073D01*
G01X1469278Y1836179D02*
X1469507Y1835923D01*
G01X1469636Y1864540D02*
X1469855Y1864270D01*
G01X1469636Y1861390D02*
X1469855Y1861120D01*
G01X1469636Y1858240D02*
X1469855Y1857970D01*
G01X1469636Y1855091D02*
X1469855Y1854821D01*
G01X1469636Y1851941D02*
X1469855Y1851671D01*
G01X1469636Y1848792D02*
X1469855Y1848522D01*
G01X1469636Y1845642D02*
X1469855Y1845372D01*
G01X1469636Y1842492D02*
X1469855Y1842222D01*
G01X1469636Y1839343D02*
X1469855Y1839073D01*
G01X1469636Y1836193D02*
X1469855Y1835923D01*
G01X1469636Y1833044D02*
X1469855Y1832774D01*
G01X1469636Y1829894D02*
X1469855Y1829624D01*
G01X1469636Y1826744D02*
X1469855Y1826474D01*
G01X1469636Y1823595D02*
X1469855Y1823325D01*
G01X1469636Y1820445D02*
X1469855Y1820175D01*
G01X1469636Y1817296D02*
X1469855Y1817025D01*
G01X1469636Y1814146D02*
X1469855Y1813876D01*
G01X1469636Y1810996D02*
X1469855Y1810726D01*
G01X1469636Y1807847D02*
X1469855Y1807577D01*
G01X1469636Y1804697D02*
X1469855Y1804427D01*
G01X1469636Y1801547D02*
X1469855Y1801277D01*
G01X1469636Y1798398D02*
X1469855Y1798128D01*
G01X1469278Y1833029D02*
X1469507Y1832774D01*
G01X1469278Y1829880D02*
X1469507Y1829624D01*
G01X1469278Y1826730D02*
X1469507Y1826474D01*
G01X1469278Y1823581D02*
X1469507Y1823325D01*
G01X1469278Y1820431D02*
X1469507Y1820175D01*
G01X1469278Y1817281D02*
X1469507Y1817025D01*
G01X1469278Y1814132D02*
X1469507Y1813876D01*
G01X1469278Y1810982D02*
X1469507Y1810726D01*
G01X1469278Y1807833D02*
X1469507Y1807577D01*
G01X1469278Y1804683D02*
X1469507Y1804427D01*
G01X1469278Y1801533D02*
X1469507Y1801277D01*
G01X1469278Y1798384D02*
X1469507Y1798128D01*
G01X1470921D02*
Y1797459D01*
G01Y1804427D02*
Y1803758D01*
G01Y1801277D02*
Y1800608D01*
G01Y1807577D02*
Y1806907D01*
G01Y1813876D02*
Y1813207D01*
G01Y1810726D02*
Y1810057D01*
G01Y1817025D02*
Y1816356D01*
G01Y1823325D02*
Y1822655D01*
G01Y1820175D02*
Y1819506D01*
G01Y1826474D02*
Y1825805D01*
G01Y1832774D02*
Y1832104D01*
G01Y1829624D02*
Y1828955D01*
G01Y1835923D02*
Y1835254D01*
G01Y1842222D02*
Y1841553D01*
G01Y1839073D02*
Y1838403D01*
G01Y1845372D02*
Y1844703D01*
G01Y1851671D02*
Y1851002D01*
G01Y1848522D02*
Y1847852D01*
G01Y1854821D02*
Y1854151D01*
G01Y1861120D02*
Y1860451D01*
G01Y1857970D02*
Y1857301D01*
G01Y1864270D02*
Y1863600D01*
G01X1470574Y1798128D02*
Y1797459D01*
G01Y1804427D02*
Y1803758D01*
G01Y1801277D02*
Y1800608D01*
G01Y1807577D02*
Y1806907D01*
G01Y1813876D02*
Y1813207D01*
G01Y1810726D02*
Y1810057D01*
G01Y1817025D02*
Y1816356D01*
G01Y1823325D02*
Y1822655D01*
G01Y1820175D02*
Y1819506D01*
G01Y1826474D02*
Y1825805D01*
G01Y1832774D02*
Y1832104D01*
G01Y1829624D02*
Y1828955D01*
G01Y1835923D02*
Y1835254D01*
G01Y1842222D02*
Y1841553D01*
G01Y1839073D02*
Y1838403D01*
G01Y1845372D02*
Y1844703D01*
G01Y1851671D02*
Y1851002D01*
G01Y1848522D02*
Y1847852D01*
G01Y1854821D02*
Y1854151D01*
G01Y1861120D02*
Y1860451D01*
G01Y1857970D02*
Y1857301D01*
G01Y1864270D02*
Y1863600D01*
G01X1469631Y1798384D02*
Y1797203D01*
G01Y1804683D02*
Y1803502D01*
G01Y1801533D02*
Y1800352D01*
G01Y1807833D02*
Y1806651D01*
G01Y1814132D02*
Y1812951D01*
G01Y1810982D02*
Y1809801D01*
G01Y1817281D02*
Y1816100D01*
G01Y1823581D02*
Y1822400D01*
G01Y1820431D02*
Y1819250D01*
G01Y1826730D02*
Y1825549D01*
G01Y1833029D02*
Y1831848D01*
G01Y1829880D02*
Y1828699D01*
G01Y1836179D02*
Y1834998D01*
G01Y1842478D02*
Y1841297D01*
G01Y1839329D02*
Y1838148D01*
G01Y1845628D02*
Y1844447D01*
G01Y1851927D02*
Y1850746D01*
G01Y1848777D02*
Y1847596D01*
G01Y1855077D02*
Y1853896D01*
G01Y1861376D02*
Y1860195D01*
G01Y1858226D02*
Y1857045D01*
G01Y1864525D02*
Y1863344D01*
G01X1469278Y1798384D02*
Y1797203D01*
G01Y1804683D02*
Y1803502D01*
G01Y1801533D02*
Y1800352D01*
G01Y1807833D02*
Y1806651D01*
G01Y1814132D02*
Y1812951D01*
G01Y1810982D02*
Y1809801D01*
G01Y1817281D02*
Y1816100D01*
G01Y1823581D02*
Y1822400D01*
G01Y1820431D02*
Y1819250D01*
G01Y1826730D02*
Y1825549D01*
G01Y1833029D02*
Y1831848D01*
G01Y1829880D02*
Y1828699D01*
G01Y1836179D02*
Y1834998D01*
G01Y1842478D02*
Y1841297D01*
G01Y1839329D02*
Y1838148D01*
G01Y1845628D02*
Y1844447D01*
G01Y1851927D02*
Y1850746D01*
G01Y1848777D02*
Y1847596D01*
G01Y1855077D02*
Y1853896D01*
G01Y1861376D02*
Y1860195D01*
G01Y1858226D02*
Y1857045D01*
G01Y1864525D02*
Y1863344D01*
G01X1467296Y1798384D02*
Y1797203D01*
G01Y1804683D02*
Y1803502D01*
G01Y1801533D02*
Y1800352D01*
G01Y1807833D02*
Y1806651D01*
G01Y1814132D02*
Y1812951D01*
G01Y1810982D02*
Y1809801D01*
G01Y1817281D02*
Y1816100D01*
G01Y1823581D02*
Y1822400D01*
G01Y1820431D02*
Y1819250D01*
G01Y1826730D02*
Y1825549D01*
G01Y1833029D02*
Y1831848D01*
G01Y1829880D02*
Y1828699D01*
G01Y1836179D02*
Y1834998D01*
G01Y1842478D02*
Y1841297D01*
G01Y1839329D02*
Y1838148D01*
G01Y1845628D02*
Y1844447D01*
G01Y1851927D02*
Y1850746D01*
G01Y1848777D02*
Y1847596D01*
G01Y1855077D02*
Y1853896D01*
G01Y1861376D02*
Y1860195D01*
G01Y1858226D02*
Y1857045D01*
G01Y1864525D02*
Y1863344D01*
G01X1467186Y1798384D02*
Y1797203D01*
G01Y1804683D02*
Y1803502D01*
G01Y1801533D02*
Y1800352D01*
G01Y1807833D02*
Y1806651D01*
G01Y1814132D02*
Y1812951D01*
G01Y1810982D02*
Y1809801D01*
G01Y1817281D02*
Y1816100D01*
G01Y1823581D02*
Y1822400D01*
G01Y1820431D02*
Y1819250D01*
G01Y1826730D02*
Y1825549D01*
G01Y1833029D02*
Y1831848D01*
G01Y1829880D02*
Y1828699D01*
G01Y1836179D02*
Y1834998D01*
G01Y1842478D02*
Y1841297D01*
G01Y1839329D02*
Y1838148D01*
G01Y1845628D02*
Y1844447D01*
G01Y1851927D02*
Y1850746D01*
G01Y1848777D02*
Y1847596D01*
G01Y1855077D02*
Y1853896D01*
G01Y1861376D02*
Y1860195D01*
G01Y1858226D02*
Y1857045D01*
G01Y1864525D02*
Y1863344D01*
G01X1458405Y1798384D02*
Y1797203D01*
G01Y1804683D02*
Y1803502D01*
G01Y1801533D02*
Y1800352D01*
G01Y1807833D02*
Y1806651D01*
G01Y1814132D02*
Y1812951D01*
G01Y1810982D02*
Y1809801D01*
G01Y1817281D02*
Y1816100D01*
G01Y1823581D02*
Y1822400D01*
G01Y1820431D02*
Y1819250D01*
G01Y1826730D02*
Y1825549D01*
G01Y1833029D02*
Y1831848D01*
G01Y1829880D02*
Y1828699D01*
G01Y1836179D02*
Y1834998D01*
G01Y1842478D02*
Y1841297D01*
G01Y1839329D02*
Y1838148D01*
G01Y1845628D02*
Y1844447D01*
G01Y1851927D02*
Y1850746D01*
G01Y1848777D02*
Y1847596D01*
G01Y1855077D02*
Y1853896D01*
G01Y1861376D02*
Y1860195D01*
G01Y1858226D02*
Y1857045D01*
G01Y1864525D02*
Y1863344D01*
G01X1458295Y1798384D02*
Y1797203D01*
G01Y1804683D02*
Y1803502D01*
G01Y1801533D02*
Y1800352D01*
G01Y1807833D02*
Y1806651D01*
G01Y1814132D02*
Y1812951D01*
G01Y1810982D02*
Y1809801D01*
G01Y1817281D02*
Y1816100D01*
G01Y1823581D02*
Y1822400D01*
G01Y1820431D02*
Y1819250D01*
G01Y1826730D02*
Y1825549D01*
G01Y1833029D02*
Y1831848D01*
G01Y1829880D02*
Y1828699D01*
G01Y1836179D02*
Y1834998D01*
G01Y1842478D02*
Y1841297D01*
G01Y1839329D02*
Y1838148D01*
G01Y1845628D02*
Y1844447D01*
G01Y1851927D02*
Y1850746D01*
G01Y1848777D02*
Y1847596D01*
G01Y1855077D02*
Y1853896D01*
G01Y1861376D02*
Y1860195D01*
G01Y1858226D02*
Y1857045D01*
G01Y1864525D02*
Y1863344D01*
G01X1457929Y1798384D02*
Y1797203D01*
G01Y1804683D02*
Y1803502D01*
G01Y1801533D02*
Y1800352D01*
G01Y1807833D02*
Y1806651D01*
G01Y1814132D02*
Y1812951D01*
G01Y1810982D02*
Y1809801D01*
G01Y1817281D02*
Y1816100D01*
G01Y1823581D02*
Y1822400D01*
G01Y1820431D02*
Y1819250D01*
G01Y1826730D02*
Y1825549D01*
G01Y1833029D02*
Y1831848D01*
G01Y1829880D02*
Y1828699D01*
G01Y1836179D02*
Y1834998D01*
G01Y1842478D02*
Y1841297D01*
G01Y1839329D02*
Y1838148D01*
G01Y1845628D02*
Y1844447D01*
G01Y1851927D02*
Y1850746D01*
G01Y1848777D02*
Y1847596D01*
G01Y1855077D02*
Y1853896D01*
G01Y1861376D02*
Y1860195D01*
G01Y1858226D02*
Y1857045D01*
G01Y1864525D02*
Y1863344D01*
G01X1457732Y1800352D02*
Y1799762D01*
G01Y1798974D02*
Y1798384D01*
G01Y1803502D02*
Y1802911D01*
G01Y1805274D02*
Y1804683D01*
G01Y1802124D02*
Y1801533D01*
G01Y1809801D02*
Y1809211D01*
G01Y1806651D02*
Y1806061D01*
G01Y1808423D02*
Y1807833D01*
G01Y1812951D02*
Y1812360D01*
G01Y1814722D02*
Y1814132D01*
G01Y1811573D02*
Y1810982D01*
G01Y1819250D02*
Y1818659D01*
G01Y1816100D02*
Y1815510D01*
G01Y1817872D02*
Y1817281D01*
G01Y1822400D02*
Y1821809D01*
G01Y1824171D02*
Y1823581D01*
G01Y1821022D02*
Y1820431D01*
G01Y1828699D02*
Y1828108D01*
G01Y1825549D02*
Y1824959D01*
G01Y1827321D02*
Y1826730D01*
G01Y1831848D02*
Y1831258D01*
G01Y1833620D02*
Y1833029D01*
G01Y1830470D02*
Y1829880D01*
G01Y1838148D02*
Y1837557D01*
G01Y1834998D02*
Y1834407D01*
G01Y1836770D02*
Y1836179D01*
G01Y1841297D02*
Y1840707D01*
G01Y1843069D02*
Y1842478D01*
G01Y1839919D02*
Y1839329D01*
G01Y1847596D02*
Y1847006D01*
G01Y1844447D02*
Y1843856D01*
G01Y1846218D02*
Y1845628D01*
G01Y1850746D02*
Y1850155D01*
G01Y1852518D02*
Y1851927D01*
G01Y1849368D02*
Y1848777D01*
G01Y1857045D02*
Y1856455D01*
G01Y1853896D02*
Y1853305D01*
G01Y1855667D02*
Y1855077D01*
G01Y1860195D02*
Y1859604D01*
G01Y1858817D02*
Y1858226D01*
G01Y1866494D02*
Y1865903D01*
G01Y1863344D02*
Y1862754D01*
G01Y1865116D02*
Y1864525D01*
G01Y1861966D02*
Y1861376D01*
G01X1457535Y1800352D02*
Y1799762D01*
G01Y1798974D02*
Y1798384D01*
G01Y1803502D02*
Y1802911D01*
G01Y1805274D02*
Y1804683D01*
G01Y1802124D02*
Y1801533D01*
G01Y1809801D02*
Y1809211D01*
G01Y1806651D02*
Y1806061D01*
G01Y1808423D02*
Y1807833D01*
G01Y1812951D02*
Y1812360D01*
G01Y1814722D02*
Y1814132D01*
G01Y1811573D02*
Y1810982D01*
G01Y1819250D02*
Y1818659D01*
G01Y1816100D02*
Y1815510D01*
G01Y1817872D02*
Y1817281D01*
G01Y1822400D02*
Y1821809D01*
G01Y1824171D02*
Y1823581D01*
G01Y1821022D02*
Y1820431D01*
G01Y1828699D02*
Y1828108D01*
G01Y1825549D02*
Y1824959D01*
G01Y1827321D02*
Y1826730D01*
G01Y1831848D02*
Y1831258D01*
G01Y1833620D02*
Y1833029D01*
G01Y1830470D02*
Y1829880D01*
G01Y1838148D02*
Y1837557D01*
G01Y1834998D02*
Y1834407D01*
G01Y1836770D02*
Y1836179D01*
G01Y1841297D02*
Y1840707D01*
G01Y1843069D02*
Y1842478D01*
G01Y1839919D02*
Y1839329D01*
G01Y1847596D02*
Y1847006D01*
G01Y1844447D02*
Y1843856D01*
G01Y1846218D02*
Y1845628D01*
G01Y1850746D02*
Y1850155D01*
G01Y1852518D02*
Y1851927D01*
G01Y1849368D02*
Y1848777D01*
G01Y1857045D02*
Y1856455D01*
G01Y1853896D02*
Y1853305D01*
G01Y1855667D02*
Y1855077D01*
G01Y1860195D02*
Y1859604D01*
G01Y1858817D02*
Y1858226D01*
G01Y1866494D02*
Y1865903D01*
G01Y1863344D02*
Y1862754D01*
G01Y1865116D02*
Y1864525D01*
G01Y1861966D02*
Y1861376D01*
G01X1444212Y1804880D02*
Y1803305D01*
G01Y1801730D02*
Y1800155D01*
G01Y1808029D02*
Y1806455D01*
G01Y1814329D02*
Y1812754D01*
G01Y1811179D02*
Y1809604D01*
G01Y1817478D02*
Y1815903D01*
G01Y1823777D02*
Y1822203D01*
G01Y1820628D02*
Y1819053D01*
G01Y1826927D02*
Y1825352D01*
G01Y1833226D02*
Y1831651D01*
G01Y1830077D02*
Y1828502D01*
G01Y1836376D02*
Y1834801D01*
G01Y1842675D02*
Y1841100D01*
G01Y1839525D02*
Y1837951D01*
G01Y1845825D02*
Y1844250D01*
G01Y1852124D02*
Y1850549D01*
G01Y1848974D02*
Y1847400D01*
G01Y1855274D02*
Y1853699D01*
G01Y1861573D02*
Y1859998D01*
G01Y1858423D02*
Y1856848D01*
G01Y1864722D02*
Y1863148D01*
G01Y1867872D02*
Y1866297D01*
G01X1442684Y1798373D02*
Y1797213D01*
G01Y1804672D02*
Y1803512D01*
G01Y1801523D02*
Y1800363D01*
G01Y1807822D02*
Y1806662D01*
G01Y1814121D02*
Y1812961D01*
G01Y1810972D02*
Y1809812D01*
G01Y1817271D02*
Y1816111D01*
G01Y1823570D02*
Y1822410D01*
G01Y1820420D02*
Y1819261D01*
G01Y1826720D02*
Y1825560D01*
G01Y1833019D02*
Y1831859D01*
G01Y1829869D02*
Y1828709D01*
G01Y1836168D02*
Y1835009D01*
G01Y1842468D02*
Y1841308D01*
G01Y1839318D02*
Y1838158D01*
G01Y1845617D02*
Y1844457D01*
G01Y1851916D02*
Y1850757D01*
G01Y1848767D02*
Y1847607D01*
G01Y1855066D02*
Y1853906D01*
G01Y1861365D02*
Y1860205D01*
G01Y1858216D02*
Y1857056D01*
G01Y1864515D02*
Y1863355D01*
G01X1443073Y1798581D02*
X1442684Y1798373D01*
G01X1443073Y1801730D02*
X1442684Y1801523D01*
G01X1443073Y1804880D02*
X1442684Y1804672D01*
G01X1443073Y1808029D02*
X1442684Y1807822D01*
G01X1443073Y1811179D02*
X1442684Y1810972D01*
G01X1443073Y1814329D02*
X1442684Y1814121D01*
G01X1443073Y1817478D02*
X1442684Y1817271D01*
G01X1443073Y1820628D02*
X1442684Y1820420D01*
G01X1443073Y1823777D02*
X1442684Y1823570D01*
G01X1443073Y1826927D02*
X1442684Y1826720D01*
G01X1443073Y1830077D02*
X1442684Y1829869D01*
G01X1443073Y1833226D02*
X1442684Y1833019D01*
G01X1443073Y1836376D02*
X1442684Y1836168D01*
G01X1443073Y1839525D02*
X1442684Y1839318D01*
G01X1443073Y1842675D02*
X1442684Y1842468D01*
G01X1443243Y1798581D02*
X1442772Y1798285D01*
G01X1442684Y1798373D02*
X1442543Y1798285D01*
G01X1443243Y1801730D02*
X1442772Y1801435D01*
G01X1442684Y1801523D02*
X1442543Y1801435D01*
G01X1443243Y1804880D02*
X1442772Y1804585D01*
G01X1442684Y1804672D02*
X1442543Y1804585D01*
G01X1443243Y1808029D02*
X1442772Y1807734D01*
G01X1442684Y1807822D02*
X1442543Y1807734D01*
G01X1443243Y1811179D02*
X1442772Y1810884D01*
G01X1442684Y1810972D02*
X1442543Y1810884D01*
G01X1443243Y1814329D02*
X1442772Y1814033D01*
G01X1442684Y1814121D02*
X1442543Y1814033D01*
G01X1443243Y1817478D02*
X1442772Y1817183D01*
G01X1442684Y1817271D02*
X1442543Y1817183D01*
G01X1443243Y1820628D02*
X1442772Y1820333D01*
G01X1442684Y1820420D02*
X1442543Y1820333D01*
G01X1443243Y1823777D02*
X1442772Y1823482D01*
G01X1442684Y1823570D02*
X1442543Y1823482D01*
G01X1443243Y1826927D02*
X1442772Y1826632D01*
G01X1442684Y1826720D02*
X1442543Y1826632D01*
G01X1443243Y1830077D02*
X1442772Y1829781D01*
G01X1442684Y1829869D02*
X1442543Y1829781D01*
G01X1469507Y1797459D02*
X1469278Y1797203D01*
G01X1469507Y1800608D02*
X1469278Y1800352D01*
G01X1469507Y1803758D02*
X1469278Y1803502D01*
G01X1469507Y1806907D02*
X1469278Y1806651D01*
G01X1469507Y1810057D02*
X1469278Y1809801D01*
G01X1469507Y1813207D02*
X1469278Y1812951D01*
G01X1469507Y1816356D02*
X1469278Y1816100D01*
G01X1469507Y1819506D02*
X1469278Y1819250D01*
G01X1469507Y1822655D02*
X1469278Y1822400D01*
G01X1469507Y1825805D02*
X1469278Y1825549D01*
G01X1469507Y1828955D02*
X1469278Y1828699D01*
G01X1469507Y1832104D02*
X1469278Y1831848D01*
G01X1469507Y1835254D02*
X1469278Y1834998D01*
G01X1469507Y1838403D02*
X1469278Y1838148D01*
G01X1469507Y1841553D02*
X1469278Y1841297D01*
G01X1469507Y1844703D02*
X1469278Y1844447D01*
G01X1469855Y1797459D02*
X1469636Y1797189D01*
G01X1469855Y1800608D02*
X1469636Y1800338D01*
G01X1469855Y1803758D02*
X1469636Y1803488D01*
G01X1469855Y1806907D02*
X1469636Y1806637D01*
G01X1469855Y1810057D02*
X1469636Y1809787D01*
G01X1469855Y1813207D02*
X1469636Y1812937D01*
G01X1469855Y1816356D02*
X1469636Y1816086D01*
G01X1469855Y1819506D02*
X1469636Y1819236D01*
G01X1469855Y1822655D02*
X1469636Y1822385D01*
G01X1469855Y1825805D02*
X1469636Y1825535D01*
G01X1469855Y1828955D02*
X1469636Y1828685D01*
G01X1469855Y1832104D02*
X1469636Y1831834D01*
G01X1469855Y1835254D02*
X1469636Y1834984D01*
G01X1469855Y1838403D02*
X1469636Y1838133D01*
G01X1469855Y1841553D02*
X1469636Y1841283D01*
G01X1469855Y1844703D02*
X1469636Y1844433D01*
G01X1469855Y1847852D02*
X1469636Y1847582D01*
G01X1469855Y1851002D02*
X1469636Y1850732D01*
G01X1469855Y1854151D02*
X1469636Y1853881D01*
G01X1443073Y1845825D02*
X1442684Y1845617D01*
G01X1443073Y1848974D02*
X1442684Y1848767D01*
G01X1443073Y1852124D02*
X1442684Y1851916D01*
G01X1443073Y1855274D02*
X1442684Y1855066D01*
G01X1443073Y1858423D02*
X1442684Y1858216D01*
G01X1443073Y1861573D02*
X1442684Y1861365D01*
G01X1443073Y1864722D02*
X1442684Y1864515D01*
G01X1443243Y1833226D02*
X1442772Y1832931D01*
G01X1442684Y1833019D02*
X1442543Y1832931D01*
G01X1443243Y1836376D02*
X1442772Y1836081D01*
G01X1442684Y1836168D02*
X1442543Y1836081D01*
G01X1443243Y1839525D02*
X1442772Y1839230D01*
G01X1442684Y1839318D02*
X1442543Y1839230D01*
G01X1443243Y1842675D02*
X1442772Y1842380D01*
G01X1442684Y1842468D02*
X1442543Y1842380D01*
G01X1443243Y1845825D02*
X1442772Y1845529D01*
G01X1442684Y1845617D02*
X1442543Y1845529D01*
G01X1443243Y1848974D02*
X1442772Y1848679D01*
G01X1442684Y1848767D02*
X1442543Y1848679D01*
G01X1443243Y1852124D02*
X1442772Y1851829D01*
G01X1442684Y1851916D02*
X1442543Y1851829D01*
G01X1443243Y1855274D02*
X1442772Y1854978D01*
G01X1442684Y1855066D02*
X1442543Y1854978D01*
G01X1443243Y1858423D02*
X1442772Y1858128D01*
G01X1442684Y1858216D02*
X1442543Y1858128D01*
G01X1443243Y1861573D02*
X1442772Y1861277D01*
G01X1442684Y1861365D02*
X1442543Y1861277D01*
G01X1443243Y1864722D02*
X1442772Y1864427D01*
G01X1442684Y1864515D02*
X1442543Y1864427D01*
G01X1469507Y1847852D02*
X1469278Y1847596D01*
G01X1469507Y1851002D02*
X1469278Y1850746D01*
G01X1469507Y1854151D02*
X1469278Y1853896D01*
G01X1469507Y1857301D02*
X1469278Y1857045D01*
G01X1469507Y1860451D02*
X1469278Y1860195D01*
G01X1469507Y1863600D02*
X1469278Y1863344D01*
G01X1469507Y1866750D02*
X1469278Y1866494D01*
G01X1469855Y1857301D02*
X1469636Y1857031D01*
G01X1469855Y1860451D02*
X1469636Y1860181D01*
G01X1469855Y1863600D02*
X1469636Y1863330D01*
G01X1469855Y1866750D02*
X1469636Y1866480D01*
G01X1439047Y1869780D02*
X1442543Y1869742D01*
G01X1437751Y1869794D02*
X1441007Y1869758D01*
G01X1439047Y1866630D02*
X1442543Y1866592D01*
G01X1437751Y1866645D02*
X1441007Y1866609D01*
G01X1438785Y1869780D02*
X1436420Y1869806D01*
G01X1438785Y1866630D02*
X1436420Y1866657D01*
G01X1441235Y1869758D02*
X1442772Y1869742D01*
G01X1441235Y1866609D02*
X1442772Y1866592D01*
G01X1441235Y1869758D02*
X1438785Y1869780D01*
G01X1437751Y1869794D02*
X1436420Y1869806D01*
G01X1441235Y1866609D02*
X1438785Y1866630D01*
G01X1437751Y1866645D02*
X1436420Y1866657D01*
G01X1439047Y1869780D02*
X1438785D01*
G01X1441235Y1869758D02*
X1441007D01*
G01X1441235Y1867560D02*
X1441007D01*
G01X1439047Y1867539D02*
X1438785D01*
G01X1439047Y1866630D02*
X1438785D01*
G01X1441235Y1866609D02*
X1441007D01*
G01X1440094Y1867550D02*
X1438785Y1867539D01*
G01X1441235Y1867560D02*
X1440094Y1867550D01*
G01X1437751Y1867524D02*
X1436420Y1867513D01*
G01X1442543Y1867577D02*
X1441007Y1867560D01*
G01X1442543Y1867577D02*
X1439047Y1867539D01*
G01X1441235Y1867560D02*
X1442772Y1867577D01*
G01X1439047Y1867539D02*
X1440094Y1867550D01*
G01X1438785Y1867539D02*
X1436420Y1867513D01*
G01X1437751Y1867524D02*
X1439047Y1867539D01*
G01X1441235Y1870710D02*
Y1869758D01*
G01Y1867560D02*
Y1866609D01*
G01X1441007Y1870710D02*
Y1869758D01*
G01Y1867560D02*
Y1866609D01*
G01X1439047Y1870688D02*
Y1869780D01*
G01Y1867539D02*
Y1866630D01*
G01X1438785Y1870688D02*
Y1869780D01*
G01Y1867539D02*
Y1866630D01*
G01X1437751Y1870668D02*
Y1869800D01*
G01Y1867518D02*
Y1866651D01*
G01X1436420Y1870662D02*
Y1869806D01*
G01Y1867513D02*
Y1866657D01*
G01X1439047Y1939071D02*
X1442543Y1939033D01*
G01X1437751Y1939086D02*
X1441007Y1939050D01*
G01X1439047Y1935922D02*
X1442543Y1935884D01*
G01X1437751Y1935936D02*
X1441007Y1935900D01*
G01X1439047Y1920174D02*
X1442543Y1920136D01*
G01X1437751Y1920188D02*
X1441007Y1920152D01*
G01X1439047Y1917024D02*
X1442543Y1916986D01*
G01X1437751Y1917038D02*
X1441007Y1917003D01*
G01X1439047Y1913874D02*
X1442543Y1913837D01*
G01X1437751Y1913889D02*
X1441007Y1913853D01*
G01X1439047Y1910725D02*
X1442543Y1910687D01*
G01X1437751Y1910739D02*
X1441007Y1910703D01*
G01X1439047Y1907575D02*
X1442543Y1907537D01*
G01X1437751Y1907590D02*
X1441007Y1907554D01*
G01X1439047Y1904426D02*
X1442543Y1904388D01*
G01X1437751Y1904440D02*
X1441007Y1904404D01*
G01X1439047Y1901276D02*
X1442543Y1901238D01*
G01X1437751Y1901290D02*
X1441007Y1901255D01*
G01X1439047Y1898126D02*
X1442543Y1898088D01*
G01X1437751Y1898141D02*
X1441007Y1898105D01*
G01X1438785Y1939071D02*
X1436420Y1939097D01*
G01X1438785Y1935922D02*
X1436420Y1935948D01*
G01X1438785Y1920174D02*
X1436420Y1920200D01*
G01X1438785Y1917024D02*
X1436420Y1917050D01*
G01X1438785Y1913875D02*
X1436420Y1913901D01*
G01X1438785Y1910725D02*
X1436420Y1910751D01*
G01X1438785Y1907575D02*
X1436420Y1907601D01*
G01X1438785Y1904426D02*
X1436420Y1904452D01*
G01X1438785Y1901276D02*
X1436420Y1901302D01*
G01X1438785Y1898127D02*
X1436420Y1898153D01*
G01X1441235Y1939050D02*
X1442772Y1939033D01*
G01X1441235Y1935900D02*
X1442772Y1935884D01*
G01X1441235Y1920152D02*
X1442772Y1920136D01*
G01X1441235Y1917003D02*
X1442772Y1916986D01*
G01X1441235Y1913853D02*
X1442772Y1913837D01*
G01X1441235Y1910703D02*
X1442772Y1910687D01*
G01X1441235Y1907554D02*
X1442772Y1907537D01*
G01X1441235Y1904404D02*
X1442772Y1904388D01*
G01X1441235Y1901255D02*
X1442772Y1901238D01*
G01X1441235Y1898105D02*
X1442772Y1898088D01*
G01X1441235Y1939050D02*
X1438785Y1939071D01*
G01X1437751Y1939086D02*
X1436420Y1939097D01*
G01X1441235Y1935900D02*
X1438785Y1935922D01*
G01X1437751Y1935936D02*
X1436420Y1935948D01*
G01X1441235Y1920152D02*
X1438785Y1920174D01*
G01X1437751Y1920188D02*
X1436420Y1920200D01*
G01X1441235Y1917003D02*
X1438785Y1917024D01*
G01X1437751Y1917038D02*
X1436420Y1917050D01*
G01X1441235Y1913853D02*
X1438785Y1913875D01*
G01X1437751Y1913889D02*
X1436420Y1913901D01*
G01X1441235Y1910703D02*
X1438785Y1910725D01*
G01X1437751Y1910739D02*
X1436420Y1910751D01*
G01X1441235Y1907554D02*
X1438785Y1907575D01*
G01X1437751Y1907590D02*
X1436420Y1907601D01*
G01X1441235Y1904404D02*
X1438785Y1904426D01*
G01X1437751Y1904440D02*
X1436420Y1904452D01*
G01X1441235Y1901255D02*
X1438785Y1901276D01*
G01X1437751Y1901290D02*
X1436420Y1901302D01*
G01X1441235Y1898105D02*
X1438785Y1898127D01*
G01X1437751Y1898141D02*
X1436420Y1898153D01*
G01X1441235Y1894955D02*
X1438785Y1894977D01*
G01X1437751Y1894991D02*
X1436420Y1895003D01*
G01X1439047Y1939071D02*
X1438785D01*
G01X1441235Y1939050D02*
X1441007D01*
G01X1441235Y1936852D02*
X1441007D01*
G01X1439047Y1936830D02*
X1438785D01*
G01X1439047Y1935922D02*
X1438785D01*
G01X1441235Y1935900D02*
X1441007D01*
G01X1449937Y1932439D02*
X1430449D01*
G01Y1924565D02*
X1449937D01*
G01X1441235Y1921104D02*
X1441007D01*
G01X1439047Y1921082D02*
X1438785D01*
G01X1439047Y1920174D02*
X1438785D01*
G01X1441235Y1920152D02*
X1441007D01*
G01X1441235Y1917954D02*
X1441007D01*
G01X1439047Y1917932D02*
X1438785D01*
G01X1439047Y1917024D02*
X1438785D01*
G01X1441235Y1917003D02*
X1441007D01*
G01X1441235Y1914804D02*
X1441007D01*
G01X1439047Y1914783D02*
X1438785D01*
G01X1439047Y1913875D02*
X1438785D01*
G01X1441235Y1913853D02*
X1441007D01*
G01X1441235Y1911655D02*
X1441007D01*
G01X1439047Y1911633D02*
X1438785D01*
G01X1439047Y1910725D02*
X1438785D01*
G01X1441235Y1910703D02*
X1441007D01*
G01X1441235Y1908505D02*
X1441007D01*
G01X1439047Y1908484D02*
X1438785D01*
G01X1439047Y1907575D02*
X1438785D01*
G01X1441235Y1907554D02*
X1441007D01*
G01X1441235Y1905355D02*
X1441007D01*
G01X1439047Y1905334D02*
X1438785D01*
G01X1439047Y1904426D02*
X1438785D01*
G01X1441235Y1904404D02*
X1441007D01*
G01Y1902206D02*
X1441235D01*
G01X1439047Y1902184D02*
X1438785D01*
G01X1439047Y1901276D02*
X1438785D01*
G01X1441235Y1901255D02*
X1441007D01*
G01X1441235Y1899056D02*
X1441007D01*
G01X1439047Y1899035D02*
X1438785D01*
G01X1439047Y1898127D02*
X1438785D01*
G01X1441235Y1898105D02*
X1441007D01*
G01X1441235Y1895907D02*
X1441007D01*
G01X1439047Y1895885D02*
X1438785D01*
G01X1439047Y1894977D02*
X1438785D01*
G01X1441235Y1894955D02*
X1441007D01*
G01X1441235Y1892757D02*
X1441007D01*
G01X1439047Y1892735D02*
X1438785D01*
G01X1439047Y1891827D02*
X1438785D01*
G01X1441235Y1891806D02*
X1441007D01*
G01X1440094Y1936842D02*
X1438785Y1936830D01*
G01X1441235Y1936852D02*
X1440094Y1936842D01*
G01Y1921094D02*
X1438785Y1921082D01*
G01X1441235Y1921104D02*
X1440094Y1921094D01*
G01Y1917944D02*
X1438785Y1917932D01*
G01X1441235Y1917954D02*
X1440094Y1917944D01*
G01Y1914794D02*
X1438785Y1914783D01*
G01X1441235Y1914804D02*
X1440094Y1914794D01*
G01Y1911645D02*
X1438785Y1911633D01*
G01X1441235Y1911655D02*
X1440094Y1911645D01*
G01Y1908495D02*
X1438785Y1908484D01*
G01X1441235Y1908505D02*
X1440094Y1908495D01*
G01Y1905345D02*
X1438785Y1905334D01*
G01X1441235Y1905355D02*
X1440094Y1905345D01*
G01Y1902196D02*
X1438785Y1902184D01*
G01X1441235Y1902206D02*
X1440094Y1902196D01*
G01Y1899046D02*
X1438785Y1899035D01*
G01X1441235Y1899056D02*
X1440094Y1899046D01*
G01Y1895897D02*
X1438785Y1895885D01*
G01X1441235Y1895907D02*
X1440094Y1895897D01*
G01Y1892747D02*
X1438785Y1892735D01*
G01X1441235Y1892757D02*
X1440094Y1892747D01*
G01Y1889597D02*
X1438785Y1889586D01*
G01X1441235Y1889607D02*
X1440094Y1889597D01*
G01Y1886448D02*
X1438785Y1886436D01*
G01X1441235Y1886458D02*
X1440094Y1886448D01*
G01X1437751Y1936816D02*
X1436420Y1936804D01*
G01X1437751Y1921068D02*
X1436420Y1921056D01*
G01X1437751Y1917918D02*
X1436420Y1917906D01*
G01X1437751Y1914768D02*
X1436420Y1914757D01*
G01X1437751Y1911619D02*
X1436420Y1911607D01*
G01X1437751Y1908469D02*
X1436420Y1908457D01*
G01X1437751Y1905320D02*
X1436420Y1905308D01*
G01X1437751Y1902170D02*
X1436420Y1902158D01*
G01X1437751Y1899020D02*
X1436420Y1899009D01*
G01X1437751Y1895871D02*
X1436420Y1895859D01*
G01X1437751Y1892721D02*
X1436420Y1892709D01*
G01X1437751Y1889572D02*
X1436420Y1889560D01*
G01X1437751Y1886422D02*
X1436420Y1886410D01*
G01X1442543Y1936868D02*
X1441007Y1936852D01*
G01X1442543Y1936868D02*
X1439047Y1936830D01*
G01X1441235Y1936852D02*
X1442772Y1936868D01*
G01X1442543Y1921120D02*
X1441007Y1921104D01*
G01X1442543Y1921120D02*
X1439047Y1921082D01*
G01X1441235Y1921104D02*
X1442772Y1921120D01*
G01X1442543Y1917970D02*
X1441007Y1917954D01*
G01X1442543Y1917970D02*
X1439047Y1917932D01*
G01X1441235Y1917954D02*
X1442772Y1917970D01*
G01X1442543Y1914821D02*
X1441007Y1914804D01*
G01X1442543Y1914821D02*
X1439047Y1914783D01*
G01X1441235Y1914804D02*
X1442772Y1914821D01*
G01X1442543Y1911671D02*
X1441007Y1911655D01*
G01X1442543Y1911671D02*
X1439047Y1911633D01*
G01X1441235Y1911655D02*
X1442772Y1911671D01*
G01X1442543Y1908522D02*
X1441007Y1908505D01*
G01X1442543Y1908522D02*
X1439047Y1908484D01*
G01X1441235Y1908505D02*
X1442772Y1908522D01*
G01X1442543Y1905372D02*
X1441007Y1905355D01*
G01X1442543Y1905372D02*
X1439047Y1905334D01*
G01X1441235Y1905355D02*
X1442772Y1905372D01*
G01X1442543Y1902222D02*
X1441007Y1902206D01*
G01X1442543Y1902222D02*
X1439047Y1902184D01*
G01X1441235Y1902206D02*
X1442772Y1902222D01*
G01X1442543Y1899073D02*
X1441007Y1899056D01*
G01X1442543Y1899073D02*
X1439047Y1899035D01*
G01X1441235Y1899056D02*
X1442772Y1899073D01*
G01X1442543Y1895923D02*
X1441007Y1895907D01*
G01X1442543Y1895923D02*
X1439047Y1895885D01*
G01X1441235Y1895907D02*
X1442772Y1895923D01*
G01X1442543Y1892774D02*
X1441007Y1892757D01*
G01X1442543Y1892774D02*
X1439047Y1892736D01*
G01X1441235Y1892757D02*
X1442772Y1892774D01*
G01X1442543Y1889624D02*
X1441007Y1889607D01*
G01X1442543Y1889624D02*
X1439047Y1889586D01*
G01X1441235Y1889607D02*
X1442772Y1889624D01*
G01X1442543Y1886474D02*
X1441007Y1886458D01*
G01X1442543Y1886474D02*
X1439047Y1886436D01*
G01X1441235Y1886458D02*
X1442772Y1886474D01*
G01X1439047Y1936830D02*
X1440094Y1936842D01*
G01X1438785Y1936830D02*
X1436420Y1936804D01*
G01X1437751Y1936816D02*
X1439047Y1936830D01*
G01Y1921082D02*
X1440094Y1921094D01*
G01X1438785Y1921082D02*
X1436420Y1921056D01*
G01X1437751Y1921068D02*
X1439047Y1921082D01*
G01Y1917932D02*
X1440094Y1917944D01*
G01X1438785Y1917932D02*
X1436420Y1917906D01*
G01X1437751Y1917918D02*
X1439047Y1917932D01*
G01Y1914783D02*
X1440094Y1914794D01*
G01X1438785Y1914783D02*
X1436420Y1914757D01*
G01X1437751Y1914768D02*
X1439047Y1914783D01*
G01Y1911633D02*
X1440094Y1911645D01*
G01X1438785Y1911633D02*
X1436420Y1911607D01*
G01X1437751Y1911619D02*
X1439047Y1911633D01*
G01Y1908484D02*
X1440094Y1908495D01*
G01X1438785Y1908484D02*
X1436420Y1908457D01*
G01X1437751Y1908469D02*
X1439047Y1908484D01*
G01Y1905334D02*
X1440094Y1905345D01*
G01X1438785Y1905334D02*
X1436420Y1905308D01*
G01X1437751Y1905320D02*
X1439047Y1905334D01*
G01Y1902184D02*
X1440094Y1902196D01*
G01X1438785Y1902184D02*
X1436420Y1902158D01*
G01X1437751Y1902170D02*
X1439047Y1902184D01*
G01Y1899035D02*
X1440094Y1899046D01*
G01X1438785Y1899035D02*
X1436420Y1899009D01*
G01X1437751Y1899020D02*
X1439047Y1899035D01*
G01Y1895885D02*
X1440094Y1895897D01*
G01X1438785Y1895885D02*
X1436420Y1895859D01*
G01X1437751Y1895871D02*
X1439047Y1895885D01*
G01Y1892735D02*
X1440094Y1892747D01*
G01X1438785Y1892735D02*
X1436420Y1892709D01*
G01X1437751Y1892721D02*
X1439047Y1892735D01*
G01Y1889586D02*
X1440094Y1889597D01*
G01X1438785Y1889586D02*
X1436420Y1889560D01*
G01X1437751Y1889572D02*
X1439047Y1889586D01*
G01Y1886436D02*
X1440094Y1886448D01*
G01X1438785Y1886436D02*
X1436420Y1886410D01*
G01X1437751Y1886422D02*
X1439047Y1886436D01*
G01Y1894977D02*
X1442543Y1894939D01*
G01X1437751Y1894991D02*
X1441007Y1894955D01*
G01X1439047Y1891827D02*
X1442543Y1891789D01*
G01X1437751Y1891842D02*
X1441007Y1891806D01*
G01X1439047Y1888678D02*
X1442543Y1888640D01*
G01X1437751Y1888692D02*
X1441007Y1888656D01*
G01X1439047Y1885528D02*
X1442543Y1885490D01*
G01X1437751Y1885542D02*
X1441007Y1885507D01*
G01X1439047Y1882378D02*
X1442543Y1882340D01*
G01X1437751Y1882393D02*
X1441007Y1882357D01*
G01X1439047Y1879229D02*
X1442543Y1879191D01*
G01X1437751Y1879243D02*
X1441007Y1879207D01*
G01X1439047Y1876079D02*
X1442543Y1876041D01*
G01X1437751Y1876094D02*
X1441007Y1876058D01*
G01X1439047Y1872930D02*
X1442543Y1872892D01*
G01X1437751Y1872944D02*
X1441007Y1872908D01*
G01X1438785Y1894977D02*
X1436420Y1895003D01*
G01X1438785Y1891827D02*
X1436420Y1891853D01*
G01X1438785Y1888678D02*
X1436420Y1888704D01*
G01X1438785Y1885528D02*
X1436420Y1885554D01*
G01X1438785Y1882378D02*
X1436420Y1882405D01*
G01X1438785Y1879229D02*
X1436420Y1879255D01*
G01X1438785Y1876079D02*
X1436420Y1876105D01*
G01X1438785Y1872930D02*
X1436420Y1872956D01*
G01X1441235Y1894955D02*
X1442772Y1894939D01*
G01X1441235Y1891806D02*
X1442772Y1891789D01*
G01X1441235Y1888656D02*
X1442772Y1888640D01*
G01X1441235Y1885507D02*
X1442772Y1885490D01*
G01X1441235Y1882357D02*
X1442772Y1882340D01*
G01X1441235Y1879207D02*
X1442772Y1879191D01*
G01X1441235Y1876058D02*
X1442772Y1876041D01*
G01X1441235Y1872908D02*
X1442772Y1872892D01*
G01X1441235Y1891806D02*
X1438785Y1891827D01*
G01X1437751Y1891842D02*
X1436420Y1891853D01*
G01X1441235Y1888656D02*
X1438785Y1888678D01*
G01X1437751Y1888692D02*
X1436420Y1888704D01*
G01X1441235Y1885507D02*
X1438785Y1885528D01*
G01X1437751Y1885542D02*
X1436420Y1885554D01*
G01X1441235Y1882357D02*
X1438785Y1882378D01*
G01X1437751Y1882393D02*
X1436420Y1882405D01*
G01X1441235Y1879207D02*
X1438785Y1879229D01*
G01X1437751Y1879243D02*
X1436420Y1879255D01*
G01X1441235Y1876058D02*
X1438785Y1876079D01*
G01X1437751Y1876094D02*
X1436420Y1876105D01*
G01X1441235Y1872908D02*
X1438785Y1872930D01*
G01X1437751Y1872944D02*
X1436420Y1872956D01*
G01X1441235Y1889607D02*
X1441007D01*
G01X1439047Y1889586D02*
X1438785D01*
G01X1439047Y1888678D02*
X1438785D01*
G01X1441235Y1888656D02*
X1441007D01*
G01X1441235Y1886458D02*
X1441007D01*
G01X1439047Y1886436D02*
X1438785D01*
G01X1439047Y1885528D02*
X1438785D01*
G01X1441235Y1885507D02*
X1441007D01*
G01X1441235Y1883308D02*
X1441007D01*
G01X1439047Y1883287D02*
X1438785D01*
G01X1439047Y1882378D02*
X1438785D01*
G01X1441235Y1882357D02*
X1441007D01*
G01X1441235Y1880159D02*
X1441007D01*
G01X1439047Y1880137D02*
X1438785D01*
G01X1439047Y1879229D02*
X1438785D01*
G01X1441235Y1879207D02*
X1441007D01*
G01X1441235Y1877009D02*
X1441007D01*
G01X1439047Y1876987D02*
X1438785D01*
G01X1439047Y1876079D02*
X1438785D01*
G01X1441235Y1876058D02*
X1441007D01*
G01X1441235Y1873859D02*
X1441007D01*
G01X1439047Y1873838D02*
X1438785D01*
G01X1439047Y1872930D02*
X1438785D01*
G01X1441235Y1872908D02*
X1441007D01*
G01X1441235Y1870710D02*
X1441007D01*
G01X1439047Y1870688D02*
X1438785D01*
G01X1440094Y1883298D02*
X1438785Y1883287D01*
G01X1441235Y1883308D02*
X1440094Y1883298D01*
G01Y1880149D02*
X1438785Y1880137D01*
G01X1441235Y1880159D02*
X1440094Y1880149D01*
G01Y1876999D02*
X1438785Y1876987D01*
G01X1441235Y1877009D02*
X1440094Y1876999D01*
G01Y1873849D02*
X1438785Y1873838D01*
G01X1441235Y1873859D02*
X1440094Y1873849D01*
G01Y1870700D02*
X1438785Y1870688D01*
G01X1441235Y1870710D02*
X1440094Y1870700D01*
G01X1437751Y1883272D02*
X1436420Y1883261D01*
G01X1437751Y1880123D02*
X1436420Y1880111D01*
G01X1437751Y1876973D02*
X1436420Y1876961D01*
G01X1437751Y1873824D02*
X1436420Y1873812D01*
G01X1437751Y1870674D02*
X1436420Y1870662D01*
G01X1442543Y1883325D02*
X1441007Y1883308D01*
G01X1442543Y1883325D02*
X1439047Y1883287D01*
G01X1441235Y1883308D02*
X1442772Y1883325D01*
G01X1442543Y1880175D02*
X1441007Y1880159D01*
G01X1442543Y1880175D02*
X1439047Y1880137D01*
G01X1441235Y1880159D02*
X1442772Y1880175D01*
G01X1442543Y1877025D02*
X1441007Y1877009D01*
G01X1442543Y1877025D02*
X1439047Y1876988D01*
G01X1441235Y1877009D02*
X1442772Y1877025D01*
G01X1442543Y1873876D02*
X1441007Y1873859D01*
G01X1442543Y1873876D02*
X1439047Y1873838D01*
G01X1441235Y1873859D02*
X1442772Y1873876D01*
G01X1442543Y1870726D02*
X1441007Y1870710D01*
G01X1442543Y1870726D02*
X1439047Y1870688D01*
G01X1441235Y1870710D02*
X1442772Y1870726D01*
G01X1439047Y1883287D02*
X1440094Y1883298D01*
G01X1438785Y1883287D02*
X1436420Y1883261D01*
G01X1437751Y1883272D02*
X1439047Y1883287D01*
G01Y1880137D02*
X1440094Y1880149D01*
G01X1438785Y1880137D02*
X1436420Y1880111D01*
G01X1437751Y1880123D02*
X1439047Y1880137D01*
G01Y1876987D02*
X1440094Y1876999D01*
G01X1438785Y1876987D02*
X1436420Y1876961D01*
G01X1437751Y1876973D02*
X1439047Y1876987D01*
G01Y1873838D02*
X1440094Y1873849D01*
G01X1438785Y1873838D02*
X1436420Y1873812D01*
G01X1437751Y1873824D02*
X1439047Y1873838D01*
G01Y1870688D02*
X1440094Y1870700D01*
G01X1438785Y1870688D02*
X1436420Y1870662D01*
G01X1437751Y1870674D02*
X1439047Y1870688D01*
G01X1426512Y1926533D02*
X1430449Y1924565D01*
G01X1441235Y1873859D02*
Y1872908D01*
G01Y1880159D02*
Y1879207D01*
G01Y1877009D02*
Y1876058D01*
G01Y1883308D02*
Y1882357D01*
G01Y1889607D02*
Y1888656D01*
G01Y1886458D02*
Y1885507D01*
G01Y1892757D02*
Y1891806D01*
G01Y1899056D02*
Y1898105D01*
G01Y1895907D02*
Y1894955D01*
G01Y1902206D02*
Y1901255D01*
G01Y1908505D02*
Y1907554D01*
G01Y1905355D02*
Y1904404D01*
G01Y1911655D02*
Y1910703D01*
G01Y1917954D02*
Y1917003D01*
G01Y1914804D02*
Y1913853D01*
G01Y1921103D02*
Y1920152D01*
G01Y1940001D02*
Y1939050D01*
G01Y1936851D02*
Y1935900D01*
G01X1441007Y1873859D02*
Y1872908D01*
G01Y1880159D02*
Y1879207D01*
G01Y1877009D02*
Y1876058D01*
G01Y1883308D02*
Y1882357D01*
G01Y1889607D02*
Y1888656D01*
G01Y1886458D02*
Y1885507D01*
G01Y1892757D02*
Y1891806D01*
G01Y1899056D02*
Y1898105D01*
G01Y1895907D02*
Y1894955D01*
G01Y1902206D02*
Y1901255D01*
G01Y1908505D02*
Y1907554D01*
G01Y1905355D02*
Y1904404D01*
G01Y1911655D02*
Y1910703D01*
G01Y1917954D02*
Y1917003D01*
G01Y1914804D02*
Y1913853D01*
G01Y1921104D02*
Y1920152D01*
G01Y1940001D02*
Y1939050D01*
G01Y1936852D02*
Y1935900D01*
G01X1439047Y1873838D02*
Y1872930D01*
G01Y1880137D02*
Y1879229D01*
G01Y1876988D02*
Y1876079D01*
G01Y1883287D02*
Y1882378D01*
G01Y1889586D02*
Y1888678D01*
G01Y1886436D02*
Y1885528D01*
G01Y1892736D02*
Y1891827D01*
G01Y1899035D02*
Y1898126D01*
G01Y1895885D02*
Y1894977D01*
G01Y1902184D02*
Y1901276D01*
G01Y1908484D02*
Y1907575D01*
G01Y1905334D02*
Y1904426D01*
G01Y1911633D02*
Y1910725D01*
G01Y1917932D02*
Y1917024D01*
G01Y1914783D02*
Y1913874D01*
G01Y1921082D02*
Y1920174D01*
G01Y1939980D02*
Y1939071D01*
G01Y1936830D02*
Y1935922D01*
G01X1438785Y1873838D02*
Y1872930D01*
G01Y1880137D02*
Y1879229D01*
G01Y1876988D02*
Y1876079D01*
G01Y1883287D02*
Y1882378D01*
G01Y1889586D02*
Y1888678D01*
G01Y1886436D02*
Y1885528D01*
G01Y1892736D02*
Y1891827D01*
G01Y1899035D02*
Y1898127D01*
G01Y1895885D02*
Y1894977D01*
G01Y1902184D02*
Y1901276D01*
G01Y1908484D02*
Y1907575D01*
G01Y1905334D02*
Y1904426D01*
G01Y1911633D02*
Y1910725D01*
G01Y1917932D02*
Y1917024D01*
G01Y1914783D02*
Y1913875D01*
G01Y1921082D02*
Y1920174D01*
G01Y1939980D02*
Y1939071D01*
G01Y1936830D02*
Y1935922D01*
G01X1437751Y1873818D02*
Y1872950D01*
G01Y1880117D02*
Y1879249D01*
G01Y1876967D02*
Y1876099D01*
G01Y1883267D02*
Y1882399D01*
G01Y1889566D02*
Y1888698D01*
G01Y1886416D02*
Y1885548D01*
G01Y1892715D02*
Y1891847D01*
G01Y1899015D02*
Y1898147D01*
G01Y1895865D02*
Y1894997D01*
G01Y1902164D02*
Y1901296D01*
G01Y1908463D02*
Y1907596D01*
G01Y1905314D02*
Y1904446D01*
G01Y1911613D02*
Y1910745D01*
G01Y1917912D02*
Y1917044D01*
G01Y1914763D02*
Y1913895D01*
G01Y1921062D02*
Y1920194D01*
G01Y1939959D02*
Y1939092D01*
G01Y1936810D02*
Y1935942D01*
G01X1436420Y1873812D02*
Y1872956D01*
G01Y1880111D02*
Y1879255D01*
G01Y1876961D02*
Y1876105D01*
G01Y1883261D02*
Y1882405D01*
G01Y1889560D02*
Y1888704D01*
G01Y1886410D02*
Y1885554D01*
G01Y1892709D02*
Y1891853D01*
G01Y1899009D02*
Y1898153D01*
G01Y1895859D02*
Y1895003D01*
G01Y1902158D02*
Y1901302D01*
G01Y1908457D02*
Y1907601D01*
G01Y1905308D02*
Y1904452D01*
G01Y1911607D02*
Y1910751D01*
G01Y1917906D02*
Y1917050D01*
G01Y1914757D02*
Y1913901D01*
G01Y1921056D02*
Y1920200D01*
G01Y1939954D02*
Y1939097D01*
G01Y1936804D02*
Y1935948D01*
G01X1430449Y2111573D02*
Y1932439D01*
G01D02*
X1426512Y1930470D01*
G01X1470921Y1869900D02*
X1469507D01*
G01X1442772Y1869742D02*
X1442543D01*
G01X1469631Y1869644D02*
X1457535D01*
G01X1444212Y1869447D02*
X1443073D01*
G01X1457732Y1869053D02*
X1457220D01*
G01X1457732Y1868266D02*
X1457220D01*
G01X1444212Y1867872D02*
X1443073D01*
G01X1469631Y1867675D02*
X1457535D01*
G01X1442772Y1867577D02*
X1442543D01*
G01X1470921Y1867419D02*
X1469507D01*
G01X1470921Y1866750D02*
X1469507D01*
G01X1442772Y1866592D02*
X1442543D01*
G01X1469631Y1866494D02*
X1457535D01*
G01X1442684Y1869654D02*
X1443073Y1869447D01*
G01X1442772Y1869742D02*
X1443243Y1869447D01*
G01X1442543Y1869742D02*
X1442684Y1869654D01*
G01X1469278Y1867675D02*
X1469507Y1867419D01*
G01X1469636Y1867689D02*
X1469855Y1867419D01*
G01X1470921Y1870569D02*
Y1869900D01*
G01Y1867419D02*
Y1866750D01*
G01X1470574Y1870569D02*
Y1869900D01*
G01Y1867419D02*
Y1866750D01*
G01X1469631Y1870825D02*
Y1869644D01*
G01Y1867675D02*
Y1866494D01*
G01X1469278Y1870825D02*
Y1869644D01*
G01Y1867675D02*
Y1866494D01*
G01X1467296Y1870825D02*
Y1869644D01*
G01Y1867675D02*
Y1866494D01*
G01X1467186Y1870825D02*
Y1869644D01*
G01Y1867675D02*
Y1866494D01*
G01X1458405Y1870825D02*
Y1869644D01*
G01Y1867675D02*
Y1866494D01*
G01X1458295Y1870825D02*
Y1869644D01*
G01Y1867675D02*
Y1866494D01*
G01X1457929Y1870825D02*
Y1869644D01*
G01Y1867675D02*
Y1866494D01*
G01X1457732Y1869644D02*
Y1869053D01*
G01Y1868266D02*
Y1867675D01*
G01X1457535Y1869644D02*
Y1869053D01*
G01Y1868266D02*
Y1867675D01*
G01X1444212Y1871022D02*
Y1869447D01*
G01X1442684Y1870814D02*
Y1869654D01*
G01Y1867664D02*
Y1866505D01*
G01X1443073Y1867872D02*
X1442684Y1867664D01*
G01X1443243Y1867872D02*
X1442772Y1867577D01*
G01X1442684Y1867664D02*
X1442543Y1867577D01*
G01X1469507Y1869900D02*
X1469278Y1869644D01*
G01X1469855Y1869900D02*
X1469636Y1869629D01*
G01X1474543Y1924171D02*
G03Y1932833I0J4331D01*
G01X1470921Y1939191D02*
X1469507D01*
G01X1442772Y1939033D02*
X1442543D01*
G01X1469631Y1938935D02*
X1457535D01*
G01X1444212Y1938738D02*
X1443073D01*
G01X1457732Y1938344D02*
X1457220D01*
G01X1457732Y1937557D02*
X1457220D01*
G01X1444212Y1937163D02*
X1443073D01*
G01X1469631Y1936966D02*
X1457535D01*
G01X1442772Y1936868D02*
X1442543D01*
G01X1470921Y1936711D02*
X1469507D01*
G01X1470921Y1936041D02*
X1469507D01*
G01X1442772Y1935884D02*
X1442543D01*
G01X1469631Y1935785D02*
X1457535D01*
G01X1444212Y1935588D02*
X1443073D01*
G01X1457732Y1935195D02*
X1457220D01*
G01X1474543Y1932833D02*
X1459189D01*
G01X1474937Y1932439D02*
X1457220D01*
G01X1474937Y1924565D02*
X1457220D01*
G01X1459189Y1924171D02*
X1474543D01*
G01X1457732Y1921809D02*
X1457220D01*
G01X1444212Y1921415D02*
X1443073D01*
G01X1469631Y1921218D02*
X1457535D01*
G01X1442772Y1921120D02*
X1442543D01*
G01X1470921Y1920963D02*
X1469507D01*
G01X1470921Y1920293D02*
X1469507D01*
G01X1442772Y1920136D02*
X1442543D01*
G01X1469631Y1920037D02*
X1457535D01*
G01X1444212Y1919840D02*
X1443073D01*
G01X1457732Y1919447D02*
X1457220D01*
G01X1457732Y1918659D02*
X1457220D01*
G01X1444212Y1918266D02*
X1443073D01*
G01X1469631Y1918069D02*
X1457535D01*
G01X1442772Y1917970D02*
X1442543D01*
G01X1470921Y1917813D02*
X1469507D01*
G01X1470921Y1917144D02*
X1469507D01*
G01X1442772Y1916986D02*
X1442543D01*
G01X1469631Y1916888D02*
X1457535D01*
G01X1444212Y1916691D02*
X1443073D01*
G01X1457732Y1916297D02*
X1457220D01*
G01X1457732Y1915510D02*
X1457220D01*
G01X1444212Y1915116D02*
X1443073D01*
G01X1469631Y1914919D02*
X1457535D01*
G01X1442772Y1914821D02*
X1442543D01*
G01X1470921Y1914663D02*
X1469507D01*
G01X1470921Y1913994D02*
X1469507D01*
G01X1442772Y1913837D02*
X1442543D01*
G01X1469631Y1913738D02*
X1457535D01*
G01X1444212Y1913541D02*
X1443073D01*
G01X1457732Y1913148D02*
X1457220D01*
G01X1457732Y1912360D02*
X1457220D01*
G01X1444212Y1911966D02*
X1443073D01*
G01X1469631Y1911770D02*
X1457535D01*
G01X1442772Y1911671D02*
X1442543D01*
G01X1470921Y1911514D02*
X1469507D01*
G01X1470921Y1910844D02*
X1469507D01*
G01X1442772Y1910687D02*
X1442543D01*
G01X1469631Y1910588D02*
X1457535D01*
G01X1444212Y1910392D02*
X1443073D01*
G01X1457732Y1909998D02*
X1457220D01*
G01X1457732Y1909211D02*
X1457220D01*
G01X1444212Y1908817D02*
X1443073D01*
G01X1469631Y1908620D02*
X1457535D01*
G01X1442772Y1908522D02*
X1442543D01*
G01X1470921Y1908364D02*
X1469507D01*
G01X1470921Y1907695D02*
X1469507D01*
G01X1442772Y1907537D02*
X1442543D01*
G01X1469631Y1907439D02*
X1457535D01*
G01X1444212Y1907242D02*
X1443073D01*
G01X1457732Y1906848D02*
X1457220D01*
G01X1457732Y1906061D02*
X1457220D01*
G01X1444212Y1905667D02*
X1443073D01*
G01X1469631Y1905470D02*
X1457535D01*
G01X1442772Y1905372D02*
X1442543D01*
G01X1470921Y1905214D02*
X1469507D01*
G01X1470921Y1904545D02*
X1469507D01*
G01X1442772Y1904388D02*
X1442543D01*
G01X1469631Y1904289D02*
X1457535D01*
G01X1444212Y1904092D02*
X1443073D01*
G01X1457732Y1903699D02*
X1457220D01*
G01X1457732Y1902911D02*
X1457220D01*
G01X1444212Y1902518D02*
X1443073D01*
G01X1469631Y1902321D02*
X1457535D01*
G01X1442772Y1902222D02*
X1442543D01*
G01X1470921Y1902065D02*
X1469507D01*
G01X1470921Y1901396D02*
X1469507D01*
G01X1442772Y1901238D02*
X1442543D01*
G01X1469631Y1901140D02*
X1457535D01*
G01X1444212Y1900943D02*
X1443073D01*
G01X1457732Y1900549D02*
X1457220D01*
G01X1457732Y1899762D02*
X1457220D01*
G01X1444212Y1899368D02*
X1443073D01*
G01X1469631Y1899171D02*
X1457535D01*
G01X1442772Y1899073D02*
X1442543D01*
G01X1470921Y1898915D02*
X1469507D01*
G01X1470921Y1898246D02*
X1469507D01*
G01X1442772Y1898088D02*
X1442543D01*
G01X1469631Y1897990D02*
X1457535D01*
G01X1444212Y1897793D02*
X1443073D01*
G01X1457732Y1897400D02*
X1457220D01*
G01X1457732Y1896612D02*
X1457220D01*
G01X1444212Y1896218D02*
X1443073D01*
G01X1469631Y1896022D02*
X1457535D01*
G01X1442772Y1895923D02*
X1442543D01*
G01X1470921Y1895766D02*
X1469507D01*
G01X1470921Y1895096D02*
X1469507D01*
G01X1442772Y1894939D02*
X1442543D01*
G01X1469631Y1894840D02*
X1457535D01*
G01X1444212Y1894644D02*
X1443073D01*
G01X1457732Y1894250D02*
X1457220D01*
G01X1457732Y1893463D02*
X1457220D01*
G01X1444212Y1893069D02*
X1443073D01*
G01X1469631Y1892872D02*
X1457535D01*
G01X1442772Y1892774D02*
X1442543D01*
G01X1470921Y1892616D02*
X1469507D01*
G01X1470921Y1891947D02*
X1469507D01*
G01X1442772Y1891789D02*
X1442543D01*
G01X1469631Y1891691D02*
X1457535D01*
G01X1444212Y1891494D02*
X1443073D01*
G01X1457732Y1891100D02*
X1457220D01*
G01X1457732Y1890313D02*
X1457220D01*
G01X1444212Y1889919D02*
X1443073D01*
G01X1469631Y1889722D02*
X1457535D01*
G01X1442772Y1889624D02*
X1442543D01*
G01X1470921Y1889466D02*
X1469507D01*
G01X1470921Y1888797D02*
X1469507D01*
G01X1442772Y1888640D02*
X1442543D01*
G01X1469631Y1888541D02*
X1457535D01*
G01X1444212Y1888344D02*
X1443073D01*
G01X1457732Y1887951D02*
X1457220D01*
G01X1457732Y1887163D02*
X1457220D01*
G01X1444212Y1886770D02*
X1443073D01*
G01X1469631Y1886573D02*
X1457535D01*
G01X1442772Y1886474D02*
X1442543D01*
G01X1470921Y1886317D02*
X1469507D01*
G01X1470921Y1885648D02*
X1469507D01*
G01X1442772Y1885490D02*
X1442543D01*
G01X1469631Y1885392D02*
X1457535D01*
G01X1444212Y1885195D02*
X1443073D01*
G01X1457732Y1884801D02*
X1457220D01*
G01X1457732Y1884014D02*
X1457220D01*
G01X1444212Y1883620D02*
X1443073D01*
G01X1469631Y1883423D02*
X1457535D01*
G01X1442772Y1883325D02*
X1442543D01*
G01X1470921Y1883167D02*
X1469507D01*
G01X1470921Y1882498D02*
X1469507D01*
G01X1442772Y1882340D02*
X1442543D01*
G01X1469631Y1882242D02*
X1457535D01*
G01X1444212Y1882045D02*
X1443073D01*
G01X1457732Y1881651D02*
X1457220D01*
G01X1457732Y1880864D02*
X1457220D01*
G01X1444212Y1880470D02*
X1443073D01*
G01X1469631Y1880274D02*
X1457535D01*
G01X1442772Y1880175D02*
X1442543D01*
G01X1470921Y1880018D02*
X1469507D01*
G01X1470921Y1879348D02*
X1469507D01*
G01X1442772Y1879191D02*
X1442543D01*
G01X1469631Y1879092D02*
X1457535D01*
G01X1444212Y1878896D02*
X1443073D01*
G01X1457732Y1878502D02*
X1457220D01*
G01X1457732Y1877714D02*
X1457220D01*
G01X1444212Y1877321D02*
X1443073D01*
G01X1469631Y1877124D02*
X1457535D01*
G01X1442772Y1877025D02*
X1442543D01*
G01X1470921Y1876868D02*
X1469507D01*
G01X1470921Y1876199D02*
X1469507D01*
G01X1442772Y1876041D02*
X1442543D01*
G01X1469631Y1875943D02*
X1457535D01*
G01X1444212Y1875746D02*
X1443073D01*
G01X1457732Y1875352D02*
X1457220D01*
G01X1457732Y1874565D02*
X1457220D01*
G01X1444212Y1874171D02*
X1443073D01*
G01X1469631Y1873974D02*
X1457535D01*
G01X1442772Y1873876D02*
X1442543D01*
G01X1470921Y1873718D02*
X1469507D01*
G01X1470921Y1873049D02*
X1469507D01*
G01X1442772Y1872892D02*
X1442543D01*
G01X1469631Y1872793D02*
X1457535D01*
G01X1444212Y1872596D02*
X1443073D01*
G01X1457732Y1872203D02*
X1457220D01*
G01X1457732Y1871415D02*
X1457220D01*
G01X1444212Y1871022D02*
X1443073D01*
G01X1469631Y1870825D02*
X1457535D01*
G01X1442772Y1870726D02*
X1442543D01*
G01X1470921Y1870569D02*
X1469507D01*
G01X1442684Y1938946D02*
X1443073Y1938738D01*
G01X1442684Y1935796D02*
X1443073Y1935588D01*
G01X1442684Y1920048D02*
X1443073Y1919840D01*
G01X1442684Y1916898D02*
X1443073Y1916691D01*
G01X1442684Y1913749D02*
X1443073Y1913541D01*
G01X1442684Y1910599D02*
X1443073Y1910392D01*
G01X1442684Y1907449D02*
X1443073Y1907242D01*
G01X1442684Y1904300D02*
X1443073Y1904092D01*
G01X1442772Y1939033D02*
X1443243Y1938738D01*
G01X1442543Y1939033D02*
X1442684Y1938946D01*
G01X1442772Y1935884D02*
X1443243Y1935588D01*
G01X1442543Y1935884D02*
X1442684Y1935796D01*
G01X1442772Y1920136D02*
X1443243Y1919840D01*
G01X1442543Y1920136D02*
X1442684Y1920048D01*
G01X1442772Y1916986D02*
X1443243Y1916691D01*
G01X1442543Y1916986D02*
X1442684Y1916898D01*
G01X1442772Y1913837D02*
X1443243Y1913541D01*
G01X1442543Y1913837D02*
X1442684Y1913749D01*
G01X1442772Y1910687D02*
X1443243Y1910392D01*
G01X1442543Y1910687D02*
X1442684Y1910599D01*
G01X1442772Y1907537D02*
X1443243Y1907242D01*
G01X1442543Y1907537D02*
X1442684Y1907449D01*
G01X1442772Y1904388D02*
X1443243Y1904092D01*
G01X1442543Y1904388D02*
X1442684Y1904300D01*
G01X1442772Y1901238D02*
X1443243Y1900943D01*
G01X1442543Y1901238D02*
X1442684Y1901150D01*
G01X1442772Y1898088D02*
X1443243Y1897793D01*
G01X1442543Y1898088D02*
X1442684Y1898001D01*
G01X1442772Y1894939D02*
X1443243Y1894644D01*
G01X1442543Y1894939D02*
X1442684Y1894851D01*
G01X1442772Y1891789D02*
X1443243Y1891494D01*
G01X1442543Y1891789D02*
X1442684Y1891701D01*
G01X1442772Y1888640D02*
X1443243Y1888344D01*
G01X1442543Y1888640D02*
X1442684Y1888552D01*
G01X1442772Y1885490D02*
X1443243Y1885195D01*
G01X1442543Y1885490D02*
X1442684Y1885402D01*
G01X1442772Y1882340D02*
X1443243Y1882045D01*
G01X1442543Y1882340D02*
X1442684Y1882253D01*
G01X1442772Y1879191D02*
X1443243Y1878896D01*
G01X1442543Y1879191D02*
X1442684Y1879103D01*
G01Y1901150D02*
X1443073Y1900943D01*
G01X1442684Y1898001D02*
X1443073Y1897793D01*
G01X1442684Y1894851D02*
X1443073Y1894644D01*
G01X1442684Y1891701D02*
X1443073Y1891494D01*
G01X1442684Y1888552D02*
X1443073Y1888344D01*
G01X1442684Y1885402D02*
X1443073Y1885195D01*
G01X1442684Y1882253D02*
X1443073Y1882045D01*
G01X1442684Y1879103D02*
X1443073Y1878896D01*
G01X1442684Y1875953D02*
X1443073Y1875746D01*
G01X1442684Y1872804D02*
X1443073Y1872596D01*
G01X1442772Y1876041D02*
X1443243Y1875746D01*
G01X1442543Y1876041D02*
X1442684Y1875953D01*
G01X1442772Y1872892D02*
X1443243Y1872596D01*
G01X1442543Y1872892D02*
X1442684Y1872804D01*
G01X1474937Y1932439D02*
X1476905Y1930470D01*
G01X1459189Y1932833D02*
X1457220Y1934801D01*
G01X1493047Y1925483D02*
X1497767Y1920842D01*
G01X1493047Y1924380D02*
X1497772Y1919734D01*
G01X1469636Y1936981D02*
X1469855Y1936711D01*
G01X1469636Y1921233D02*
X1469855Y1920963D01*
G01X1469636Y1918083D02*
X1469855Y1917813D01*
G01X1469636Y1914933D02*
X1469855Y1914663D01*
G01X1469636Y1911784D02*
X1469855Y1911514D01*
G01X1469636Y1908634D02*
X1469855Y1908364D01*
G01X1469636Y1905485D02*
X1469855Y1905214D01*
G01X1469636Y1902335D02*
X1469855Y1902065D01*
G01X1469636Y1899185D02*
X1469855Y1898915D01*
G01X1469636Y1896036D02*
X1469855Y1895766D01*
G01X1469278Y1936966D02*
X1469507Y1936711D01*
G01X1469278Y1921218D02*
X1469507Y1920963D01*
G01X1469278Y1918069D02*
X1469507Y1917813D01*
G01X1469278Y1914919D02*
X1469507Y1914663D01*
G01X1469278Y1911770D02*
X1469507Y1911514D01*
G01X1469278Y1908620D02*
X1469507Y1908364D01*
G01X1469278Y1905470D02*
X1469507Y1905214D01*
G01X1469278Y1902321D02*
X1469507Y1902065D01*
G01X1469278Y1899171D02*
X1469507Y1898915D01*
G01X1469278Y1896022D02*
X1469507Y1895766D01*
G01X1469278Y1892872D02*
X1469507Y1892616D01*
G01X1469278Y1889722D02*
X1469507Y1889466D01*
G01X1469278Y1886573D02*
X1469507Y1886317D01*
G01X1469278Y1883423D02*
X1469507Y1883167D01*
G01X1469278Y1880274D02*
X1469507Y1880018D01*
G01X1469278Y1877124D02*
X1469507Y1876868D01*
G01X1469278Y1873974D02*
X1469507Y1873718D01*
G01X1469278Y1870825D02*
X1469507Y1870569D01*
G01X1469636Y1892886D02*
X1469855Y1892616D01*
G01X1469636Y1889736D02*
X1469855Y1889466D01*
G01X1469636Y1886587D02*
X1469855Y1886317D01*
G01X1469636Y1883437D02*
X1469855Y1883167D01*
G01X1469636Y1880288D02*
X1469855Y1880018D01*
G01X1469636Y1877138D02*
X1469855Y1876868D01*
G01X1469636Y1873988D02*
X1469855Y1873718D01*
G01X1469636Y1870839D02*
X1469855Y1870569D01*
G01X1493047Y1924380D02*
Y1926112D01*
G01X1476905Y1930470D02*
Y1926533D01*
G01X1470921Y1873718D02*
Y1873049D01*
G01Y1880018D02*
Y1879348D01*
G01Y1876868D02*
Y1876199D01*
G01Y1883167D02*
Y1882498D01*
G01Y1889466D02*
Y1888797D01*
G01Y1886317D02*
Y1885648D01*
G01Y1892616D02*
Y1891947D01*
G01Y1898915D02*
Y1898246D01*
G01Y1895766D02*
Y1895096D01*
G01Y1902065D02*
Y1901396D01*
G01Y1908364D02*
Y1907695D01*
G01Y1905214D02*
Y1904545D01*
G01Y1911514D02*
Y1910844D01*
G01Y1917813D02*
Y1917144D01*
G01Y1914663D02*
Y1913994D01*
G01Y1920963D02*
Y1920293D01*
G01Y1936711D02*
Y1936041D01*
G01Y1939860D02*
Y1939191D01*
G01X1470574Y1873718D02*
Y1873049D01*
G01Y1880018D02*
Y1879348D01*
G01Y1876868D02*
Y1876199D01*
G01Y1883167D02*
Y1882498D01*
G01Y1889466D02*
Y1888797D01*
G01Y1886317D02*
Y1885648D01*
G01Y1892616D02*
Y1891947D01*
G01Y1898915D02*
Y1898246D01*
G01Y1895766D02*
Y1895096D01*
G01Y1902065D02*
Y1901396D01*
G01Y1908364D02*
Y1907695D01*
G01Y1905214D02*
Y1904545D01*
G01Y1911514D02*
Y1910844D01*
G01Y1917813D02*
Y1917144D01*
G01Y1914663D02*
Y1913994D01*
G01Y1920963D02*
Y1920293D01*
G01Y1936711D02*
Y1936041D01*
G01Y1939860D02*
Y1939191D01*
G01X1469631Y1873974D02*
Y1872793D01*
G01Y1880274D02*
Y1879092D01*
G01Y1877124D02*
Y1875943D01*
G01Y1883423D02*
Y1882242D01*
G01Y1889722D02*
Y1888541D01*
G01Y1886573D02*
Y1885392D01*
G01Y1892872D02*
Y1891691D01*
G01Y1899171D02*
Y1897990D01*
G01Y1896022D02*
Y1894840D01*
G01Y1902321D02*
Y1901140D01*
G01Y1908620D02*
Y1907439D01*
G01Y1905470D02*
Y1904289D01*
G01Y1911770D02*
Y1910588D01*
G01Y1914919D02*
Y1913738D01*
G01Y1921218D02*
Y1920037D01*
G01Y1918069D02*
Y1916888D01*
G01Y1940116D02*
Y1938935D01*
G01Y1936966D02*
Y1935785D01*
G01X1469278Y1873974D02*
Y1872793D01*
G01Y1880274D02*
Y1879092D01*
G01Y1877124D02*
Y1875943D01*
G01Y1883423D02*
Y1882242D01*
G01Y1889722D02*
Y1888541D01*
G01Y1886573D02*
Y1885392D01*
G01Y1892872D02*
Y1891691D01*
G01Y1899171D02*
Y1897990D01*
G01Y1896022D02*
Y1894840D01*
G01Y1902321D02*
Y1901140D01*
G01Y1908620D02*
Y1907439D01*
G01Y1905470D02*
Y1904289D01*
G01Y1911770D02*
Y1910588D01*
G01Y1914919D02*
Y1913738D01*
G01Y1921218D02*
Y1920037D01*
G01Y1918069D02*
Y1916888D01*
G01Y1940116D02*
Y1938935D01*
G01Y1936966D02*
Y1935785D01*
G01X1467296Y1873974D02*
Y1872793D01*
G01Y1880274D02*
Y1879092D01*
G01Y1877124D02*
Y1875943D01*
G01Y1883423D02*
Y1882242D01*
G01Y1889722D02*
Y1888541D01*
G01Y1886573D02*
Y1885392D01*
G01Y1892872D02*
Y1891691D01*
G01Y1899171D02*
Y1897990D01*
G01Y1896022D02*
Y1894840D01*
G01Y1902321D02*
Y1901140D01*
G01Y1908620D02*
Y1907439D01*
G01Y1905470D02*
Y1904289D01*
G01Y1911770D02*
Y1910588D01*
G01Y1914919D02*
Y1913738D01*
G01Y1921218D02*
Y1920037D01*
G01Y1918069D02*
Y1916888D01*
G01Y1940116D02*
Y1938935D01*
G01Y1936966D02*
Y1935785D01*
G01X1467186Y1873974D02*
Y1872793D01*
G01Y1880274D02*
Y1879092D01*
G01Y1877124D02*
Y1875943D01*
G01Y1883423D02*
Y1882242D01*
G01Y1889722D02*
Y1888541D01*
G01Y1886573D02*
Y1885392D01*
G01Y1892872D02*
Y1891691D01*
G01Y1899171D02*
Y1897990D01*
G01Y1896022D02*
Y1894840D01*
G01Y1902321D02*
Y1901140D01*
G01Y1908620D02*
Y1907439D01*
G01Y1905470D02*
Y1904289D01*
G01Y1911770D02*
Y1910588D01*
G01Y1914919D02*
Y1913738D01*
G01Y1921218D02*
Y1920037D01*
G01Y1918069D02*
Y1916888D01*
G01Y1940116D02*
Y1938935D01*
G01Y1936966D02*
Y1935785D01*
G01X1458405Y1873974D02*
Y1872793D01*
G01Y1880274D02*
Y1879092D01*
G01Y1877124D02*
Y1875943D01*
G01Y1883423D02*
Y1882242D01*
G01Y1889722D02*
Y1888541D01*
G01Y1886573D02*
Y1885392D01*
G01Y1892872D02*
Y1891691D01*
G01Y1899171D02*
Y1897990D01*
G01Y1896022D02*
Y1894840D01*
G01Y1902321D02*
Y1901140D01*
G01Y1908620D02*
Y1907439D01*
G01Y1905470D02*
Y1904289D01*
G01Y1911770D02*
Y1910588D01*
G01Y1914919D02*
Y1913738D01*
G01Y1921218D02*
Y1920037D01*
G01Y1918069D02*
Y1916888D01*
G01Y1940116D02*
Y1938935D01*
G01Y1936966D02*
Y1935785D01*
G01X1458295Y1873974D02*
Y1872793D01*
G01Y1880274D02*
Y1879092D01*
G01Y1877124D02*
Y1875943D01*
G01Y1883423D02*
Y1882242D01*
G01Y1889722D02*
Y1888541D01*
G01Y1886573D02*
Y1885392D01*
G01Y1892872D02*
Y1891691D01*
G01Y1899171D02*
Y1897990D01*
G01Y1896022D02*
Y1894840D01*
G01Y1902321D02*
Y1901140D01*
G01Y1908620D02*
Y1907439D01*
G01Y1905470D02*
Y1904289D01*
G01Y1911770D02*
Y1910588D01*
G01Y1914919D02*
Y1913738D01*
G01Y1921218D02*
Y1920037D01*
G01Y1918069D02*
Y1916888D01*
G01Y1940116D02*
Y1938935D01*
G01Y1936966D02*
Y1935785D01*
G01X1457929Y1873974D02*
Y1872793D01*
G01Y1880274D02*
Y1879092D01*
G01Y1877124D02*
Y1875943D01*
G01Y1883423D02*
Y1882242D01*
G01Y1889722D02*
Y1888541D01*
G01Y1886573D02*
Y1885392D01*
G01Y1892872D02*
Y1891691D01*
G01Y1899171D02*
Y1897990D01*
G01Y1896022D02*
Y1894840D01*
G01Y1902321D02*
Y1901140D01*
G01Y1908620D02*
Y1907439D01*
G01Y1905470D02*
Y1904289D01*
G01Y1911770D02*
Y1910588D01*
G01Y1914919D02*
Y1913738D01*
G01Y1921218D02*
Y1920037D01*
G01Y1918069D02*
Y1916888D01*
G01Y1940116D02*
Y1938935D01*
G01Y1936966D02*
Y1935785D01*
G01X1457732Y1872793D02*
Y1872203D01*
G01Y1874565D02*
Y1873974D01*
G01Y1871415D02*
Y1870825D01*
G01Y1879092D02*
Y1878502D01*
G01Y1875943D02*
Y1875352D01*
G01Y1877714D02*
Y1877124D01*
G01Y1882242D02*
Y1881651D01*
G01Y1884014D02*
Y1883423D01*
G01Y1880864D02*
Y1880274D01*
G01Y1888541D02*
Y1887951D01*
G01Y1885392D02*
Y1884801D01*
G01Y1887163D02*
Y1886573D01*
G01Y1891691D02*
Y1891100D01*
G01Y1893463D02*
Y1892872D01*
G01Y1890313D02*
Y1889722D01*
G01Y1897990D02*
Y1897400D01*
G01Y1894840D02*
Y1894250D01*
G01Y1896612D02*
Y1896022D01*
G01Y1901140D02*
Y1900549D01*
G01Y1902911D02*
Y1902321D01*
G01Y1899762D02*
Y1899171D01*
G01Y1907439D02*
Y1906848D01*
G01Y1904289D02*
Y1903699D01*
G01Y1906061D02*
Y1905470D01*
G01Y1910588D02*
Y1909998D01*
G01Y1912360D02*
Y1911770D01*
G01Y1909211D02*
Y1908620D01*
G01Y1916888D02*
Y1916297D01*
G01Y1913738D02*
Y1913148D01*
G01Y1915510D02*
Y1914919D01*
G01Y1920037D02*
Y1919447D01*
G01Y1921809D02*
Y1921218D01*
G01Y1918659D02*
Y1918069D01*
G01Y1935785D02*
Y1935195D01*
G01Y1938935D02*
Y1938344D01*
G01Y1937557D02*
Y1936966D01*
G01X1457535Y1872793D02*
Y1872203D01*
G01Y1874565D02*
Y1873974D01*
G01Y1871415D02*
Y1870825D01*
G01Y1879092D02*
Y1878502D01*
G01Y1875943D02*
Y1875352D01*
G01Y1877714D02*
Y1877124D01*
G01Y1882242D02*
Y1881651D01*
G01Y1884014D02*
Y1883423D01*
G01Y1880864D02*
Y1880274D01*
G01Y1888541D02*
Y1887951D01*
G01Y1885392D02*
Y1884801D01*
G01Y1887163D02*
Y1886573D01*
G01Y1891691D02*
Y1891100D01*
G01Y1893463D02*
Y1892872D01*
G01Y1890313D02*
Y1889722D01*
G01Y1897990D02*
Y1897400D01*
G01Y1894840D02*
Y1894250D01*
G01Y1896612D02*
Y1896022D01*
G01Y1901140D02*
Y1900549D01*
G01Y1902911D02*
Y1902321D01*
G01Y1899762D02*
Y1899171D01*
G01Y1907439D02*
Y1906848D01*
G01Y1904289D02*
Y1903699D01*
G01Y1906061D02*
Y1905470D01*
G01Y1910588D02*
Y1909998D01*
G01Y1912360D02*
Y1911770D01*
G01Y1909211D02*
Y1908620D01*
G01Y1916888D02*
Y1916297D01*
G01Y1913738D02*
Y1913148D01*
G01Y1915510D02*
Y1914919D01*
G01Y1920037D02*
Y1919447D01*
G01Y1921809D02*
Y1921218D01*
G01Y1918659D02*
Y1918069D01*
G01Y1935785D02*
Y1935195D01*
G01Y1938935D02*
Y1938344D01*
G01Y1937557D02*
Y1936966D01*
G01X1457220Y2261801D02*
Y1934801D01*
G01X1449937Y2113541D02*
Y1932439D01*
G01X1444212Y1874171D02*
Y1872596D01*
G01Y1880470D02*
Y1878896D01*
G01Y1877321D02*
Y1875746D01*
G01Y1883620D02*
Y1882045D01*
G01Y1889919D02*
Y1888344D01*
G01Y1886770D02*
Y1885195D01*
G01Y1893069D02*
Y1891494D01*
G01Y1896218D02*
Y1894644D01*
G01Y1902518D02*
Y1900943D01*
G01Y1899368D02*
Y1897793D01*
G01Y1905667D02*
Y1904092D01*
G01Y1911966D02*
Y1910392D01*
G01Y1908817D02*
Y1907242D01*
G01Y1915116D02*
Y1913541D01*
G01Y1921415D02*
Y1919840D01*
G01Y1918266D02*
Y1916691D01*
G01Y1940313D02*
Y1938738D01*
G01Y1937163D02*
Y1935588D01*
G01X1442684Y1873964D02*
Y1872804D01*
G01Y1880263D02*
Y1879103D01*
G01Y1877113D02*
Y1875953D01*
G01Y1883413D02*
Y1882253D01*
G01Y1889712D02*
Y1888552D01*
G01Y1886562D02*
Y1885402D01*
G01Y1892861D02*
Y1891701D01*
G01Y1899161D02*
Y1898001D01*
G01Y1896011D02*
Y1894851D01*
G01Y1902310D02*
Y1901150D01*
G01Y1908609D02*
Y1907449D01*
G01Y1905460D02*
Y1904300D01*
G01Y1911759D02*
Y1910599D01*
G01Y1918058D02*
Y1916898D01*
G01Y1914909D02*
Y1913749D01*
G01Y1921208D02*
Y1920048D01*
G01Y1940105D02*
Y1938946D01*
G01Y1936956D02*
Y1935796D01*
G01X1443073Y1871022D02*
X1442684Y1870814D01*
G01X1443073Y1874171D02*
X1442684Y1873964D01*
G01X1443073Y1877321D02*
X1442684Y1877113D01*
G01X1443073Y1880470D02*
X1442684Y1880263D01*
G01X1443073Y1883620D02*
X1442684Y1883413D01*
G01X1443073Y1886770D02*
X1442684Y1886562D01*
G01X1443073Y1889919D02*
X1442684Y1889712D01*
G01X1443073Y1893069D02*
X1442684Y1892861D01*
G01X1443073Y1896218D02*
X1442684Y1896011D01*
G01X1443073Y1899368D02*
X1442684Y1899161D01*
G01X1443073Y1902518D02*
X1442684Y1902310D01*
G01X1443073Y1905667D02*
X1442684Y1905460D01*
G01X1443073Y1908817D02*
X1442684Y1908609D01*
G01X1443073Y1911966D02*
X1442684Y1911759D01*
G01X1443073Y1915116D02*
X1442684Y1914909D01*
G01X1443073Y1918266D02*
X1442684Y1918058D01*
G01X1443073Y1921415D02*
X1442684Y1921208D01*
G01X1496457Y1928081D02*
X1493047Y1926112D01*
G01X1443243Y1871022D02*
X1442772Y1870726D01*
G01X1442684Y1870814D02*
X1442543Y1870726D01*
G01X1443243Y1874171D02*
X1442772Y1873876D01*
G01X1442684Y1873964D02*
X1442543Y1873876D01*
G01X1443243Y1877321D02*
X1442772Y1877025D01*
G01X1442684Y1877113D02*
X1442543Y1877025D01*
G01X1443243Y1880470D02*
X1442772Y1880175D01*
G01X1442684Y1880263D02*
X1442543Y1880175D01*
G01X1443243Y1883620D02*
X1442772Y1883325D01*
G01X1442684Y1883413D02*
X1442543Y1883325D01*
G01X1443243Y1886770D02*
X1442772Y1886474D01*
G01X1442684Y1886562D02*
X1442543Y1886474D01*
G01X1443243Y1889919D02*
X1442772Y1889624D01*
G01X1442684Y1889712D02*
X1442543Y1889624D01*
G01X1443243Y1893069D02*
X1442772Y1892774D01*
G01X1442684Y1892861D02*
X1442543Y1892774D01*
G01X1443243Y1896218D02*
X1442772Y1895923D01*
G01X1442684Y1896011D02*
X1442543Y1895923D01*
G01X1443243Y1899368D02*
X1442772Y1899073D01*
G01X1442684Y1899161D02*
X1442543Y1899073D01*
G01X1443243Y1902518D02*
X1442772Y1902222D01*
G01X1442684Y1902310D02*
X1442543Y1902222D01*
G01X1443243Y1905667D02*
X1442772Y1905372D01*
G01X1442684Y1905460D02*
X1442543Y1905372D01*
G01X1443243Y1908817D02*
X1442772Y1908522D01*
G01X1442684Y1908609D02*
X1442543Y1908522D01*
G01X1443243Y1911966D02*
X1442772Y1911671D01*
G01X1442684Y1911759D02*
X1442543Y1911671D01*
G01X1443243Y1915116D02*
X1442772Y1914821D01*
G01X1442684Y1914909D02*
X1442543Y1914821D01*
G01X1443243Y1918266D02*
X1442772Y1917970D01*
G01X1442684Y1918058D02*
X1442543Y1917970D01*
G01X1443243Y1921415D02*
X1442772Y1921120D01*
G01X1442684Y1921208D02*
X1442543Y1921120D01*
G01X1476905Y1926533D02*
X1474937Y1924565D01*
G01X1457220Y1922203D02*
X1459189Y1924171D01*
G01X1469507Y1873049D02*
X1469278Y1872793D01*
G01X1469507Y1876199D02*
X1469278Y1875943D01*
G01X1469507Y1879348D02*
X1469278Y1879092D01*
G01X1469507Y1882498D02*
X1469278Y1882242D01*
G01X1469507Y1885648D02*
X1469278Y1885392D01*
G01X1469507Y1888797D02*
X1469278Y1888541D01*
G01X1469507Y1891947D02*
X1469278Y1891691D01*
G01X1469507Y1895096D02*
X1469278Y1894840D01*
G01X1469507Y1898246D02*
X1469278Y1897990D01*
G01X1469507Y1901396D02*
X1469278Y1901140D01*
G01X1469507Y1904545D02*
X1469278Y1904289D01*
G01X1469507Y1907695D02*
X1469278Y1907439D01*
G01X1469507Y1910844D02*
X1469278Y1910588D01*
G01X1469507Y1913994D02*
X1469278Y1913738D01*
G01X1469507Y1917144D02*
X1469278Y1916888D01*
G01X1469507Y1920293D02*
X1469278Y1920037D01*
G01X1469507Y1936041D02*
X1469278Y1935785D01*
G01X1469507Y1939191D02*
X1469278Y1938935D01*
G01X1469855Y1873049D02*
X1469636Y1872779D01*
G01X1469855Y1876199D02*
X1469636Y1875929D01*
G01X1469855Y1879348D02*
X1469636Y1879078D01*
G01X1469855Y1882498D02*
X1469636Y1882228D01*
G01X1469855Y1885648D02*
X1469636Y1885378D01*
G01X1469855Y1888797D02*
X1469636Y1888527D01*
G01X1469855Y1891947D02*
X1469636Y1891677D01*
G01X1469855Y1895096D02*
X1469636Y1894826D01*
G01X1469855Y1898246D02*
X1469636Y1897976D01*
G01X1469855Y1901396D02*
X1469636Y1901126D01*
G01X1469855Y1904545D02*
X1469636Y1904275D01*
G01X1469855Y1907695D02*
X1469636Y1907425D01*
G01X1469855Y1910844D02*
X1469636Y1910574D01*
G01X1469855Y1913994D02*
X1469636Y1913724D01*
G01X1469855Y1917144D02*
X1469636Y1916874D01*
G01X1469855Y1920293D02*
X1469636Y1920023D01*
G01X1469855Y1936041D02*
X1469636Y1935771D01*
G01X1469855Y1939191D02*
X1469636Y1938921D01*
G01X1443073Y1937163D02*
X1442684Y1936956D01*
G01X1443243Y1937163D02*
X1442772Y1936868D01*
G01X1442684Y1936956D02*
X1442543Y1936868D01*
G01X1439047Y1942221D02*
X1442543Y1942183D01*
G01X1437751Y1942235D02*
X1441007Y1942199D01*
G01X1438785Y1942221D02*
X1436420Y1942247D01*
G01X1441235Y1942199D02*
X1442772Y1942183D01*
G01X1441235Y1942199D02*
X1438785Y1942221D01*
G01X1437751Y1942235D02*
X1436420Y1942247D01*
G01X1439047Y1942221D02*
X1438785D01*
G01X1441235Y1942199D02*
X1441007D01*
G01X1441235Y1940001D02*
X1441007D01*
G01X1439047Y1939980D02*
X1438785D01*
G01X1440094Y1939991D02*
X1438785Y1939980D01*
G01X1441235Y1940001D02*
X1440094Y1939991D01*
G01X1437751Y1939965D02*
X1436420Y1939954D01*
G01X1442543Y1940018D02*
X1441007Y1940001D01*
G01X1442543Y1940018D02*
X1439047Y1939980D01*
G01X1441235Y1940001D02*
X1442772Y1940018D01*
G01X1439047Y1939980D02*
X1440094Y1939991D01*
G01X1438785Y1939980D02*
X1436420Y1939954D01*
G01X1437751Y1939965D02*
X1439047Y1939980D01*
G01X1441235Y1943151D02*
Y1942199D01*
G01X1441007Y1943151D02*
Y1942199D01*
G01X1439047Y1943129D02*
Y1942221D01*
G01X1438785Y1943129D02*
Y1942221D01*
G01X1437751Y1943109D02*
Y1942241D01*
G01X1436420Y1943103D02*
Y1942247D01*
G01X1439047Y2011512D02*
X1442543Y2011474D01*
G01X1437751Y2011527D02*
X1441007Y2011491D01*
G01X1439047Y2008363D02*
X1442543Y2008325D01*
G01X1437751Y2008377D02*
X1441007Y2008341D01*
G01X1439047Y2005213D02*
X1442543Y2005175D01*
G01X1437751Y2005227D02*
X1441007Y2005192D01*
G01X1439047Y2002063D02*
X1442543Y2002025D01*
G01X1437751Y2002078D02*
X1441007Y2002042D01*
G01X1439047Y1998914D02*
X1442543Y1998876D01*
G01X1437751Y1998928D02*
X1441007Y1998892D01*
G01X1439047Y1995764D02*
X1442543Y1995726D01*
G01X1437751Y1995779D02*
X1441007Y1995743D01*
G01X1439047Y1992615D02*
X1442543Y1992577D01*
G01X1437751Y1992629D02*
X1441007Y1992593D01*
G01X1439047Y1989465D02*
X1442543Y1989427D01*
G01X1437751Y1989479D02*
X1441007Y1989444D01*
G01X1439047Y1986315D02*
X1442543Y1986277D01*
G01X1437751Y1986330D02*
X1441007Y1986294D01*
G01X1439047Y1983166D02*
X1442543Y1983128D01*
G01X1437751Y1983180D02*
X1441007Y1983144D01*
G01X1439047Y1980016D02*
X1442543Y1979978D01*
G01X1437751Y1980031D02*
X1441007Y1979995D01*
G01X1439047Y1976867D02*
X1442543Y1976829D01*
G01X1437751Y1976881D02*
X1441007Y1976845D01*
G01X1439047Y1973717D02*
X1442543Y1973679D01*
G01X1437751Y1973731D02*
X1441007Y1973695D01*
G01X1438785Y2011512D02*
X1436420Y2011538D01*
G01X1438785Y2008363D02*
X1436420Y2008389D01*
G01X1438785Y2005213D02*
X1436420Y2005239D01*
G01X1438785Y2002064D02*
X1436420Y2002090D01*
G01X1438785Y1998914D02*
X1436420Y1998940D01*
G01X1438785Y1995764D02*
X1436420Y1995790D01*
G01X1438785Y1992615D02*
X1436420Y1992641D01*
G01X1438785Y1989465D02*
X1436420Y1989491D01*
G01X1438785Y1986315D02*
X1436420Y1986342D01*
G01X1438785Y1983166D02*
X1436420Y1983192D01*
G01X1438785Y1980016D02*
X1436420Y1980042D01*
G01X1438785Y1976867D02*
X1436420Y1976893D01*
G01X1438785Y1973717D02*
X1436420Y1973743D01*
G01X1441235Y2011491D02*
X1442772Y2011474D01*
G01X1441235Y2008341D02*
X1442772Y2008325D01*
G01X1441235Y2005192D02*
X1442772Y2005175D01*
G01X1441235Y2002042D02*
X1442772Y2002025D01*
G01X1441235Y1998892D02*
X1442772Y1998876D01*
G01X1441235Y1995743D02*
X1442772Y1995726D01*
G01X1441235Y1992593D02*
X1442772Y1992577D01*
G01X1441235Y1989444D02*
X1442772Y1989427D01*
G01X1441235Y1986294D02*
X1442772Y1986277D01*
G01X1441235Y1983144D02*
X1442772Y1983128D01*
G01X1441235Y1979995D02*
X1442772Y1979978D01*
G01X1441235Y1976845D02*
X1442772Y1976829D01*
G01X1441235Y1973695D02*
X1442772Y1973679D01*
G01X1441235Y2011491D02*
X1438785Y2011512D01*
G01X1437751Y2011527D02*
X1436420Y2011538D01*
G01X1441235Y2008341D02*
X1438785Y2008363D01*
G01X1437751Y2008377D02*
X1436420Y2008389D01*
G01X1441235Y2005192D02*
X1438785Y2005213D01*
G01X1437751Y2005227D02*
X1436420Y2005239D01*
G01X1441235Y2002042D02*
X1438785Y2002064D01*
G01X1437751Y2002078D02*
X1436420Y2002090D01*
G01X1441235Y1998892D02*
X1438785Y1998914D01*
G01X1437751Y1998928D02*
X1436420Y1998940D01*
G01X1441235Y1995743D02*
X1438785Y1995764D01*
G01X1437751Y1995779D02*
X1436420Y1995790D01*
G01X1441235Y1992593D02*
X1438785Y1992615D01*
G01X1437751Y1992629D02*
X1436420Y1992641D01*
G01X1441235Y1989444D02*
X1438785Y1989465D01*
G01X1437751Y1989479D02*
X1436420Y1989491D01*
G01X1441235Y1986294D02*
X1438785Y1986315D01*
G01X1437751Y1986330D02*
X1436420Y1986342D01*
G01X1441235Y1983144D02*
X1438785Y1983166D01*
G01X1437751Y1983180D02*
X1436420Y1983192D01*
G01X1441235Y1979995D02*
X1438785Y1980016D01*
G01X1437751Y1980031D02*
X1436420Y1980042D01*
G01X1441235Y1976845D02*
X1438785Y1976867D01*
G01X1437751Y1976881D02*
X1436420Y1976893D01*
G01X1441235Y1973695D02*
X1438785Y1973717D01*
G01X1437751Y1973731D02*
X1436420Y1973743D01*
G01X1439047Y2011512D02*
X1438785D01*
G01X1441235Y2011491D02*
X1441007D01*
G01X1441235Y2009293D02*
X1441007D01*
G01X1439047Y2009271D02*
X1438785D01*
G01X1439047Y2008363D02*
X1438785D01*
G01X1441235Y2008341D02*
X1441007D01*
G01X1441235Y2006143D02*
X1441007D01*
G01X1439047Y2006121D02*
X1438785D01*
G01X1439047Y2005213D02*
X1438785D01*
G01X1441235Y2005192D02*
X1441007D01*
G01X1441235Y2002993D02*
X1441007D01*
G01X1439047Y2002972D02*
X1438785D01*
G01X1439047Y2002064D02*
X1438785D01*
G01X1441235Y2002042D02*
X1441007D01*
G01X1441235Y1999844D02*
X1441007D01*
G01X1439047Y1999822D02*
X1438785D01*
G01X1439047Y1998914D02*
X1438785D01*
G01X1441235Y1998892D02*
X1441007D01*
G01X1441235Y1996694D02*
X1441007D01*
G01X1439047Y1996673D02*
X1438785D01*
G01X1439047Y1995764D02*
X1438785D01*
G01X1441235Y1995743D02*
X1441007D01*
G01X1441235Y1993544D02*
X1441007D01*
G01X1439047Y1993523D02*
X1438785D01*
G01X1439047Y1992615D02*
X1438785D01*
G01X1441235Y1992593D02*
X1441007D01*
G01X1441235Y1990395D02*
X1441007D01*
G01X1439047Y1990373D02*
X1438785D01*
G01X1439047Y1989465D02*
X1438785D01*
G01X1441235Y1989444D02*
X1441007D01*
G01X1441235Y1987245D02*
X1441007D01*
G01X1439047Y1987224D02*
X1438785D01*
G01X1439047Y1986315D02*
X1438785D01*
G01X1441235Y1986294D02*
X1441007D01*
G01X1441235Y1984096D02*
X1441007D01*
G01X1439047Y1984074D02*
X1438785D01*
G01X1439047Y1983166D02*
X1438785D01*
G01X1441235Y1983144D02*
X1441007D01*
G01X1441235Y1980946D02*
X1441007D01*
G01X1439047Y1980924D02*
X1438785D01*
G01X1439047Y1980016D02*
X1438785D01*
G01X1441235Y1979995D02*
X1441007D01*
G01X1441235Y1977796D02*
X1441007D01*
G01X1439047Y1977775D02*
X1438785D01*
G01X1439047Y1976867D02*
X1438785D01*
G01X1441235Y1976845D02*
X1441007D01*
G01X1441235Y1974647D02*
X1441007D01*
G01X1439047Y1974625D02*
X1438785D01*
G01X1439047Y1973717D02*
X1438785D01*
G01X1441235Y1973695D02*
X1441007D01*
G01X1441235Y1971497D02*
X1441007D01*
G01X1439047Y1971476D02*
X1438785D01*
G01X1439047Y1970567D02*
X1438785D01*
G01X1441235Y1970546D02*
X1441007D01*
G01X1441235Y1968348D02*
X1441007D01*
G01X1439047Y1968326D02*
X1438785D01*
G01X1439047Y1967418D02*
X1438785D01*
G01X1441235Y1967396D02*
X1441007D01*
G01X1440094Y2009283D02*
X1438785Y2009271D01*
G01X1441235Y2009293D02*
X1440094Y2009283D01*
G01Y2006133D02*
X1438785Y2006121D01*
G01X1441235Y2006143D02*
X1440094Y2006133D01*
G01Y2002983D02*
X1438785Y2002972D01*
G01X1441235Y2002993D02*
X1440094Y2002983D01*
G01Y1999834D02*
X1438785Y1999822D01*
G01X1441235Y1999844D02*
X1440094Y1999834D01*
G01Y1996684D02*
X1438785Y1996673D01*
G01X1441235Y1996694D02*
X1440094Y1996684D01*
G01Y1993534D02*
X1438785Y1993523D01*
G01X1441235Y1993544D02*
X1440094Y1993534D01*
G01Y1990385D02*
X1438785Y1990373D01*
G01X1441235Y1990395D02*
X1440094Y1990385D01*
G01Y1987235D02*
X1438785Y1987224D01*
G01X1441235Y1987245D02*
X1440094Y1987235D01*
G01Y1984086D02*
X1438785Y1984074D01*
G01X1441235Y1984096D02*
X1440094Y1984086D01*
G01Y1980936D02*
X1438785Y1980924D01*
G01X1441235Y1980946D02*
X1440094Y1980936D01*
G01Y1977786D02*
X1438785Y1977775D01*
G01X1441235Y1977796D02*
X1440094Y1977786D01*
G01Y1974637D02*
X1438785Y1974625D01*
G01X1441235Y1974647D02*
X1440094Y1974637D01*
G01Y1971487D02*
X1438785Y1971476D01*
G01X1441235Y1971497D02*
X1440094Y1971487D01*
G01Y1968338D02*
X1438785Y1968326D01*
G01X1441235Y1968348D02*
X1440094Y1968338D01*
G01Y1965188D02*
X1438785Y1965176D01*
G01X1441235Y1965198D02*
X1440094Y1965188D01*
G01Y1962038D02*
X1438785Y1962027D01*
G01X1441235Y1962048D02*
X1440094Y1962038D01*
G01X1437751Y2009257D02*
X1436420Y2009245D01*
G01X1437751Y2006107D02*
X1436420Y2006095D01*
G01X1437751Y2002957D02*
X1436420Y2002946D01*
G01X1437751Y1999808D02*
X1436420Y1999796D01*
G01X1437751Y1996658D02*
X1436420Y1996646D01*
G01X1437751Y1993509D02*
X1436420Y1993497D01*
G01X1437751Y1990359D02*
X1436420Y1990347D01*
G01X1437751Y1987209D02*
X1436420Y1987198D01*
G01X1437751Y1984060D02*
X1436420Y1984048D01*
G01X1437751Y1980910D02*
X1436420Y1980898D01*
G01X1437751Y1977761D02*
X1436420Y1977749D01*
G01X1437751Y1974611D02*
X1436420Y1974599D01*
G01X1437751Y1971461D02*
X1436420Y1971450D01*
G01X1437751Y1968312D02*
X1436420Y1968300D01*
G01X1437751Y1965162D02*
X1436420Y1965150D01*
G01X1437751Y1962013D02*
X1436420Y1962001D01*
G01X1442543Y2009309D02*
X1441007Y2009293D01*
G01X1442543Y2009309D02*
X1439047Y2009271D01*
G01X1441235Y2009293D02*
X1442772Y2009309D01*
G01X1442543Y2006159D02*
X1441007Y2006143D01*
G01X1442543Y2006159D02*
X1439047Y2006121D01*
G01X1441235Y2006143D02*
X1442772Y2006159D01*
G01X1442543Y2003010D02*
X1441007Y2002993D01*
G01X1442543Y2003010D02*
X1439047Y2002972D01*
G01X1441235Y2002993D02*
X1442772Y2003010D01*
G01X1442543Y1999860D02*
X1441007Y1999844D01*
G01X1442543Y1999860D02*
X1439047Y1999822D01*
G01X1441235Y1999844D02*
X1442772Y1999860D01*
G01X1442543Y1996711D02*
X1441007Y1996694D01*
G01X1442543Y1996711D02*
X1439047Y1996673D01*
G01X1441235Y1996694D02*
X1442772Y1996711D01*
G01X1442543Y1993561D02*
X1441007Y1993544D01*
G01X1442543Y1993561D02*
X1439047Y1993523D01*
G01X1441235Y1993544D02*
X1442772Y1993561D01*
G01X1442543Y1990411D02*
X1441007Y1990395D01*
G01X1442543Y1990411D02*
X1439047Y1990373D01*
G01X1441235Y1990395D02*
X1442772Y1990411D01*
G01X1442543Y1987262D02*
X1441007Y1987245D01*
G01X1442543Y1987262D02*
X1439047Y1987224D01*
G01X1441235Y1987245D02*
X1442772Y1987262D01*
G01X1442543Y1984112D02*
X1441007Y1984096D01*
G01X1442543Y1984112D02*
X1439047Y1984074D01*
G01X1441235Y1984096D02*
X1442772Y1984112D01*
G01X1442543Y1980963D02*
X1441007Y1980946D01*
G01X1442543Y1980963D02*
X1439047Y1980925D01*
G01X1441235Y1980946D02*
X1442772Y1980963D01*
G01X1442543Y1977813D02*
X1441007Y1977796D01*
G01X1442543Y1977813D02*
X1439047Y1977775D01*
G01X1441235Y1977796D02*
X1442772Y1977813D01*
G01X1442543Y1974663D02*
X1441007Y1974647D01*
G01X1442543Y1974663D02*
X1439047Y1974625D01*
G01X1441235Y1974647D02*
X1442772Y1974663D01*
G01X1442543Y1971514D02*
X1441007Y1971497D01*
G01X1442543Y1971514D02*
X1439047Y1971476D01*
G01X1441235Y1971497D02*
X1442772Y1971514D01*
G01X1442543Y1968364D02*
X1441007Y1968348D01*
G01X1442543Y1968364D02*
X1439047Y1968326D01*
G01X1441235Y1968348D02*
X1442772Y1968364D01*
G01X1442543Y1965214D02*
X1441007Y1965198D01*
G01X1442543Y1965214D02*
X1439047Y1965177D01*
G01X1441235Y1965198D02*
X1442772Y1965214D01*
G01X1442543Y1962065D02*
X1441007Y1962048D01*
G01X1442543Y1962065D02*
X1439047Y1962027D01*
G01X1441235Y1962048D02*
X1442772Y1962065D01*
G01X1439047Y2009271D02*
X1440094Y2009283D01*
G01X1438785Y2009271D02*
X1436420Y2009245D01*
G01X1437751Y2009257D02*
X1439047Y2009271D01*
G01Y2006121D02*
X1440094Y2006133D01*
G01X1438785Y2006121D02*
X1436420Y2006095D01*
G01X1437751Y2006107D02*
X1439047Y2006121D01*
G01Y2002972D02*
X1440094Y2002983D01*
G01X1438785Y2002972D02*
X1436420Y2002946D01*
G01X1437751Y2002957D02*
X1439047Y2002972D01*
G01Y1999822D02*
X1440094Y1999834D01*
G01X1438785Y1999822D02*
X1436420Y1999796D01*
G01X1437751Y1999808D02*
X1439047Y1999822D01*
G01Y1996673D02*
X1440094Y1996684D01*
G01X1438785Y1996673D02*
X1436420Y1996646D01*
G01X1437751Y1996658D02*
X1439047Y1996673D01*
G01Y1993523D02*
X1440094Y1993534D01*
G01X1438785Y1993523D02*
X1436420Y1993497D01*
G01X1437751Y1993509D02*
X1439047Y1993523D01*
G01Y1990373D02*
X1440094Y1990385D01*
G01X1438785Y1990373D02*
X1436420Y1990347D01*
G01X1437751Y1990359D02*
X1439047Y1990373D01*
G01Y1987224D02*
X1440094Y1987235D01*
G01X1438785Y1987224D02*
X1436420Y1987198D01*
G01X1437751Y1987209D02*
X1439047Y1987224D01*
G01Y1984074D02*
X1440094Y1984086D01*
G01X1438785Y1984074D02*
X1436420Y1984048D01*
G01X1437751Y1984060D02*
X1439047Y1984074D01*
G01Y1980924D02*
X1440094Y1980936D01*
G01X1438785Y1980924D02*
X1436420Y1980898D01*
G01X1437751Y1980910D02*
X1439047Y1980924D01*
G01Y1977775D02*
X1440094Y1977786D01*
G01X1438785Y1977775D02*
X1436420Y1977749D01*
G01X1437751Y1977761D02*
X1439047Y1977775D01*
G01Y1974625D02*
X1440094Y1974637D01*
G01X1438785Y1974625D02*
X1436420Y1974599D01*
G01X1437751Y1974611D02*
X1439047Y1974625D01*
G01Y1971476D02*
X1440094Y1971487D01*
G01X1438785Y1971476D02*
X1436420Y1971450D01*
G01X1437751Y1971461D02*
X1439047Y1971476D01*
G01Y1968326D02*
X1440094Y1968338D01*
G01X1438785Y1968326D02*
X1436420Y1968300D01*
G01X1437751Y1968312D02*
X1439047Y1968326D01*
G01Y1965176D02*
X1440094Y1965188D01*
G01X1438785Y1965176D02*
X1436420Y1965150D01*
G01X1437751Y1965162D02*
X1439047Y1965176D01*
G01Y1962027D02*
X1440094Y1962038D01*
G01X1438785Y1962027D02*
X1436420Y1962001D01*
G01X1437751Y1962013D02*
X1439047Y1962027D01*
G01Y1970567D02*
X1442543Y1970529D01*
G01X1437751Y1970582D02*
X1441007Y1970546D01*
G01X1439047Y1967418D02*
X1442543Y1967380D01*
G01X1437751Y1967432D02*
X1441007Y1967396D01*
G01X1439047Y1964268D02*
X1442543Y1964230D01*
G01X1437751Y1964283D02*
X1441007Y1964247D01*
G01X1439047Y1961119D02*
X1442543Y1961081D01*
G01X1437751Y1961133D02*
X1441007Y1961097D01*
G01X1439047Y1957969D02*
X1442543Y1957931D01*
G01X1437751Y1957983D02*
X1441007Y1957947D01*
G01X1439047Y1954819D02*
X1442543Y1954781D01*
G01X1437751Y1954834D02*
X1441007Y1954798D01*
G01X1439047Y1951670D02*
X1442543Y1951632D01*
G01X1437751Y1951684D02*
X1441007Y1951648D01*
G01X1439047Y1948520D02*
X1442543Y1948482D01*
G01X1437751Y1948535D02*
X1441007Y1948499D01*
G01X1439047Y1945371D02*
X1442543Y1945333D01*
G01X1437751Y1945385D02*
X1441007Y1945349D01*
G01X1438785Y1970567D02*
X1436420Y1970594D01*
G01X1438785Y1967418D02*
X1436420Y1967444D01*
G01X1438785Y1964268D02*
X1436420Y1964294D01*
G01X1438785Y1961119D02*
X1436420Y1961145D01*
G01X1438785Y1957969D02*
X1436420Y1957995D01*
G01X1438785Y1954819D02*
X1436420Y1954846D01*
G01X1438785Y1951670D02*
X1436420Y1951696D01*
G01X1438785Y1948520D02*
X1436420Y1948546D01*
G01X1438785Y1945371D02*
X1436420Y1945397D01*
G01X1441235Y1970546D02*
X1442772Y1970529D01*
G01X1441235Y1967396D02*
X1442772Y1967380D01*
G01X1441235Y1964247D02*
X1442772Y1964230D01*
G01X1441235Y1961097D02*
X1442772Y1961081D01*
G01X1441235Y1957947D02*
X1442772Y1957931D01*
G01X1441235Y1954798D02*
X1442772Y1954781D01*
G01X1441235Y1951648D02*
X1442772Y1951632D01*
G01X1441235Y1948499D02*
X1442772Y1948482D01*
G01X1441235Y1945349D02*
X1442772Y1945333D01*
G01X1441235Y1970546D02*
X1438785Y1970567D01*
G01X1437751Y1970582D02*
X1436420Y1970594D01*
G01X1441235Y1967396D02*
X1438785Y1967418D01*
G01X1437751Y1967432D02*
X1436420Y1967444D01*
G01X1441235Y1964247D02*
X1438785Y1964268D01*
G01X1437751Y1964283D02*
X1436420Y1964294D01*
G01X1441235Y1961097D02*
X1438785Y1961119D01*
G01X1437751Y1961133D02*
X1436420Y1961145D01*
G01X1441235Y1957947D02*
X1438785Y1957969D01*
G01X1437751Y1957983D02*
X1436420Y1957995D01*
G01X1441235Y1954798D02*
X1438785Y1954819D01*
G01X1437751Y1954834D02*
X1436420Y1954846D01*
G01X1441235Y1951648D02*
X1438785Y1951670D01*
G01X1437751Y1951684D02*
X1436420Y1951696D01*
G01X1441235Y1948499D02*
X1438785Y1948520D01*
G01X1437751Y1948535D02*
X1436420Y1948546D01*
G01X1441235Y1945349D02*
X1438785Y1945371D01*
G01X1437751Y1945385D02*
X1436420Y1945397D01*
G01X1441235Y1965198D02*
X1441007D01*
G01X1439047Y1965176D02*
X1438785D01*
G01X1439047Y1964268D02*
X1438785D01*
G01X1441235Y1964247D02*
X1441007D01*
G01X1441235Y1962048D02*
X1441007D01*
G01X1439047Y1962027D02*
X1438785D01*
G01X1439047Y1961119D02*
X1438785D01*
G01X1441235Y1961097D02*
X1441007D01*
G01X1441235Y1958899D02*
X1441007D01*
G01X1439047Y1958877D02*
X1438785D01*
G01X1439047Y1957969D02*
X1438785D01*
G01X1441235Y1957947D02*
X1441007D01*
G01X1441235Y1955749D02*
X1441007D01*
G01X1439047Y1955728D02*
X1438785D01*
G01X1439047Y1954819D02*
X1438785D01*
G01X1441235Y1954798D02*
X1441007D01*
G01X1441235Y1952600D02*
X1441007D01*
G01X1439047Y1952578D02*
X1438785D01*
G01X1439047Y1951670D02*
X1438785D01*
G01X1441235Y1951648D02*
X1441007D01*
G01X1441235Y1949450D02*
X1441007D01*
G01X1439047Y1949428D02*
X1438785D01*
G01X1439047Y1948520D02*
X1438785D01*
G01X1441235Y1948499D02*
X1441007D01*
G01X1441235Y1946300D02*
X1441007D01*
G01X1439047Y1946279D02*
X1438785D01*
G01X1439047Y1945371D02*
X1438785D01*
G01X1441235Y1945349D02*
X1441007D01*
G01X1441235Y1943151D02*
X1441007D01*
G01X1439047Y1943129D02*
X1438785D01*
G01X1440094Y1958889D02*
X1438785Y1958877D01*
G01X1441235Y1958899D02*
X1440094Y1958889D01*
G01Y1955739D02*
X1438785Y1955728D01*
G01X1441235Y1955749D02*
X1440094Y1955739D01*
G01Y1952590D02*
X1438785Y1952578D01*
G01X1441235Y1952600D02*
X1440094Y1952590D01*
G01Y1949440D02*
X1438785Y1949428D01*
G01X1441235Y1949450D02*
X1440094Y1949440D01*
G01Y1946290D02*
X1438785Y1946279D01*
G01X1441235Y1946300D02*
X1440094Y1946290D01*
G01Y1943141D02*
X1438785Y1943129D01*
G01X1441235Y1943151D02*
X1440094Y1943141D01*
G01X1437751Y1958863D02*
X1436420Y1958851D01*
G01X1437751Y1955713D02*
X1436420Y1955702D01*
G01X1437751Y1952564D02*
X1436420Y1952552D01*
G01X1437751Y1949414D02*
X1436420Y1949402D01*
G01X1437751Y1946265D02*
X1436420Y1946253D01*
G01X1437751Y1943115D02*
X1436420Y1943103D01*
G01X1442543Y1958915D02*
X1441007Y1958899D01*
G01X1442543Y1958915D02*
X1439047Y1958877D01*
G01X1441235Y1958899D02*
X1442772Y1958915D01*
G01X1442543Y1955766D02*
X1441007Y1955749D01*
G01X1442543Y1955766D02*
X1439047Y1955728D01*
G01X1441235Y1955749D02*
X1442772Y1955766D01*
G01X1442543Y1952616D02*
X1441007Y1952600D01*
G01X1442543Y1952616D02*
X1439047Y1952578D01*
G01X1441235Y1952600D02*
X1442772Y1952616D01*
G01X1442543Y1949466D02*
X1441007Y1949450D01*
G01X1442543Y1949466D02*
X1439047Y1949428D01*
G01X1441235Y1949450D02*
X1442772Y1949466D01*
G01X1442543Y1946317D02*
X1441007Y1946300D01*
G01X1442543Y1946317D02*
X1439047Y1946279D01*
G01X1441235Y1946300D02*
X1442772Y1946317D01*
G01X1442543Y1943167D02*
X1441007Y1943151D01*
G01X1442543Y1943167D02*
X1439047Y1943129D01*
G01X1441235Y1943151D02*
X1442772Y1943167D01*
G01X1439047Y1958877D02*
X1440094Y1958889D01*
G01X1438785Y1958877D02*
X1436420Y1958851D01*
G01X1437751Y1958863D02*
X1439047Y1958877D01*
G01Y1955728D02*
X1440094Y1955739D01*
G01X1438785Y1955728D02*
X1436420Y1955702D01*
G01X1437751Y1955713D02*
X1439047Y1955728D01*
G01Y1952578D02*
X1440094Y1952590D01*
G01X1438785Y1952578D02*
X1436420Y1952552D01*
G01X1437751Y1952564D02*
X1439047Y1952578D01*
G01Y1949428D02*
X1440094Y1949440D01*
G01X1438785Y1949428D02*
X1436420Y1949402D01*
G01X1437751Y1949414D02*
X1439047Y1949428D01*
G01Y1946279D02*
X1440094Y1946290D01*
G01X1438785Y1946279D02*
X1436420Y1946253D01*
G01X1437751Y1946265D02*
X1439047Y1946279D01*
G01Y1943129D02*
X1440094Y1943141D01*
G01X1438785Y1943129D02*
X1436420Y1943103D01*
G01X1437751Y1943115D02*
X1439047Y1943129D01*
G01X1441235Y1949450D02*
Y1948499D01*
G01Y1946300D02*
Y1945349D01*
G01Y1952600D02*
Y1951648D01*
G01Y1958899D02*
Y1957947D01*
G01Y1955749D02*
Y1954798D01*
G01Y1962048D02*
Y1961097D01*
G01Y1968348D02*
Y1967396D01*
G01Y1965198D02*
Y1964247D01*
G01Y1971497D02*
Y1970546D01*
G01Y1977796D02*
Y1976845D01*
G01Y1974647D02*
Y1973695D01*
G01Y1980946D02*
Y1979995D01*
G01Y1987245D02*
Y1986294D01*
G01Y1984096D02*
Y1983144D01*
G01Y1990395D02*
Y1989444D01*
G01Y1996694D02*
Y1995743D01*
G01Y1993544D02*
Y1992593D01*
G01Y1999844D02*
Y1998892D01*
G01Y2006143D02*
Y2005192D01*
G01Y2002993D02*
Y2002042D01*
G01Y2009292D02*
Y2008341D01*
G01Y2012442D02*
Y2011491D01*
G01X1441007Y1949450D02*
Y1948499D01*
G01Y1946300D02*
Y1945349D01*
G01Y1952600D02*
Y1951648D01*
G01Y1958899D02*
Y1957947D01*
G01Y1955749D02*
Y1954798D01*
G01Y1962048D02*
Y1961097D01*
G01Y1968348D02*
Y1967396D01*
G01Y1965198D02*
Y1964247D01*
G01Y1971497D02*
Y1970546D01*
G01Y1977796D02*
Y1976845D01*
G01Y1974647D02*
Y1973695D01*
G01Y1980946D02*
Y1979995D01*
G01Y1987245D02*
Y1986294D01*
G01Y1984096D02*
Y1983144D01*
G01Y1990395D02*
Y1989444D01*
G01Y1996694D02*
Y1995743D01*
G01Y1993544D02*
Y1992593D01*
G01Y1999844D02*
Y1998892D01*
G01Y2006143D02*
Y2005192D01*
G01Y2002993D02*
Y2002042D01*
G01Y2009293D02*
Y2008341D01*
G01Y2012442D02*
Y2011491D01*
G01X1439047Y1949428D02*
Y1948520D01*
G01Y1946279D02*
Y1945371D01*
G01Y1952578D02*
Y1951670D01*
G01Y1958877D02*
Y1957969D01*
G01Y1955728D02*
Y1954819D01*
G01Y1962027D02*
Y1961119D01*
G01Y1968326D02*
Y1967418D01*
G01Y1965177D02*
Y1964268D01*
G01Y1971476D02*
Y1970567D01*
G01Y1977775D02*
Y1976867D01*
G01Y1974625D02*
Y1973717D01*
G01Y1980925D02*
Y1980016D01*
G01Y1987224D02*
Y1986315D01*
G01Y1984074D02*
Y1983166D01*
G01Y1990373D02*
Y1989465D01*
G01Y1996673D02*
Y1995764D01*
G01Y1993523D02*
Y1992615D01*
G01Y1999822D02*
Y1998914D01*
G01Y2006121D02*
Y2005213D01*
G01Y2002972D02*
Y2002063D01*
G01Y2009271D02*
Y2008363D01*
G01Y2012421D02*
Y2011512D01*
G01X1438785Y1949428D02*
Y1948520D01*
G01Y1946279D02*
Y1945371D01*
G01Y1952578D02*
Y1951670D01*
G01Y1958877D02*
Y1957969D01*
G01Y1955728D02*
Y1954819D01*
G01Y1962027D02*
Y1961119D01*
G01Y1968326D02*
Y1967418D01*
G01Y1965177D02*
Y1964268D01*
G01Y1971476D02*
Y1970567D01*
G01Y1977775D02*
Y1976867D01*
G01Y1974625D02*
Y1973717D01*
G01Y1980925D02*
Y1980016D01*
G01Y1987224D02*
Y1986315D01*
G01Y1984074D02*
Y1983166D01*
G01Y1990373D02*
Y1989465D01*
G01Y1996673D02*
Y1995764D01*
G01Y1993523D02*
Y1992615D01*
G01Y1999822D02*
Y1998914D01*
G01Y2006121D02*
Y2005213D01*
G01Y2002972D02*
Y2002064D01*
G01Y2009271D02*
Y2008363D01*
G01Y2012421D02*
Y2011512D01*
G01X1437751Y1949408D02*
Y1948540D01*
G01Y1946259D02*
Y1945391D01*
G01Y1952558D02*
Y1951690D01*
G01Y1958857D02*
Y1957989D01*
G01Y1955707D02*
Y1954840D01*
G01Y1962007D02*
Y1961139D01*
G01Y1968306D02*
Y1967438D01*
G01Y1965156D02*
Y1964288D01*
G01Y1971455D02*
Y1970588D01*
G01Y1977755D02*
Y1976887D01*
G01Y1974605D02*
Y1973737D01*
G01Y1980904D02*
Y1980036D01*
G01Y1987204D02*
Y1986336D01*
G01Y1984054D02*
Y1983186D01*
G01Y1990353D02*
Y1989485D01*
G01Y1996652D02*
Y1995784D01*
G01Y1993503D02*
Y1992635D01*
G01Y1999802D02*
Y1998934D01*
G01Y2006101D02*
Y2005233D01*
G01Y2002952D02*
Y2002084D01*
G01Y2009251D02*
Y2008383D01*
G01Y2012400D02*
Y2011533D01*
G01X1436420Y1949402D02*
Y1948546D01*
G01Y1946253D02*
Y1945397D01*
G01Y1952552D02*
Y1951696D01*
G01Y1958851D02*
Y1957995D01*
G01Y1955702D02*
Y1954846D01*
G01Y1962001D02*
Y1961145D01*
G01Y1968300D02*
Y1967444D01*
G01Y1965150D02*
Y1964294D01*
G01Y1971450D02*
Y1970594D01*
G01Y1977749D02*
Y1976893D01*
G01Y1974599D02*
Y1973743D01*
G01Y1980898D02*
Y1980042D01*
G01Y1987198D02*
Y1986342D01*
G01Y1984048D02*
Y1983192D01*
G01Y1990347D02*
Y1989491D01*
G01Y1996646D02*
Y1995790D01*
G01Y1993497D02*
Y1992641D01*
G01Y1999796D02*
Y1998940D01*
G01Y2006095D02*
Y2005239D01*
G01Y2002946D02*
Y2002090D01*
G01Y2009245D02*
Y2008389D01*
G01Y2012394D02*
Y2011538D01*
G01X1470921Y1942340D02*
X1469507D01*
G01X1442772Y1942183D02*
X1442543D01*
G01X1469631Y1942085D02*
X1457535D01*
G01X1444212Y1941888D02*
X1443073D01*
G01X1457732Y1941494D02*
X1457220D01*
G01X1457732Y1940707D02*
X1457220D01*
G01X1444212Y1940313D02*
X1443073D01*
G01X1469631Y1940116D02*
X1457535D01*
G01X1442772Y1940018D02*
X1442543D01*
G01X1470921Y1939860D02*
X1469507D01*
G01X1442684Y1942095D02*
X1443073Y1941888D01*
G01X1442772Y1942183D02*
X1443243Y1941888D01*
G01X1442543Y1942183D02*
X1442684Y1942095D01*
G01X1469636Y1940130D02*
X1469855Y1939860D01*
G01X1469278Y1940116D02*
X1469507Y1939860D01*
G01X1470921Y1943010D02*
Y1942340D01*
G01X1470574Y1943010D02*
Y1942340D01*
G01X1469631Y1943266D02*
Y1942085D01*
G01X1469278Y1943266D02*
Y1942085D01*
G01X1467296Y1943266D02*
Y1942085D01*
G01X1467186Y1943266D02*
Y1942085D01*
G01X1458405Y1943266D02*
Y1942085D01*
G01X1458295Y1943266D02*
Y1942085D01*
G01X1457929Y1943266D02*
Y1942085D01*
G01X1457732Y1940707D02*
Y1940116D01*
G01Y1942085D02*
Y1941494D01*
G01X1457535Y1940707D02*
Y1940116D01*
G01Y1942085D02*
Y1941494D01*
G01X1444212Y1943463D02*
Y1941888D01*
G01X1442684Y1943255D02*
Y1942095D01*
G01X1469507Y1942340D02*
X1469278Y1942085D01*
G01X1469855Y1942340D02*
X1469636Y1942070D01*
G01X1443073Y1940313D02*
X1442684Y1940105D01*
G01X1443243Y1940313D02*
X1442772Y1940018D01*
G01X1442684Y1940105D02*
X1442543Y1940018D01*
G01X1470921Y2011632D02*
X1469507D01*
G01X1442772Y2011474D02*
X1442543D01*
G01X1469631Y2011376D02*
X1457535D01*
G01X1444212Y2011179D02*
X1443073D01*
G01X1457732Y2010785D02*
X1457220D01*
G01X1457732Y2009998D02*
X1457220D01*
G01X1444212Y2009604D02*
X1443073D01*
G01X1469631Y2009407D02*
X1457535D01*
G01X1442772Y2009309D02*
X1442543D01*
G01X1470921Y2009151D02*
X1469507D01*
G01X1470921Y2008482D02*
X1469507D01*
G01X1442772Y2008325D02*
X1442543D01*
G01X1469631Y2008226D02*
X1457535D01*
G01X1444212Y2008029D02*
X1443073D01*
G01X1457732Y2007636D02*
X1457220D01*
G01X1457732Y2006848D02*
X1457220D01*
G01X1444212Y2006455D02*
X1443073D01*
G01X1469631Y2006258D02*
X1457535D01*
G01X1442772Y2006159D02*
X1442543D01*
G01X1470921Y2006002D02*
X1469507D01*
G01X1470921Y2005333D02*
X1469507D01*
G01X1442772Y2005175D02*
X1442543D01*
G01X1469631Y2005077D02*
X1457535D01*
G01X1444212Y2004880D02*
X1443073D01*
G01X1457732Y2004486D02*
X1457220D01*
G01X1457732Y2003699D02*
X1457220D01*
G01X1444212Y2003305D02*
X1443073D01*
G01X1469631Y2003108D02*
X1457535D01*
G01X1442772Y2003010D02*
X1442543D01*
G01X1470921Y2002852D02*
X1469507D01*
G01X1470921Y2002183D02*
X1469507D01*
G01X1442772Y2002025D02*
X1442543D01*
G01X1469631Y2001927D02*
X1457535D01*
G01X1444212Y2001730D02*
X1443073D01*
G01X1457732Y2001337D02*
X1457220D01*
G01X1457732Y2000549D02*
X1457220D01*
G01X1444212Y2000155D02*
X1443073D01*
G01X1469631Y1999959D02*
X1457535D01*
G01X1442772Y1999860D02*
X1442543D01*
G01X1470921Y1999703D02*
X1469507D01*
G01X1470921Y1999033D02*
X1469507D01*
G01X1442772Y1998876D02*
X1442543D01*
G01X1469631Y1998777D02*
X1457535D01*
G01X1444212Y1998581D02*
X1443073D01*
G01X1457732Y1998187D02*
X1457220D01*
G01X1457732Y1997400D02*
X1457220D01*
G01X1444212Y1997006D02*
X1443073D01*
G01X1469631Y1996809D02*
X1457535D01*
G01X1442772Y1996711D02*
X1442543D01*
G01X1470921Y1996553D02*
X1469507D01*
G01X1470921Y1995884D02*
X1469507D01*
G01X1442772Y1995726D02*
X1442543D01*
G01X1469631Y1995628D02*
X1457535D01*
G01X1444212Y1995431D02*
X1443073D01*
G01X1457732Y1995037D02*
X1457220D01*
G01X1457732Y1994250D02*
X1457220D01*
G01X1444212Y1993856D02*
X1443073D01*
G01X1469631Y1993659D02*
X1457535D01*
G01X1442772Y1993561D02*
X1442543D01*
G01X1470921Y1993403D02*
X1469507D01*
G01X1470921Y1992734D02*
X1469507D01*
G01X1442772Y1992577D02*
X1442543D01*
G01X1469631Y1992478D02*
X1457535D01*
G01X1444212Y1992281D02*
X1443073D01*
G01X1457732Y1991888D02*
X1457220D01*
G01X1457732Y1991100D02*
X1457220D01*
G01X1444212Y1990707D02*
X1443073D01*
G01X1469631Y1990510D02*
X1457535D01*
G01X1442772Y1990411D02*
X1442543D01*
G01X1470921Y1990254D02*
X1469507D01*
G01X1470921Y1989585D02*
X1469507D01*
G01X1442772Y1989427D02*
X1442543D01*
G01X1469631Y1989329D02*
X1457535D01*
G01X1444212Y1989132D02*
X1443073D01*
G01X1457732Y1988738D02*
X1457220D01*
G01X1457732Y1987951D02*
X1457220D01*
G01X1444212Y1987557D02*
X1443073D01*
G01X1469631Y1987360D02*
X1457535D01*
G01X1442772Y1987262D02*
X1442543D01*
G01X1470921Y1987104D02*
X1469507D01*
G01X1470921Y1986435D02*
X1469507D01*
G01X1442772Y1986277D02*
X1442543D01*
G01X1469631Y1986179D02*
X1457535D01*
G01X1444212Y1985982D02*
X1443073D01*
G01X1457732Y1985588D02*
X1457220D01*
G01X1457732Y1984801D02*
X1457220D01*
G01X1444212Y1984407D02*
X1443073D01*
G01X1469631Y1984211D02*
X1457535D01*
G01X1442772Y1984112D02*
X1442543D01*
G01X1470921Y1983955D02*
X1469507D01*
G01X1470921Y1983285D02*
X1469507D01*
G01X1442772Y1983128D02*
X1442543D01*
G01X1469631Y1983029D02*
X1457535D01*
G01X1444212Y1982833D02*
X1443073D01*
G01X1457732Y1982439D02*
X1457220D01*
G01X1457732Y1981651D02*
X1457220D01*
G01X1444212Y1981258D02*
X1443073D01*
G01X1469631Y1981061D02*
X1457535D01*
G01X1442772Y1980963D02*
X1442543D01*
G01X1470921Y1980805D02*
X1469507D01*
G01X1470921Y1980136D02*
X1469507D01*
G01X1442772Y1979978D02*
X1442543D01*
G01X1469631Y1979880D02*
X1457535D01*
G01X1444212Y1979683D02*
X1443073D01*
G01X1457732Y1979289D02*
X1457220D01*
G01X1457732Y1978502D02*
X1457220D01*
G01X1444212Y1978108D02*
X1443073D01*
G01X1469631Y1977911D02*
X1457535D01*
G01X1442772Y1977813D02*
X1442543D01*
G01X1470921Y1977655D02*
X1469507D01*
G01X1470921Y1976986D02*
X1469507D01*
G01X1442772Y1976829D02*
X1442543D01*
G01X1469631Y1976730D02*
X1457535D01*
G01X1444212Y1976533D02*
X1443073D01*
G01X1457732Y1976140D02*
X1457220D01*
G01X1457732Y1975352D02*
X1457220D01*
G01X1444212Y1974959D02*
X1443073D01*
G01X1469631Y1974762D02*
X1457535D01*
G01X1442772Y1974663D02*
X1442543D01*
G01X1470921Y1974506D02*
X1469507D01*
G01X1470921Y1973837D02*
X1469507D01*
G01X1442772Y1973679D02*
X1442543D01*
G01X1469631Y1973581D02*
X1457535D01*
G01X1444212Y1973384D02*
X1443073D01*
G01X1457732Y1972990D02*
X1457220D01*
G01X1457732Y1972203D02*
X1457220D01*
G01X1444212Y1971809D02*
X1443073D01*
G01X1469631Y1971612D02*
X1457535D01*
G01X1442772Y1971514D02*
X1442543D01*
G01X1470921Y1971356D02*
X1469507D01*
G01X1470921Y1970687D02*
X1469507D01*
G01X1442772Y1970529D02*
X1442543D01*
G01X1469631Y1970431D02*
X1457535D01*
G01X1444212Y1970234D02*
X1443073D01*
G01X1457732Y1969840D02*
X1457220D01*
G01X1457732Y1969053D02*
X1457220D01*
G01X1444212Y1968659D02*
X1443073D01*
G01X1469631Y1968463D02*
X1457535D01*
G01X1442772Y1968364D02*
X1442543D01*
G01X1470921Y1968207D02*
X1469507D01*
G01X1470921Y1967537D02*
X1469507D01*
G01X1442772Y1967380D02*
X1442543D01*
G01X1469631Y1967281D02*
X1457535D01*
G01X1444212Y1967085D02*
X1443073D01*
G01X1457732Y1966691D02*
X1457220D01*
G01X1457732Y1965903D02*
X1457220D01*
G01X1444212Y1965510D02*
X1443073D01*
G01X1469631Y1965313D02*
X1457535D01*
G01X1442772Y1965214D02*
X1442543D01*
G01X1470921Y1965057D02*
X1469507D01*
G01X1470921Y1964388D02*
X1469507D01*
G01X1442772Y1964230D02*
X1442543D01*
G01X1469631Y1964132D02*
X1457535D01*
G01X1444212Y1963935D02*
X1443073D01*
G01X1457732Y1963541D02*
X1457220D01*
G01X1457732Y1962754D02*
X1457220D01*
G01X1444212Y1962360D02*
X1443073D01*
G01X1469631Y1962163D02*
X1457535D01*
G01X1442772Y1962065D02*
X1442543D01*
G01X1470921Y1961907D02*
X1469507D01*
G01X1470921Y1961238D02*
X1469507D01*
G01X1442772Y1961081D02*
X1442543D01*
G01X1469631Y1960982D02*
X1457535D01*
G01X1444212Y1960785D02*
X1443073D01*
G01X1457732Y1960392D02*
X1457220D01*
G01X1457732Y1959604D02*
X1457220D01*
G01X1444212Y1959211D02*
X1443073D01*
G01X1469631Y1959014D02*
X1457535D01*
G01X1442772Y1958915D02*
X1442543D01*
G01X1470921Y1958758D02*
X1469507D01*
G01X1470921Y1958088D02*
X1469507D01*
G01X1442772Y1957931D02*
X1442543D01*
G01X1469631Y1957833D02*
X1457535D01*
G01X1444212Y1957636D02*
X1443073D01*
G01X1457732Y1957242D02*
X1457220D01*
G01X1457732Y1956455D02*
X1457220D01*
G01X1444212Y1956061D02*
X1443073D01*
G01X1469631Y1955864D02*
X1457535D01*
G01X1442772Y1955766D02*
X1442543D01*
G01X1470921Y1955608D02*
X1469507D01*
G01X1470921Y1954939D02*
X1469507D01*
G01X1442772Y1954781D02*
X1442543D01*
G01X1469631Y1954683D02*
X1457535D01*
G01X1444212Y1954486D02*
X1443073D01*
G01X1457732Y1954092D02*
X1457220D01*
G01X1457732Y1953305D02*
X1457220D01*
G01X1444212Y1952911D02*
X1443073D01*
G01X1469631Y1952714D02*
X1457535D01*
G01X1442772Y1952616D02*
X1442543D01*
G01X1470921Y1952459D02*
X1469507D01*
G01X1470921Y1951789D02*
X1469507D01*
G01X1442772Y1951632D02*
X1442543D01*
G01X1469631Y1951533D02*
X1457535D01*
G01X1444212Y1951337D02*
X1443073D01*
G01X1457732Y1950943D02*
X1457220D01*
G01X1457732Y1950155D02*
X1457220D01*
G01X1444212Y1949762D02*
X1443073D01*
G01X1469631Y1949565D02*
X1457535D01*
G01X1442772Y1949466D02*
X1442543D01*
G01X1470921Y1949309D02*
X1469507D01*
G01X1470921Y1948640D02*
X1469507D01*
G01X1442772Y1948482D02*
X1442543D01*
G01X1469631Y1948384D02*
X1457535D01*
G01X1444212Y1948187D02*
X1443073D01*
G01X1457732Y1947793D02*
X1457220D01*
G01X1457732Y1947006D02*
X1457220D01*
G01X1444212Y1946612D02*
X1443073D01*
G01X1469631Y1946415D02*
X1457535D01*
G01X1442772Y1946317D02*
X1442543D01*
G01X1470921Y1946159D02*
X1469507D01*
G01X1470921Y1945490D02*
X1469507D01*
G01X1442772Y1945333D02*
X1442543D01*
G01X1469631Y1945234D02*
X1457535D01*
G01X1444212Y1945037D02*
X1443073D01*
G01X1457732Y1944644D02*
X1457220D01*
G01X1457732Y1943856D02*
X1457220D01*
G01X1444212Y1943463D02*
X1443073D01*
G01X1469631Y1943266D02*
X1457535D01*
G01X1442772Y1943167D02*
X1442543D01*
G01X1470921Y1943010D02*
X1469507D01*
G01X1442684Y2011387D02*
X1443073Y2011179D01*
G01X1442684Y2008237D02*
X1443073Y2008029D01*
G01X1442684Y2005087D02*
X1443073Y2004880D01*
G01X1442684Y2001938D02*
X1443073Y2001730D01*
G01X1442684Y1998788D02*
X1443073Y1998581D01*
G01X1442684Y1995638D02*
X1443073Y1995431D01*
G01X1442684Y1992489D02*
X1443073Y1992281D01*
G01X1442772Y2011474D02*
X1443243Y2011179D01*
G01X1442543Y2011474D02*
X1442684Y2011387D01*
G01X1442772Y2008325D02*
X1443243Y2008029D01*
G01X1442543Y2008325D02*
X1442684Y2008237D01*
G01X1442772Y2005175D02*
X1443243Y2004880D01*
G01X1442543Y2005175D02*
X1442684Y2005087D01*
G01X1442772Y2002025D02*
X1443243Y2001730D01*
G01X1442543Y2002025D02*
X1442684Y2001938D01*
G01X1442772Y1998876D02*
X1443243Y1998581D01*
G01X1442543Y1998876D02*
X1442684Y1998788D01*
G01X1442772Y1995726D02*
X1443243Y1995431D01*
G01X1442543Y1995726D02*
X1442684Y1995638D01*
G01X1442772Y1992577D02*
X1443243Y1992281D01*
G01X1442543Y1992577D02*
X1442684Y1992489D01*
G01X1442772Y1989427D02*
X1443243Y1989132D01*
G01X1442543Y1989427D02*
X1442684Y1989339D01*
G01X1442772Y1986277D02*
X1443243Y1985982D01*
G01X1442543Y1986277D02*
X1442684Y1986190D01*
G01X1442772Y1983128D02*
X1443243Y1982833D01*
G01X1442543Y1983128D02*
X1442684Y1983040D01*
G01X1442772Y1979978D02*
X1443243Y1979683D01*
G01X1442543Y1979978D02*
X1442684Y1979890D01*
G01X1442772Y1976829D02*
X1443243Y1976533D01*
G01X1442543Y1976829D02*
X1442684Y1976741D01*
G01X1442772Y1973679D02*
X1443243Y1973384D01*
G01X1442543Y1973679D02*
X1442684Y1973591D01*
G01X1442772Y1970529D02*
X1443243Y1970234D01*
G01X1442543Y1970529D02*
X1442684Y1970442D01*
G01Y1989339D02*
X1443073Y1989132D01*
G01X1442684Y1986190D02*
X1443073Y1985982D01*
G01X1442684Y1983040D02*
X1443073Y1982833D01*
G01X1442684Y1979890D02*
X1443073Y1979683D01*
G01X1442684Y1976741D02*
X1443073Y1976533D01*
G01X1442684Y1973591D02*
X1443073Y1973384D01*
G01X1442684Y1970442D02*
X1443073Y1970234D01*
G01X1442684Y1967292D02*
X1443073Y1967085D01*
G01X1442684Y1964142D02*
X1443073Y1963935D01*
G01X1442684Y1960993D02*
X1443073Y1960785D01*
G01X1442684Y1957843D02*
X1443073Y1957636D01*
G01X1442684Y1954694D02*
X1443073Y1954486D01*
G01X1442684Y1951544D02*
X1443073Y1951337D01*
G01X1442684Y1948394D02*
X1443073Y1948187D01*
G01X1442684Y1945245D02*
X1443073Y1945037D01*
G01X1442772Y1967380D02*
X1443243Y1967085D01*
G01X1442543Y1967380D02*
X1442684Y1967292D01*
G01X1442772Y1964230D02*
X1443243Y1963935D01*
G01X1442543Y1964230D02*
X1442684Y1964142D01*
G01X1442772Y1961081D02*
X1443243Y1960785D01*
G01X1442543Y1961081D02*
X1442684Y1960993D01*
G01X1442772Y1957931D02*
X1443243Y1957636D01*
G01X1442543Y1957931D02*
X1442684Y1957843D01*
G01X1442772Y1954781D02*
X1443243Y1954486D01*
G01X1442543Y1954781D02*
X1442684Y1954694D01*
G01X1442772Y1951632D02*
X1443243Y1951337D01*
G01X1442543Y1951632D02*
X1442684Y1951544D01*
G01X1442772Y1948482D02*
X1443243Y1948187D01*
G01X1442543Y1948482D02*
X1442684Y1948394D01*
G01X1442772Y1945333D02*
X1443243Y1945037D01*
G01X1442543Y1945333D02*
X1442684Y1945245D01*
G01X1469278Y2009407D02*
X1469507Y2009151D01*
G01X1469278Y2006258D02*
X1469507Y2006002D01*
G01X1469278Y2003108D02*
X1469507Y2002852D01*
G01X1469278Y1999959D02*
X1469507Y1999703D01*
G01X1469278Y1996809D02*
X1469507Y1996553D01*
G01X1469278Y1993659D02*
X1469507Y1993403D01*
G01X1469278Y1990510D02*
X1469507Y1990254D01*
G01X1469278Y1987360D02*
X1469507Y1987104D01*
G01X1469278Y1984211D02*
X1469507Y1983955D01*
G01X1469278Y1981061D02*
X1469507Y1980805D01*
G01X1469278Y1977911D02*
X1469507Y1977655D01*
G01X1469278Y1974762D02*
X1469507Y1974506D01*
G01X1469278Y1971612D02*
X1469507Y1971356D01*
G01X1469278Y1968463D02*
X1469507Y1968207D01*
G01X1469278Y1965313D02*
X1469507Y1965057D01*
G01X1469278Y1962163D02*
X1469507Y1961907D01*
G01X1469278Y1959014D02*
X1469507Y1958758D01*
G01X1469278Y1955864D02*
X1469507Y1955608D01*
G01X1469278Y1952714D02*
X1469507Y1952459D01*
G01X1469636Y2009422D02*
X1469855Y2009151D01*
G01X1469636Y2006272D02*
X1469855Y2006002D01*
G01X1469636Y2003122D02*
X1469855Y2002852D01*
G01X1469636Y1999973D02*
X1469855Y1999703D01*
G01X1469636Y1996823D02*
X1469855Y1996553D01*
G01X1469636Y1993673D02*
X1469855Y1993403D01*
G01X1469636Y1990524D02*
X1469855Y1990254D01*
G01X1469636Y1987374D02*
X1469855Y1987104D01*
G01X1469636Y1984225D02*
X1469855Y1983955D01*
G01X1469636Y1981075D02*
X1469855Y1980805D01*
G01X1469636Y1977925D02*
X1469855Y1977655D01*
G01X1469636Y1974776D02*
X1469855Y1974506D01*
G01X1469636Y1971626D02*
X1469855Y1971356D01*
G01X1469636Y1968477D02*
X1469855Y1968207D01*
G01X1469636Y1965327D02*
X1469855Y1965057D01*
G01X1469636Y1962177D02*
X1469855Y1961907D01*
G01X1469636Y1959028D02*
X1469855Y1958758D01*
G01X1469636Y1955878D02*
X1469855Y1955608D01*
G01X1469636Y1952729D02*
X1469855Y1952459D01*
G01X1469636Y1949579D02*
X1469855Y1949309D01*
G01X1469636Y1946429D02*
X1469855Y1946159D01*
G01X1469636Y1943280D02*
X1469855Y1943010D01*
G01X1469278Y1949565D02*
X1469507Y1949309D01*
G01X1469278Y1946415D02*
X1469507Y1946159D01*
G01X1469278Y1943266D02*
X1469507Y1943010D01*
G01X1470921Y1949309D02*
Y1948640D01*
G01Y1946159D02*
Y1945490D01*
G01Y1952459D02*
Y1951789D01*
G01Y1958758D02*
Y1958088D01*
G01Y1955608D02*
Y1954939D01*
G01Y1961907D02*
Y1961238D01*
G01Y1968207D02*
Y1967537D01*
G01Y1965057D02*
Y1964388D01*
G01Y1971356D02*
Y1970687D01*
G01Y1977655D02*
Y1976986D01*
G01Y1974506D02*
Y1973837D01*
G01Y1980805D02*
Y1980136D01*
G01Y1987104D02*
Y1986435D01*
G01Y1983955D02*
Y1983285D01*
G01Y1990254D02*
Y1989585D01*
G01Y1996553D02*
Y1995884D01*
G01Y1993403D02*
Y1992734D01*
G01Y1999703D02*
Y1999033D01*
G01Y2006002D02*
Y2005333D01*
G01Y2002852D02*
Y2002183D01*
G01Y2009151D02*
Y2008482D01*
G01Y2012301D02*
Y2011632D01*
G01X1470574Y1949309D02*
Y1948640D01*
G01Y1946159D02*
Y1945490D01*
G01Y1952459D02*
Y1951789D01*
G01Y1958758D02*
Y1958088D01*
G01Y1955608D02*
Y1954939D01*
G01Y1961907D02*
Y1961238D01*
G01Y1968207D02*
Y1967537D01*
G01Y1965057D02*
Y1964388D01*
G01Y1971356D02*
Y1970687D01*
G01Y1977655D02*
Y1976986D01*
G01Y1974506D02*
Y1973837D01*
G01Y1980805D02*
Y1980136D01*
G01Y1987104D02*
Y1986435D01*
G01Y1983955D02*
Y1983285D01*
G01Y1990254D02*
Y1989585D01*
G01Y1996553D02*
Y1995884D01*
G01Y1993403D02*
Y1992734D01*
G01Y1999703D02*
Y1999033D01*
G01Y2006002D02*
Y2005333D01*
G01Y2002852D02*
Y2002183D01*
G01Y2009151D02*
Y2008482D01*
G01Y2012301D02*
Y2011632D01*
G01X1469631Y1949565D02*
Y1948384D01*
G01Y1946415D02*
Y1945234D01*
G01Y1952714D02*
Y1951533D01*
G01Y1959014D02*
Y1957833D01*
G01Y1955864D02*
Y1954683D01*
G01Y1962163D02*
Y1960982D01*
G01Y1968463D02*
Y1967281D01*
G01Y1965313D02*
Y1964132D01*
G01Y1971612D02*
Y1970431D01*
G01Y1977911D02*
Y1976730D01*
G01Y1974762D02*
Y1973581D01*
G01Y1981061D02*
Y1979880D01*
G01Y1987360D02*
Y1986179D01*
G01Y1984211D02*
Y1983029D01*
G01Y1990510D02*
Y1989329D01*
G01Y1996809D02*
Y1995628D01*
G01Y1993659D02*
Y1992478D01*
G01Y1999959D02*
Y1998777D01*
G01Y2006258D02*
Y2005077D01*
G01Y2003108D02*
Y2001927D01*
G01Y2009407D02*
Y2008226D01*
G01Y2012557D02*
Y2011376D01*
G01X1469278Y1949565D02*
Y1948384D01*
G01Y1946415D02*
Y1945234D01*
G01Y1952714D02*
Y1951533D01*
G01Y1959014D02*
Y1957833D01*
G01Y1955864D02*
Y1954683D01*
G01Y1962163D02*
Y1960982D01*
G01Y1968463D02*
Y1967281D01*
G01Y1965313D02*
Y1964132D01*
G01Y1971612D02*
Y1970431D01*
G01Y1977911D02*
Y1976730D01*
G01Y1974762D02*
Y1973581D01*
G01Y1981061D02*
Y1979880D01*
G01Y1987360D02*
Y1986179D01*
G01Y1984211D02*
Y1983029D01*
G01Y1990510D02*
Y1989329D01*
G01Y1996809D02*
Y1995628D01*
G01Y1993659D02*
Y1992478D01*
G01Y1999959D02*
Y1998777D01*
G01Y2006258D02*
Y2005077D01*
G01Y2003108D02*
Y2001927D01*
G01Y2009407D02*
Y2008226D01*
G01Y2012557D02*
Y2011376D01*
G01X1467296Y1949565D02*
Y1948384D01*
G01Y1946415D02*
Y1945234D01*
G01Y1952714D02*
Y1951533D01*
G01Y1959014D02*
Y1957833D01*
G01Y1955864D02*
Y1954683D01*
G01Y1962163D02*
Y1960982D01*
G01Y1968463D02*
Y1967281D01*
G01Y1965313D02*
Y1964132D01*
G01Y1971612D02*
Y1970431D01*
G01Y1977911D02*
Y1976730D01*
G01Y1974762D02*
Y1973581D01*
G01Y1981061D02*
Y1979880D01*
G01Y1987360D02*
Y1986179D01*
G01Y1984211D02*
Y1983029D01*
G01Y1990510D02*
Y1989329D01*
G01Y1996809D02*
Y1995628D01*
G01Y1993659D02*
Y1992478D01*
G01Y1999959D02*
Y1998777D01*
G01Y2006258D02*
Y2005077D01*
G01Y2003108D02*
Y2001927D01*
G01Y2009407D02*
Y2008226D01*
G01Y2012557D02*
Y2011376D01*
G01X1467186Y1949565D02*
Y1948384D01*
G01Y1946415D02*
Y1945234D01*
G01Y1952714D02*
Y1951533D01*
G01Y1959014D02*
Y1957833D01*
G01Y1955864D02*
Y1954683D01*
G01Y1962163D02*
Y1960982D01*
G01Y1968463D02*
Y1967281D01*
G01Y1965313D02*
Y1964132D01*
G01Y1971612D02*
Y1970431D01*
G01Y1977911D02*
Y1976730D01*
G01Y1974762D02*
Y1973581D01*
G01Y1981061D02*
Y1979880D01*
G01Y1987360D02*
Y1986179D01*
G01Y1984211D02*
Y1983029D01*
G01Y1990510D02*
Y1989329D01*
G01Y1996809D02*
Y1995628D01*
G01Y1993659D02*
Y1992478D01*
G01Y1999959D02*
Y1998777D01*
G01Y2006258D02*
Y2005077D01*
G01Y2003108D02*
Y2001927D01*
G01Y2009407D02*
Y2008226D01*
G01Y2012557D02*
Y2011376D01*
G01X1458405Y1949565D02*
Y1948384D01*
G01Y1946415D02*
Y1945234D01*
G01Y1952714D02*
Y1951533D01*
G01Y1959014D02*
Y1957833D01*
G01Y1955864D02*
Y1954683D01*
G01Y1962163D02*
Y1960982D01*
G01Y1968463D02*
Y1967281D01*
G01Y1965313D02*
Y1964132D01*
G01Y1971612D02*
Y1970431D01*
G01Y1977911D02*
Y1976730D01*
G01Y1974762D02*
Y1973581D01*
G01Y1981061D02*
Y1979880D01*
G01Y1987360D02*
Y1986179D01*
G01Y1984211D02*
Y1983029D01*
G01Y1990510D02*
Y1989329D01*
G01Y1996809D02*
Y1995628D01*
G01Y1993659D02*
Y1992478D01*
G01Y1999959D02*
Y1998777D01*
G01Y2006258D02*
Y2005077D01*
G01Y2003108D02*
Y2001927D01*
G01Y2009407D02*
Y2008226D01*
G01Y2012557D02*
Y2011376D01*
G01X1458295Y1949565D02*
Y1948384D01*
G01Y1946415D02*
Y1945234D01*
G01Y1952714D02*
Y1951533D01*
G01Y1959014D02*
Y1957833D01*
G01Y1955864D02*
Y1954683D01*
G01Y1962163D02*
Y1960982D01*
G01Y1968463D02*
Y1967281D01*
G01Y1965313D02*
Y1964132D01*
G01Y1971612D02*
Y1970431D01*
G01Y1977911D02*
Y1976730D01*
G01Y1974762D02*
Y1973581D01*
G01Y1981061D02*
Y1979880D01*
G01Y1987360D02*
Y1986179D01*
G01Y1984211D02*
Y1983029D01*
G01Y1990510D02*
Y1989329D01*
G01Y1996809D02*
Y1995628D01*
G01Y1993659D02*
Y1992478D01*
G01Y1999959D02*
Y1998777D01*
G01Y2006258D02*
Y2005077D01*
G01Y2003108D02*
Y2001927D01*
G01Y2009407D02*
Y2008226D01*
G01Y2012557D02*
Y2011376D01*
G01X1457929Y1949565D02*
Y1948384D01*
G01Y1946415D02*
Y1945234D01*
G01Y1952714D02*
Y1951533D01*
G01Y1959014D02*
Y1957833D01*
G01Y1955864D02*
Y1954683D01*
G01Y1962163D02*
Y1960982D01*
G01Y1968463D02*
Y1967281D01*
G01Y1965313D02*
Y1964132D01*
G01Y1971612D02*
Y1970431D01*
G01Y1977911D02*
Y1976730D01*
G01Y1974762D02*
Y1973581D01*
G01Y1981061D02*
Y1979880D01*
G01Y1987360D02*
Y1986179D01*
G01Y1984211D02*
Y1983029D01*
G01Y1990510D02*
Y1989329D01*
G01Y1996809D02*
Y1995628D01*
G01Y1993659D02*
Y1992478D01*
G01Y1999959D02*
Y1998777D01*
G01Y2006258D02*
Y2005077D01*
G01Y2003108D02*
Y2001927D01*
G01Y2009407D02*
Y2008226D01*
G01Y2012557D02*
Y2011376D01*
G01X1457732Y1945234D02*
Y1944644D01*
G01Y1943856D02*
Y1943266D01*
G01Y1948384D02*
Y1947793D01*
G01Y1950155D02*
Y1949565D01*
G01Y1947006D02*
Y1946415D01*
G01Y1954683D02*
Y1954092D01*
G01Y1951533D02*
Y1950943D01*
G01Y1953305D02*
Y1952714D01*
G01Y1957833D02*
Y1957242D01*
G01Y1959604D02*
Y1959014D01*
G01Y1956455D02*
Y1955864D01*
G01Y1964132D02*
Y1963541D01*
G01Y1960982D02*
Y1960392D01*
G01Y1962754D02*
Y1962163D01*
G01Y1967281D02*
Y1966691D01*
G01Y1969053D02*
Y1968463D01*
G01Y1965903D02*
Y1965313D01*
G01Y1973581D02*
Y1972990D01*
G01Y1970431D02*
Y1969840D01*
G01Y1972203D02*
Y1971612D01*
G01Y1976730D02*
Y1976140D01*
G01Y1978502D02*
Y1977911D01*
G01Y1975352D02*
Y1974762D01*
G01Y1983029D02*
Y1982439D01*
G01Y1979880D02*
Y1979289D01*
G01Y1981651D02*
Y1981061D01*
G01Y1986179D02*
Y1985588D01*
G01Y1987951D02*
Y1987360D01*
G01Y1984801D02*
Y1984211D01*
G01Y1992478D02*
Y1991888D01*
G01Y1989329D02*
Y1988738D01*
G01Y1991100D02*
Y1990510D01*
G01Y1995628D02*
Y1995037D01*
G01Y1997400D02*
Y1996809D01*
G01Y1994250D02*
Y1993659D01*
G01Y2001927D02*
Y2001337D01*
G01Y1998777D02*
Y1998187D01*
G01Y2000549D02*
Y1999959D01*
G01Y2005077D02*
Y2004486D01*
G01Y2006848D02*
Y2006258D01*
G01Y2003699D02*
Y2003108D01*
G01Y2011376D02*
Y2010785D01*
G01Y2008226D02*
Y2007636D01*
G01Y2009998D02*
Y2009407D01*
G01X1457535Y1945234D02*
Y1944644D01*
G01Y1943856D02*
Y1943266D01*
G01Y1948384D02*
Y1947793D01*
G01Y1950155D02*
Y1949565D01*
G01Y1947006D02*
Y1946415D01*
G01Y1954683D02*
Y1954092D01*
G01Y1951533D02*
Y1950943D01*
G01Y1953305D02*
Y1952714D01*
G01Y1957833D02*
Y1957242D01*
G01Y1959604D02*
Y1959014D01*
G01Y1956455D02*
Y1955864D01*
G01Y1964132D02*
Y1963541D01*
G01Y1960982D02*
Y1960392D01*
G01Y1962754D02*
Y1962163D01*
G01Y1967281D02*
Y1966691D01*
G01Y1969053D02*
Y1968463D01*
G01Y1965903D02*
Y1965313D01*
G01Y1973581D02*
Y1972990D01*
G01Y1970431D02*
Y1969840D01*
G01Y1972203D02*
Y1971612D01*
G01Y1976730D02*
Y1976140D01*
G01Y1978502D02*
Y1977911D01*
G01Y1975352D02*
Y1974762D01*
G01Y1983029D02*
Y1982439D01*
G01Y1979880D02*
Y1979289D01*
G01Y1981651D02*
Y1981061D01*
G01Y1986179D02*
Y1985588D01*
G01Y1987951D02*
Y1987360D01*
G01Y1984801D02*
Y1984211D01*
G01Y1992478D02*
Y1991888D01*
G01Y1989329D02*
Y1988738D01*
G01Y1991100D02*
Y1990510D01*
G01Y1995628D02*
Y1995037D01*
G01Y1997400D02*
Y1996809D01*
G01Y1994250D02*
Y1993659D01*
G01Y2001927D02*
Y2001337D01*
G01Y1998777D02*
Y1998187D01*
G01Y2000549D02*
Y1999959D01*
G01Y2005077D02*
Y2004486D01*
G01Y2006848D02*
Y2006258D01*
G01Y2003699D02*
Y2003108D01*
G01Y2011376D02*
Y2010785D01*
G01Y2008226D02*
Y2007636D01*
G01Y2009998D02*
Y2009407D01*
G01X1444212Y1949762D02*
Y1948187D01*
G01Y1946612D02*
Y1945037D01*
G01Y1952911D02*
Y1951337D01*
G01Y1959211D02*
Y1957636D01*
G01Y1956061D02*
Y1954486D01*
G01Y1962360D02*
Y1960785D01*
G01Y1968659D02*
Y1967085D01*
G01Y1965510D02*
Y1963935D01*
G01Y1971809D02*
Y1970234D01*
G01Y1978108D02*
Y1976533D01*
G01Y1974959D02*
Y1973384D01*
G01Y1981258D02*
Y1979683D01*
G01Y1987557D02*
Y1985982D01*
G01Y1984407D02*
Y1982833D01*
G01Y1990707D02*
Y1989132D01*
G01Y1997006D02*
Y1995431D01*
G01Y1993856D02*
Y1992281D01*
G01Y2000155D02*
Y1998581D01*
G01Y2006455D02*
Y2004880D01*
G01Y2003305D02*
Y2001730D01*
G01Y2009604D02*
Y2008029D01*
G01Y2012754D02*
Y2011179D01*
G01X1442684Y1949554D02*
Y1948394D01*
G01Y1946405D02*
Y1945245D01*
G01Y1952704D02*
Y1951544D01*
G01Y1959003D02*
Y1957843D01*
G01Y1955853D02*
Y1954694D01*
G01Y1962153D02*
Y1960993D01*
G01Y1968452D02*
Y1967292D01*
G01Y1965302D02*
Y1964142D01*
G01Y1971601D02*
Y1970442D01*
G01Y1977901D02*
Y1976741D01*
G01Y1974751D02*
Y1973591D01*
G01Y1981050D02*
Y1979890D01*
G01Y1987350D02*
Y1986190D01*
G01Y1984200D02*
Y1983040D01*
G01Y1990499D02*
Y1989339D01*
G01Y1996798D02*
Y1995638D01*
G01Y1993649D02*
Y1992489D01*
G01Y1999948D02*
Y1998788D01*
G01Y2006247D02*
Y2005087D01*
G01Y2003098D02*
Y2001938D01*
G01Y2009397D02*
Y2008237D01*
G01Y2012546D02*
Y2011387D01*
G01X1469507Y1945490D02*
X1469278Y1945234D01*
G01X1469507Y1948640D02*
X1469278Y1948384D01*
G01X1469507Y1951789D02*
X1469278Y1951533D01*
G01X1469507Y1954939D02*
X1469278Y1954683D01*
G01X1469507Y1958088D02*
X1469278Y1957833D01*
G01X1469855Y1945490D02*
X1469636Y1945220D01*
G01X1469855Y1948640D02*
X1469636Y1948370D01*
G01X1469855Y1951789D02*
X1469636Y1951519D01*
G01X1469855Y1954939D02*
X1469636Y1954669D01*
G01X1469855Y1958088D02*
X1469636Y1957818D01*
G01X1469855Y1961238D02*
X1469636Y1960968D01*
G01X1469855Y1964388D02*
X1469636Y1964118D01*
G01X1469855Y1967537D02*
X1469636Y1967267D01*
G01X1469855Y1970687D02*
X1469636Y1970417D01*
G01X1469855Y1973837D02*
X1469636Y1973566D01*
G01X1469855Y1976986D02*
X1469636Y1976716D01*
G01X1443073Y1943463D02*
X1442684Y1943255D01*
G01X1443073Y1946612D02*
X1442684Y1946405D01*
G01X1443073Y1949762D02*
X1442684Y1949554D01*
G01X1443073Y1952911D02*
X1442684Y1952704D01*
G01X1443073Y1956061D02*
X1442684Y1955853D01*
G01X1443073Y1959211D02*
X1442684Y1959003D01*
G01X1443073Y1962360D02*
X1442684Y1962153D01*
G01X1443073Y1965510D02*
X1442684Y1965302D01*
G01X1443073Y1968659D02*
X1442684Y1968452D01*
G01X1443073Y1971809D02*
X1442684Y1971601D01*
G01X1443073Y1974959D02*
X1442684Y1974751D01*
G01X1443073Y1978108D02*
X1442684Y1977901D01*
G01X1443073Y1981258D02*
X1442684Y1981050D01*
G01X1443073Y1984407D02*
X1442684Y1984200D01*
G01X1443073Y1987557D02*
X1442684Y1987350D01*
G01X1443073Y1990707D02*
X1442684Y1990499D01*
G01X1443073Y1993856D02*
X1442684Y1993649D01*
G01X1443073Y1997006D02*
X1442684Y1996798D01*
G01X1443073Y2000155D02*
X1442684Y1999948D01*
G01X1443073Y2003305D02*
X1442684Y2003098D01*
G01X1443073Y2006455D02*
X1442684Y2006247D01*
G01X1443073Y2009604D02*
X1442684Y2009397D01*
G01X1443243Y1943463D02*
X1442772Y1943167D01*
G01X1442684Y1943255D02*
X1442543Y1943167D01*
G01X1443243Y1946612D02*
X1442772Y1946317D01*
G01X1442684Y1946405D02*
X1442543Y1946317D01*
G01X1443243Y1949762D02*
X1442772Y1949466D01*
G01X1442684Y1949554D02*
X1442543Y1949466D01*
G01X1443243Y1952911D02*
X1442772Y1952616D01*
G01X1442684Y1952704D02*
X1442543Y1952616D01*
G01X1443243Y1956061D02*
X1442772Y1955766D01*
G01X1442684Y1955853D02*
X1442543Y1955766D01*
G01X1443243Y1959211D02*
X1442772Y1958915D01*
G01X1442684Y1959003D02*
X1442543Y1958915D01*
G01X1443243Y1962360D02*
X1442772Y1962065D01*
G01X1442684Y1962153D02*
X1442543Y1962065D01*
G01X1443243Y1965510D02*
X1442772Y1965214D01*
G01X1442684Y1965302D02*
X1442543Y1965214D01*
G01X1443243Y1968659D02*
X1442772Y1968364D01*
G01X1442684Y1968452D02*
X1442543Y1968364D01*
G01X1443243Y1971809D02*
X1442772Y1971514D01*
G01X1442684Y1971601D02*
X1442543Y1971514D01*
G01X1443243Y1974959D02*
X1442772Y1974663D01*
G01X1442684Y1974751D02*
X1442543Y1974663D01*
G01X1443243Y1978108D02*
X1442772Y1977813D01*
G01X1442684Y1977901D02*
X1442543Y1977813D01*
G01X1443243Y1981258D02*
X1442772Y1980963D01*
G01X1442684Y1981050D02*
X1442543Y1980963D01*
G01X1443243Y1984407D02*
X1442772Y1984112D01*
G01X1442684Y1984200D02*
X1442543Y1984112D01*
G01X1443243Y1987557D02*
X1442772Y1987262D01*
G01X1442684Y1987350D02*
X1442543Y1987262D01*
G01X1443243Y1990707D02*
X1442772Y1990411D01*
G01X1442684Y1990499D02*
X1442543Y1990411D01*
G01X1443243Y1993856D02*
X1442772Y1993561D01*
G01X1442684Y1993649D02*
X1442543Y1993561D01*
G01X1443243Y1997006D02*
X1442772Y1996711D01*
G01X1442684Y1996798D02*
X1442543Y1996711D01*
G01X1443243Y2000155D02*
X1442772Y1999860D01*
G01X1442684Y1999948D02*
X1442543Y1999860D01*
G01X1443243Y2003305D02*
X1442772Y2003010D01*
G01X1442684Y2003098D02*
X1442543Y2003010D01*
G01X1443243Y2006455D02*
X1442772Y2006159D01*
G01X1442684Y2006247D02*
X1442543Y2006159D01*
G01X1443243Y2009604D02*
X1442772Y2009309D01*
G01X1442684Y2009397D02*
X1442543Y2009309D01*
G01X1469507Y1961238D02*
X1469278Y1960982D01*
G01X1469507Y1964388D02*
X1469278Y1964132D01*
G01X1469507Y1967537D02*
X1469278Y1967281D01*
G01X1469507Y1970687D02*
X1469278Y1970431D01*
G01X1469507Y1973837D02*
X1469278Y1973581D01*
G01X1469507Y1976986D02*
X1469278Y1976730D01*
G01X1469507Y1980136D02*
X1469278Y1979880D01*
G01X1469507Y1983285D02*
X1469278Y1983029D01*
G01X1469507Y1986435D02*
X1469278Y1986179D01*
G01X1469507Y1989585D02*
X1469278Y1989329D01*
G01X1469507Y1992734D02*
X1469278Y1992478D01*
G01X1469507Y1995884D02*
X1469278Y1995628D01*
G01X1469507Y1999033D02*
X1469278Y1998777D01*
G01X1469507Y2002183D02*
X1469278Y2001927D01*
G01X1469507Y2005333D02*
X1469278Y2005077D01*
G01X1469507Y2008482D02*
X1469278Y2008226D01*
G01X1469507Y2011632D02*
X1469278Y2011376D01*
G01X1469855Y1980136D02*
X1469636Y1979866D01*
G01X1469855Y1983285D02*
X1469636Y1983015D01*
G01X1469855Y1986435D02*
X1469636Y1986165D01*
G01X1469855Y1989585D02*
X1469636Y1989315D01*
G01X1469855Y1992734D02*
X1469636Y1992464D01*
G01X1469855Y1995884D02*
X1469636Y1995614D01*
G01X1469855Y1999033D02*
X1469636Y1998763D01*
G01X1469855Y2002183D02*
X1469636Y2001913D01*
G01X1469855Y2005333D02*
X1469636Y2005063D01*
G01X1469855Y2008482D02*
X1469636Y2008212D01*
G01X1469855Y2011632D02*
X1469636Y2011362D01*
G01X1439047Y2014662D02*
X1442543Y2014624D01*
G01X1437751Y2014676D02*
X1441007Y2014640D01*
G01X1438785Y2014662D02*
X1436420Y2014688D01*
G01X1441235Y2014640D02*
X1442772Y2014624D01*
G01X1441235Y2014640D02*
X1438785Y2014662D01*
G01X1437751Y2014676D02*
X1436420Y2014688D01*
G01X1441235Y2015592D02*
X1441007D01*
G01X1439047Y2015570D02*
X1438785D01*
G01X1439047Y2014662D02*
X1438785D01*
G01X1441235Y2014640D02*
X1441007D01*
G01X1441235Y2012442D02*
X1441007D01*
G01X1439047Y2012421D02*
X1438785D01*
G01X1440094Y2015582D02*
X1438785Y2015570D01*
G01X1441235Y2015592D02*
X1440094Y2015582D01*
G01Y2012432D02*
X1438785Y2012421D01*
G01X1441235Y2012442D02*
X1440094Y2012432D01*
G01X1437751Y2015556D02*
X1436420Y2015544D01*
G01X1437751Y2012406D02*
X1436420Y2012394D01*
G01X1442543Y2015608D02*
X1441007Y2015592D01*
G01X1442543Y2015608D02*
X1439047Y2015570D01*
G01X1441235Y2015592D02*
X1442772Y2015608D01*
G01X1442543Y2012459D02*
X1441007Y2012442D01*
G01X1442543Y2012459D02*
X1439047Y2012421D01*
G01X1441235Y2012442D02*
X1442772Y2012459D01*
G01X1439047Y2015570D02*
X1440094Y2015582D01*
G01X1438785Y2015570D02*
X1436420Y2015544D01*
G01X1437751Y2015556D02*
X1439047Y2015570D01*
G01Y2012421D02*
X1440094Y2012432D01*
G01X1438785Y2012421D02*
X1436420Y2012394D01*
G01X1437751Y2012406D02*
X1439047Y2012421D01*
G01X1441235Y2015592D02*
Y2014640D01*
G01X1441007Y2015592D02*
Y2014640D01*
G01X1439047Y2015570D02*
Y2014662D01*
G01X1438785Y2015570D02*
Y2014662D01*
G01X1437751Y2015550D02*
Y2014682D01*
G01X1436420Y2015544D02*
Y2014688D01*
G01X1439797Y2084342D02*
X1438792Y2084178D01*
G01X1438122Y2082865D02*
X1437284Y2082701D01*
G01X1438122Y2082045D02*
X1437452Y2081881D01*
G01X1438122Y2076960D02*
X1437452Y2076796D01*
G01X1439047Y2083953D02*
X1442543Y2083915D01*
G01X1437751Y2083968D02*
X1441007Y2083932D01*
G01X1439047Y2080804D02*
X1442543Y2080766D01*
G01X1437751Y2080818D02*
X1441007Y2080782D01*
G01X1439047Y2077654D02*
X1442543Y2077616D01*
G01X1437751Y2077668D02*
X1441007Y2077633D01*
G01X1439047Y2074504D02*
X1442543Y2074466D01*
G01X1437751Y2074519D02*
X1441007Y2074483D01*
G01X1439047Y2071355D02*
X1442543Y2071317D01*
G01X1437751Y2071369D02*
X1441007Y2071333D01*
G01X1439047Y2068205D02*
X1442543Y2068167D01*
G01X1437751Y2068220D02*
X1441007Y2068184D01*
G01X1439047Y2065056D02*
X1442543Y2065018D01*
G01X1437751Y2065070D02*
X1441007Y2065034D01*
G01X1439047Y2061906D02*
X1442543Y2061868D01*
G01X1437751Y2061920D02*
X1441007Y2061884D01*
G01X1439047Y2058756D02*
X1442543Y2058718D01*
G01X1437751Y2058771D02*
X1441007Y2058735D01*
G01X1439047Y2055607D02*
X1442543Y2055569D01*
G01X1437751Y2055621D02*
X1441007Y2055585D01*
G01X1439047Y2052457D02*
X1442543Y2052419D01*
G01X1437751Y2052472D02*
X1441007Y2052436D01*
G01X1438785Y2083953D02*
X1436420Y2083979D01*
G01X1438785Y2080804D02*
X1436420Y2080830D01*
G01X1438785Y2077654D02*
X1436420Y2077680D01*
G01X1438785Y2074504D02*
X1436420Y2074531D01*
G01X1438785Y2071355D02*
X1436420Y2071381D01*
G01X1438785Y2068205D02*
X1436420Y2068231D01*
G01X1438785Y2065056D02*
X1436420Y2065082D01*
G01X1438785Y2061906D02*
X1436420Y2061932D01*
G01X1438785Y2058756D02*
X1436420Y2058783D01*
G01X1438785Y2055607D02*
X1436420Y2055633D01*
G01X1438785Y2052457D02*
X1436420Y2052483D01*
G01X1440094Y2049296D02*
X1442543Y2049270D01*
G01X1441235Y2083932D02*
X1442772Y2083915D01*
G01X1441235Y2080782D02*
X1442772Y2080766D01*
G01X1441235Y2077633D02*
X1442772Y2077616D01*
G01X1441235Y2074483D02*
X1442772Y2074466D01*
G01X1441235Y2071333D02*
X1442772Y2071317D01*
G01X1441235Y2068184D02*
X1442772Y2068167D01*
G01X1441235Y2065034D02*
X1442772Y2065018D01*
G01X1441235Y2061884D02*
X1442772Y2061868D01*
G01X1441235Y2058735D02*
X1442772Y2058718D01*
G01X1441235Y2055585D02*
X1442772Y2055569D01*
G01X1441235Y2052436D02*
X1442772Y2052419D01*
G01X1441235Y2049286D02*
X1442772Y2049270D01*
G01X1441235Y2083932D02*
X1438785Y2083953D01*
G01X1437751Y2083968D02*
X1436420Y2083979D01*
G01X1441235Y2080782D02*
X1438785Y2080804D01*
G01X1437751Y2080818D02*
X1436420Y2080830D01*
G01X1441235Y2077633D02*
X1438785Y2077654D01*
G01X1437751Y2077668D02*
X1436420Y2077680D01*
G01X1441235Y2074483D02*
X1438785Y2074504D01*
G01X1437751Y2074519D02*
X1436420Y2074531D01*
G01X1441235Y2071333D02*
X1438785Y2071355D01*
G01X1437751Y2071369D02*
X1436420Y2071381D01*
G01X1441235Y2068184D02*
X1438785Y2068205D01*
G01X1437751Y2068220D02*
X1436420Y2068231D01*
G01X1441235Y2065034D02*
X1438785Y2065056D01*
G01X1437751Y2065070D02*
X1436420Y2065082D01*
G01X1441235Y2061884D02*
X1438785Y2061906D01*
G01X1437751Y2061920D02*
X1436420Y2061932D01*
G01X1441235Y2058735D02*
X1438785Y2058756D01*
G01X1437751Y2058771D02*
X1436420Y2058783D01*
G01X1441235Y2055585D02*
X1438785Y2055607D01*
G01X1437751Y2055621D02*
X1436420Y2055633D01*
G01X1441235Y2052436D02*
X1438785Y2052457D01*
G01X1437751Y2052472D02*
X1436420Y2052483D01*
G01X1441235Y2049286D02*
X1438785Y2049308D01*
G01X1437751Y2049322D02*
X1436420Y2049334D01*
G01X1439047Y2083953D02*
X1438785D01*
G01X1441235Y2083932D02*
X1441007D01*
G01X1441472Y2082865D02*
X1438122D01*
G01X1441472Y2082045D02*
X1438122D01*
G01X1441235Y2081733D02*
X1441007D01*
G01X1439047Y2081712D02*
X1438785D01*
G01X1439047Y2080804D02*
X1438785D01*
G01X1441235Y2080782D02*
X1441007D01*
G01X1436949Y2079092D02*
X1433598D01*
G01X1441472D02*
X1437619D01*
G01X1441235Y2078584D02*
X1441007D01*
G01X1439047Y2078562D02*
X1438785D01*
G01X1441472Y2078272D02*
X1433598D01*
G01X1439047Y2077654D02*
X1438785D01*
G01X1441235Y2077633D02*
X1441007D01*
G01X1439462Y2076960D02*
X1438122D01*
G01X1439294Y2076140D02*
X1438289D01*
G01X1441235Y2075434D02*
X1441007D01*
G01X1439047Y2075413D02*
X1438785D01*
G01X1439047Y2074504D02*
X1438785D01*
G01X1441235Y2074483D02*
X1441007D01*
G01X1437117Y2072531D02*
X1436111D01*
G01X1439629D02*
X1437954D01*
G01X1444153D02*
X1440467D01*
G01X1441235Y2072285D02*
X1441007D01*
G01X1439047Y2072263D02*
X1438785D01*
G01X1444153Y2071711D02*
X1436111D01*
G01X1439047Y2071355D02*
X1438785D01*
G01X1441235Y2071333D02*
X1441007D01*
G01X1441472Y2070398D02*
X1437452D01*
G01X1441472Y2069578D02*
X1437452D01*
G01X1441235Y2069135D02*
X1441007D01*
G01X1439047Y2069113D02*
X1438785D01*
G01X1439047Y2068205D02*
X1438785D01*
G01X1441235Y2068184D02*
X1441007D01*
G01X1441472Y2067774D02*
X1437452D01*
G01X1441472Y2066953D02*
X1437452D01*
G01X1441235Y2065985D02*
X1441007D01*
G01X1439047Y2065964D02*
X1438785D01*
G01X1436614Y2065149D02*
X1436111D01*
G01X1441472D02*
X1437284D01*
G01X1439047Y2065056D02*
X1438785D01*
G01X1441235Y2065034D02*
X1441007D01*
G01X1441472Y2064329D02*
X1436111D01*
G01X1441235Y2062836D02*
X1441007D01*
G01X1439047Y2062814D02*
X1438785D01*
G01X1439047Y2061906D02*
X1438785D01*
G01X1441235Y2061884D02*
X1441007D01*
G01X1441235Y2059686D02*
X1441007D01*
G01X1439047Y2059665D02*
X1438785D01*
G01X1439047Y2058756D02*
X1438785D01*
G01X1441235Y2058735D02*
X1441007D01*
G01X1441235Y2056537D02*
X1441007D01*
G01X1439047Y2056515D02*
X1438785D01*
G01X1439047Y2055607D02*
X1438785D01*
G01X1441235Y2055585D02*
X1441007D01*
G01X1441235Y2053387D02*
X1441007D01*
G01X1439047Y2053365D02*
X1438785D01*
G01X1439047Y2052457D02*
X1438785D01*
G01X1441235Y2052436D02*
X1441007D01*
G01X1441235Y2050237D02*
X1441007D01*
G01X1439047Y2050216D02*
X1438785D01*
G01X1439047Y2049308D02*
X1438785D01*
G01X1441235Y2049286D02*
X1441007D01*
G01X1441235Y2047088D02*
X1441007D01*
G01X1439047Y2047066D02*
X1438785D01*
G01X1439047Y2046158D02*
X1438785D01*
G01X1441235Y2046136D02*
X1441007D01*
G01X1441235Y2043938D02*
X1441007D01*
G01X1439047Y2043917D02*
X1438785D01*
G01X1440094Y2081723D02*
X1438785Y2081712D01*
G01X1441235Y2081733D02*
X1440094Y2081723D01*
G01Y2078574D02*
X1438785Y2078562D01*
G01X1441235Y2078584D02*
X1440094Y2078574D01*
G01Y2075424D02*
X1438785Y2075413D01*
G01X1441235Y2075434D02*
X1440094Y2075424D01*
G01Y2072275D02*
X1438785Y2072263D01*
G01X1441235Y2072285D02*
X1440094Y2072275D01*
G01Y2069125D02*
X1438785Y2069113D01*
G01X1441235Y2069135D02*
X1440094Y2069125D01*
G01Y2065975D02*
X1438785Y2065964D01*
G01X1441235Y2065985D02*
X1440094Y2065975D01*
G01Y2062826D02*
X1438785Y2062814D01*
G01X1441235Y2062836D02*
X1440094Y2062826D01*
G01Y2059676D02*
X1438785Y2059665D01*
G01X1441235Y2059686D02*
X1440094Y2059676D01*
G01Y2056527D02*
X1438785Y2056515D01*
G01X1441235Y2056537D02*
X1440094Y2056527D01*
G01Y2053377D02*
X1438785Y2053365D01*
G01X1441235Y2053387D02*
X1440094Y2053377D01*
G01Y2050227D02*
X1438785Y2050216D01*
G01X1441235Y2050237D02*
X1440094Y2050227D01*
G01Y2047078D02*
X1438785Y2047066D01*
G01X1441235Y2047088D02*
X1440094Y2047078D01*
G01Y2043928D02*
X1438785Y2043917D01*
G01X1441235Y2043938D02*
X1440094Y2043928D01*
G01Y2040779D02*
X1438785Y2040767D01*
G01X1441235Y2040789D02*
X1440094Y2040779D01*
G01X1437751Y2081698D02*
X1436420Y2081686D01*
G01X1437751Y2078548D02*
X1436420Y2078536D01*
G01X1437751Y2075398D02*
X1436420Y2075387D01*
G01X1437751Y2072249D02*
X1436420Y2072237D01*
G01X1437751Y2069099D02*
X1436420Y2069087D01*
G01X1437751Y2065950D02*
X1436420Y2065938D01*
G01X1437751Y2062800D02*
X1436420Y2062788D01*
G01X1437751Y2059650D02*
X1436420Y2059639D01*
G01X1437751Y2056501D02*
X1436420Y2056489D01*
G01X1437751Y2053351D02*
X1436420Y2053339D01*
G01X1437751Y2050202D02*
X1436420Y2050190D01*
G01X1437751Y2047052D02*
X1436420Y2047040D01*
G01X1437751Y2043902D02*
X1436420Y2043891D01*
G01X1437751Y2040753D02*
X1436420Y2040741D01*
G01X1442543Y2081750D02*
X1441007Y2081733D01*
G01X1442543Y2081750D02*
X1439047Y2081712D01*
G01X1441235Y2081733D02*
X1442772Y2081750D01*
G01X1442543Y2078600D02*
X1441007Y2078584D01*
G01X1442543Y2078600D02*
X1439047Y2078562D01*
G01X1441235Y2078584D02*
X1442772Y2078600D01*
G01X1442543Y2075451D02*
X1441007Y2075434D01*
G01X1442543Y2075451D02*
X1439047Y2075413D01*
G01X1441235Y2075434D02*
X1442772Y2075451D01*
G01X1442543Y2072301D02*
X1441007Y2072285D01*
G01X1442543Y2072301D02*
X1439047Y2072263D01*
G01X1441235Y2072285D02*
X1442772Y2072301D01*
G01X1442543Y2069151D02*
X1441007Y2069135D01*
G01X1442543Y2069151D02*
X1439047Y2069114D01*
G01X1441235Y2069135D02*
X1442772Y2069151D01*
G01X1442543Y2066002D02*
X1441007Y2065985D01*
G01X1442543Y2066002D02*
X1439047Y2065964D01*
G01X1441235Y2065985D02*
X1442772Y2066002D01*
G01X1442543Y2062852D02*
X1441007Y2062836D01*
G01X1442543Y2062852D02*
X1439047Y2062814D01*
G01X1441235Y2062836D02*
X1442772Y2062852D01*
G01X1442543Y2059703D02*
X1441007Y2059686D01*
G01X1442543Y2059703D02*
X1439047Y2059665D01*
G01X1441235Y2059686D02*
X1442772Y2059703D01*
G01X1442543Y2056553D02*
X1441007Y2056537D01*
G01X1442543Y2056553D02*
X1439047Y2056515D01*
G01X1441235Y2056537D02*
X1442772Y2056553D01*
G01X1442543Y2053403D02*
X1441007Y2053387D01*
G01X1442543Y2053403D02*
X1439047Y2053365D01*
G01X1441235Y2053387D02*
X1442772Y2053403D01*
G01X1442543Y2050254D02*
X1441007Y2050237D01*
G01X1442543Y2050254D02*
X1439047Y2050216D01*
G01X1441235Y2050237D02*
X1442772Y2050254D01*
G01X1442543Y2047104D02*
X1441007Y2047088D01*
G01X1442543Y2047104D02*
X1439047Y2047066D01*
G01X1441235Y2047088D02*
X1442772Y2047104D01*
G01X1442543Y2043955D02*
X1441007Y2043938D01*
G01X1442543Y2043955D02*
X1439047Y2043917D01*
G01X1441235Y2043938D02*
X1442772Y2043955D01*
G01X1442543Y2040805D02*
X1441007Y2040789D01*
G01X1442543Y2040805D02*
X1439047Y2040767D01*
G01X1441235Y2040789D02*
X1442772Y2040805D01*
G01X1439047Y2081712D02*
X1440094Y2081723D01*
G01X1438785Y2081712D02*
X1436420Y2081686D01*
G01X1437751Y2081698D02*
X1439047Y2081712D01*
G01Y2078562D02*
X1440094Y2078574D01*
G01X1438785Y2078562D02*
X1436420Y2078536D01*
G01X1437751Y2078548D02*
X1439047Y2078562D01*
G01Y2075413D02*
X1440094Y2075424D01*
G01X1438785Y2075413D02*
X1436420Y2075387D01*
G01X1437751Y2075398D02*
X1439047Y2075413D01*
G01Y2072263D02*
X1440094Y2072275D01*
G01X1438785Y2072263D02*
X1436420Y2072237D01*
G01X1437751Y2072249D02*
X1439047Y2072263D01*
G01Y2069113D02*
X1440094Y2069125D01*
G01X1438785Y2069113D02*
X1436420Y2069087D01*
G01X1437751Y2069099D02*
X1439047Y2069113D01*
G01Y2065964D02*
X1440094Y2065975D01*
G01X1438785Y2065964D02*
X1436420Y2065938D01*
G01X1437751Y2065950D02*
X1439047Y2065964D01*
G01Y2062814D02*
X1440094Y2062826D01*
G01X1438785Y2062814D02*
X1436420Y2062788D01*
G01X1437751Y2062800D02*
X1439047Y2062814D01*
G01Y2059665D02*
X1440094Y2059676D01*
G01X1438785Y2059665D02*
X1436420Y2059639D01*
G01X1437751Y2059650D02*
X1439047Y2059665D01*
G01Y2056515D02*
X1440094Y2056527D01*
G01X1438785Y2056515D02*
X1436420Y2056489D01*
G01X1437751Y2056501D02*
X1439047Y2056515D01*
G01Y2053365D02*
X1440094Y2053377D01*
G01X1438785Y2053365D02*
X1436420Y2053339D01*
G01X1437751Y2053351D02*
X1439047Y2053365D01*
G01Y2050216D02*
X1440094Y2050227D01*
G01X1438785Y2050216D02*
X1436420Y2050190D01*
G01X1437751Y2050202D02*
X1439047Y2050216D01*
G01Y2047066D02*
X1440094Y2047078D01*
G01X1438785Y2047066D02*
X1436420Y2047040D01*
G01X1437751Y2047052D02*
X1439047Y2047066D01*
G01Y2043917D02*
X1440094Y2043928D01*
G01X1438785Y2043917D02*
X1436420Y2043891D01*
G01X1437751Y2043902D02*
X1439047Y2043917D01*
G01Y2040767D02*
X1440094Y2040779D01*
G01X1438785Y2040767D02*
X1436420Y2040741D01*
G01X1437751Y2040753D02*
X1439047Y2040767D01*
G01X1438792Y2084178D02*
X1437787Y2084342D01*
G01X1439047Y2049308D02*
X1440094Y2049296D01*
G01X1437751Y2049322D02*
X1441007Y2049286D01*
G01X1439047Y2046158D02*
X1442543Y2046120D01*
G01X1437751Y2046172D02*
X1441007Y2046136D01*
G01X1439047Y2043008D02*
X1442543Y2042970D01*
G01X1437751Y2043023D02*
X1441007Y2042987D01*
G01X1439047Y2039859D02*
X1442543Y2039821D01*
G01X1437751Y2039873D02*
X1441007Y2039837D01*
G01X1439047Y2036709D02*
X1442543Y2036671D01*
G01X1437751Y2036723D02*
X1441007Y2036688D01*
G01X1439047Y2033560D02*
X1442543Y2033522D01*
G01X1437751Y2033574D02*
X1441007Y2033538D01*
G01X1439047Y2030410D02*
X1442543Y2030372D01*
G01X1437751Y2030424D02*
X1441007Y2030388D01*
G01X1439047Y2027260D02*
X1442543Y2027222D01*
G01X1437751Y2027275D02*
X1441007Y2027239D01*
G01X1439047Y2024111D02*
X1442543Y2024073D01*
G01X1437751Y2024125D02*
X1441007Y2024089D01*
G01X1439047Y2020961D02*
X1442543Y2020923D01*
G01X1437751Y2020975D02*
X1441007Y2020940D01*
G01X1439047Y2017811D02*
X1442543Y2017774D01*
G01X1437751Y2017826D02*
X1441007Y2017790D01*
G01X1438785Y2049308D02*
X1436420Y2049334D01*
G01X1438785Y2046158D02*
X1436420Y2046184D01*
G01X1438785Y2043008D02*
X1436420Y2043034D01*
G01X1438785Y2039859D02*
X1436420Y2039885D01*
G01X1438785Y2036709D02*
X1436420Y2036735D01*
G01X1438785Y2033560D02*
X1436420Y2033586D01*
G01X1438785Y2030410D02*
X1436420Y2030436D01*
G01X1438785Y2027260D02*
X1436420Y2027286D01*
G01X1438785Y2024111D02*
X1436420Y2024137D01*
G01X1438785Y2020961D02*
X1436420Y2020987D01*
G01X1438785Y2017812D02*
X1436420Y2017838D01*
G01X1441235Y2046136D02*
X1442772Y2046120D01*
G01X1441235Y2042987D02*
X1442772Y2042970D01*
G01X1441235Y2039837D02*
X1442772Y2039821D01*
G01X1441235Y2036688D02*
X1442772Y2036671D01*
G01X1441235Y2033538D02*
X1442772Y2033522D01*
G01X1441235Y2030388D02*
X1442772Y2030372D01*
G01X1441235Y2027239D02*
X1442772Y2027222D01*
G01X1441235Y2024089D02*
X1442772Y2024073D01*
G01X1441235Y2020940D02*
X1442772Y2020923D01*
G01X1441235Y2017790D02*
X1442772Y2017774D01*
G01X1441235Y2046136D02*
X1438785Y2046158D01*
G01X1437751Y2046172D02*
X1436420Y2046184D01*
G01X1441235Y2042987D02*
X1438785Y2043008D01*
G01X1437751Y2043023D02*
X1436420Y2043034D01*
G01X1441235Y2039837D02*
X1438785Y2039859D01*
G01X1437751Y2039873D02*
X1436420Y2039885D01*
G01X1441235Y2036688D02*
X1438785Y2036709D01*
G01X1437751Y2036723D02*
X1436420Y2036735D01*
G01X1441235Y2033538D02*
X1438785Y2033560D01*
G01X1437751Y2033574D02*
X1436420Y2033586D01*
G01X1441235Y2030388D02*
X1438785Y2030410D01*
G01X1437751Y2030424D02*
X1436420Y2030436D01*
G01X1441235Y2027239D02*
X1438785Y2027260D01*
G01X1437751Y2027275D02*
X1436420Y2027286D01*
G01X1441235Y2024089D02*
X1438785Y2024111D01*
G01X1437751Y2024125D02*
X1436420Y2024137D01*
G01X1441235Y2020940D02*
X1438785Y2020961D01*
G01X1437751Y2020975D02*
X1436420Y2020987D01*
G01X1441235Y2017790D02*
X1438785Y2017812D01*
G01X1437751Y2017826D02*
X1436420Y2017838D01*
G01X1439047Y2043008D02*
X1438785D01*
G01X1441235Y2042987D02*
X1441007D01*
G01X1441235Y2040789D02*
X1441007D01*
G01X1439047Y2040767D02*
X1438785D01*
G01X1439047Y2039859D02*
X1438785D01*
G01X1441235Y2039837D02*
X1441007D01*
G01X1441235Y2037639D02*
X1441007D01*
G01X1439047Y2037617D02*
X1438785D01*
G01X1439047Y2036709D02*
X1438785D01*
G01X1441235Y2036688D02*
X1441007D01*
G01X1441235Y2034489D02*
X1441007D01*
G01X1439047Y2034468D02*
X1438785D01*
G01X1439047Y2033560D02*
X1438785D01*
G01X1441235Y2033538D02*
X1441007D01*
G01X1441235Y2031340D02*
X1441007D01*
G01X1439047Y2031318D02*
X1438785D01*
G01X1439047Y2030410D02*
X1438785D01*
G01X1441235Y2030388D02*
X1441007D01*
G01X1441235Y2028190D02*
X1441007D01*
G01X1439047Y2028169D02*
X1438785D01*
G01X1439047Y2027260D02*
X1438785D01*
G01X1441235Y2027239D02*
X1441007D01*
G01X1441235Y2025041D02*
X1441007D01*
G01X1439047Y2025019D02*
X1438785D01*
G01X1439047Y2024111D02*
X1438785D01*
G01X1441235Y2024089D02*
X1441007D01*
G01X1441235Y2021891D02*
X1441007D01*
G01X1439047Y2021869D02*
X1438785D01*
G01X1439047Y2020961D02*
X1438785D01*
G01X1441235Y2020940D02*
X1441007D01*
G01X1441235Y2018741D02*
X1441007D01*
G01X1439047Y2018720D02*
X1438785D01*
G01X1439047Y2017812D02*
X1438785D01*
G01X1441235Y2017790D02*
X1441007D01*
G01X1440094Y2037629D02*
X1438785Y2037617D01*
G01X1441235Y2037639D02*
X1440094Y2037629D01*
G01Y2034479D02*
X1438785Y2034468D01*
G01X1441235Y2034489D02*
X1440094Y2034479D01*
G01Y2031330D02*
X1438785Y2031318D01*
G01X1441235Y2031340D02*
X1440094Y2031330D01*
G01Y2028180D02*
X1438785Y2028169D01*
G01X1441235Y2028190D02*
X1440094Y2028180D01*
G01Y2025031D02*
X1438785Y2025019D01*
G01X1441235Y2025041D02*
X1440094Y2025031D01*
G01Y2021881D02*
X1438785Y2021869D01*
G01X1441235Y2021891D02*
X1440094Y2021881D01*
G01Y2018731D02*
X1438785Y2018720D01*
G01X1441235Y2018741D02*
X1440094Y2018731D01*
G01X1437751Y2037603D02*
X1436420Y2037591D01*
G01X1437751Y2034453D02*
X1436420Y2034442D01*
G01X1437751Y2031304D02*
X1436420Y2031292D01*
G01X1437751Y2028154D02*
X1436420Y2028142D01*
G01X1437751Y2025005D02*
X1436420Y2024993D01*
G01X1437751Y2021855D02*
X1436420Y2021843D01*
G01X1437751Y2018705D02*
X1436420Y2018694D01*
G01X1442543Y2037655D02*
X1441007Y2037639D01*
G01X1442543Y2037655D02*
X1439047Y2037617D01*
G01X1441235Y2037639D02*
X1442772Y2037655D01*
G01X1442543Y2034506D02*
X1441007Y2034489D01*
G01X1442543Y2034506D02*
X1439047Y2034468D01*
G01X1441235Y2034489D02*
X1442772Y2034506D01*
G01X1442543Y2031356D02*
X1441007Y2031340D01*
G01X1442543Y2031356D02*
X1439047Y2031318D01*
G01X1441235Y2031340D02*
X1442772Y2031356D01*
G01X1442543Y2028207D02*
X1441007Y2028190D01*
G01X1442543Y2028207D02*
X1439047Y2028169D01*
G01X1441235Y2028190D02*
X1442772Y2028207D01*
G01X1442543Y2025057D02*
X1441007Y2025041D01*
G01X1442543Y2025057D02*
X1439047Y2025019D01*
G01X1441235Y2025041D02*
X1442772Y2025057D01*
G01X1442543Y2021907D02*
X1441007Y2021891D01*
G01X1442543Y2021907D02*
X1439047Y2021869D01*
G01X1441235Y2021891D02*
X1442772Y2021907D01*
G01X1442543Y2018758D02*
X1441007Y2018741D01*
G01X1442543Y2018758D02*
X1439047Y2018720D01*
G01X1441235Y2018741D02*
X1442772Y2018758D01*
G01X1439047Y2037617D02*
X1440094Y2037629D01*
G01X1438785Y2037617D02*
X1436420Y2037591D01*
G01X1437751Y2037603D02*
X1439047Y2037617D01*
G01Y2034468D02*
X1440094Y2034479D01*
G01X1438785Y2034468D02*
X1436420Y2034442D01*
G01X1437751Y2034453D02*
X1439047Y2034468D01*
G01Y2031318D02*
X1440094Y2031330D01*
G01X1438785Y2031318D02*
X1436420Y2031292D01*
G01X1437751Y2031304D02*
X1439047Y2031318D01*
G01Y2028169D02*
X1440094Y2028180D01*
G01X1438785Y2028169D02*
X1436420Y2028142D01*
G01X1437751Y2028154D02*
X1439047Y2028169D01*
G01Y2025019D02*
X1440094Y2025031D01*
G01X1438785Y2025019D02*
X1436420Y2024993D01*
G01X1437751Y2025005D02*
X1439047Y2025019D01*
G01Y2021869D02*
X1440094Y2021881D01*
G01X1438785Y2021869D02*
X1436420Y2021843D01*
G01X1437751Y2021855D02*
X1439047Y2021869D01*
G01Y2018720D02*
X1440094Y2018731D01*
G01X1438785Y2018720D02*
X1436420Y2018694D01*
G01X1437751Y2018705D02*
X1439047Y2018720D01*
G01X1440132Y2076796D02*
X1439462Y2076960D01*
G01X1433598Y2059079D02*
X1441472Y2056455D01*
G01X1439294Y2076140D02*
X1439797Y2075976D01*
G01X1439462Y2058095D02*
X1441472Y2057439D01*
G01X1434268Y2059735D02*
X1438792Y2058259D01*
G01X1437117Y2084670D02*
X1437787Y2084342D01*
G01X1439797Y2075976D02*
X1440132Y2075812D01*
G01X1436781Y2072695D02*
X1437117Y2072531D01*
G01Y2067938D02*
X1437452Y2067774D01*
G01Y2072859D02*
X1437954Y2072531D01*
G01X1440132Y2076796D02*
X1440970Y2076140D01*
G01X1436781Y2084998D02*
X1437117Y2084670D01*
G01X1437284Y2079421D02*
X1437619Y2079092D01*
G01X1436614Y2079421D02*
X1436949Y2079092D01*
G01X1436446Y2073023D02*
X1436781Y2072695D01*
G01X1436949Y2068102D02*
X1437117Y2067938D01*
G01X1436279Y2068102D02*
X1436781Y2067609D01*
G01X1436949Y2065477D02*
X1437284Y2065149D01*
G01X1436279Y2065477D02*
X1436614Y2065149D01*
G01X1440970Y2076140D02*
X1441305Y2075648D01*
G01X1440132Y2075812D02*
X1440467Y2075319D01*
G01X1436949Y2079913D02*
X1437284Y2079421D01*
G01X1436279Y2079913D02*
X1436614Y2079421D01*
G01X1437117Y2073351D02*
X1437452Y2072859D01*
G01X1436279Y2073351D02*
X1436446Y2073023D01*
G01X1436781Y2068430D02*
X1436949Y2068102D01*
G01X1436111Y2068594D02*
X1436279Y2068102D01*
G01X1436781Y2065969D02*
X1436949Y2065477D01*
G01X1436111Y2065969D02*
X1436279Y2065477D01*
G01X1441305Y2075648D02*
X1441472Y2074991D01*
G01X1440467Y2075319D02*
X1440635Y2074663D01*
G01X1436781Y2080569D02*
X1436949Y2079913D01*
G01X1436111Y2080569D02*
X1436279Y2079913D01*
G01X1436949Y2074007D02*
X1437117Y2073351D01*
G01X1436111Y2074007D02*
X1436279Y2073351D01*
G01X1441235Y2018741D02*
Y2017790D01*
G01Y2025040D02*
Y2024089D01*
G01Y2021891D02*
Y2020940D01*
G01Y2028190D02*
Y2027239D01*
G01Y2034489D02*
Y2033538D01*
G01Y2031340D02*
Y2030388D01*
G01Y2037639D02*
Y2036688D01*
G01Y2043938D02*
Y2042987D01*
G01Y2040789D02*
Y2039837D01*
G01Y2047088D02*
Y2046136D01*
G01Y2053387D02*
Y2052436D01*
G01Y2050237D02*
Y2049286D01*
G01Y2056537D02*
Y2055585D01*
G01Y2062836D02*
Y2061884D01*
G01Y2059686D02*
Y2058735D01*
G01Y2065985D02*
Y2065034D01*
G01Y2072285D02*
Y2071333D01*
G01Y2069135D02*
Y2068184D01*
G01Y2075434D02*
Y2074483D01*
G01Y2081733D02*
Y2080782D01*
G01Y2078584D02*
Y2077633D01*
G01Y2084883D02*
Y2083932D01*
G01X1441007Y2018741D02*
Y2017790D01*
G01Y2025041D02*
Y2024089D01*
G01Y2021891D02*
Y2020940D01*
G01Y2028190D02*
Y2027239D01*
G01Y2034489D02*
Y2033538D01*
G01Y2031340D02*
Y2030388D01*
G01Y2037639D02*
Y2036688D01*
G01Y2043938D02*
Y2042987D01*
G01Y2040789D02*
Y2039837D01*
G01Y2047088D02*
Y2046136D01*
G01Y2053387D02*
Y2052436D01*
G01Y2050237D02*
Y2049286D01*
G01Y2056537D02*
Y2055585D01*
G01Y2062836D02*
Y2061884D01*
G01Y2059686D02*
Y2058735D01*
G01Y2065985D02*
Y2065034D01*
G01Y2072285D02*
Y2071333D01*
G01Y2069135D02*
Y2068184D01*
G01Y2075434D02*
Y2074483D01*
G01Y2081733D02*
Y2080782D01*
G01Y2078584D02*
Y2077633D01*
G01Y2084883D02*
Y2083932D01*
G01X1440635Y2074663D02*
Y2074007D01*
G01X1439462Y2061376D02*
Y2058095D01*
G01X1439047Y2018720D02*
Y2017811D01*
G01Y2025019D02*
Y2024111D01*
G01Y2021869D02*
Y2020961D01*
G01Y2028169D02*
Y2027260D01*
G01Y2034468D02*
Y2033560D01*
G01Y2031318D02*
Y2030410D01*
G01Y2037617D02*
Y2036709D01*
G01Y2043917D02*
Y2043008D01*
G01Y2040767D02*
Y2039859D01*
G01Y2047066D02*
Y2046158D01*
G01Y2053365D02*
Y2052457D01*
G01Y2050216D02*
Y2049308D01*
G01Y2056515D02*
Y2055607D01*
G01Y2062814D02*
Y2061906D01*
G01Y2059665D02*
Y2058756D01*
G01Y2065964D02*
Y2065056D01*
G01Y2072263D02*
Y2071355D01*
G01Y2069114D02*
Y2068205D01*
G01Y2075413D02*
Y2074504D01*
G01Y2081712D02*
Y2080804D01*
G01Y2078562D02*
Y2077654D01*
G01Y2084862D02*
Y2083953D01*
G01X1438792Y2061212D02*
Y2058259D01*
G01X1438785Y2018720D02*
Y2017812D01*
G01Y2025019D02*
Y2024111D01*
G01Y2021869D02*
Y2020961D01*
G01Y2028169D02*
Y2027260D01*
G01Y2034468D02*
Y2033560D01*
G01Y2031318D02*
Y2030410D01*
G01Y2037617D02*
Y2036709D01*
G01Y2043917D02*
Y2043008D01*
G01Y2040767D02*
Y2039859D01*
G01Y2047066D02*
Y2046158D01*
G01Y2053365D02*
Y2052457D01*
G01Y2050216D02*
Y2049308D01*
G01Y2056515D02*
Y2055607D01*
G01Y2062814D02*
Y2061906D01*
G01Y2059665D02*
Y2058756D01*
G01Y2065964D02*
Y2065056D01*
G01Y2072263D02*
Y2071355D01*
G01Y2069114D02*
Y2068205D01*
G01Y2075413D02*
Y2074504D01*
G01Y2081712D02*
Y2080804D01*
G01Y2078562D02*
Y2077654D01*
G01Y2084862D02*
Y2083953D01*
G01X1437751Y2018700D02*
Y2017832D01*
G01Y2024999D02*
Y2024131D01*
G01Y2021849D02*
Y2020981D01*
G01Y2028148D02*
Y2027281D01*
G01Y2034448D02*
Y2033580D01*
G01Y2031298D02*
Y2030430D01*
G01Y2037597D02*
Y2036729D01*
G01Y2043896D02*
Y2043029D01*
G01Y2040747D02*
Y2039879D01*
G01Y2047046D02*
Y2046178D01*
G01Y2053345D02*
Y2052477D01*
G01Y2050196D02*
Y2049328D01*
G01Y2056495D02*
Y2055627D01*
G01Y2062794D02*
Y2061926D01*
G01Y2059644D02*
Y2058777D01*
G01Y2065944D02*
Y2065076D01*
G01Y2072243D02*
Y2071375D01*
G01Y2069093D02*
Y2068225D01*
G01Y2075392D02*
Y2074525D01*
G01Y2081692D02*
Y2080824D01*
G01Y2078542D02*
Y2077674D01*
G01Y2084841D02*
Y2083973D01*
G01X1436949Y2074991D02*
Y2074007D01*
G01X1436781Y2066297D02*
Y2065969D01*
G01Y2068922D02*
Y2068430D01*
G01X1436420Y2018694D02*
Y2017838D01*
G01Y2024993D02*
Y2024137D01*
G01Y2021843D02*
Y2020987D01*
G01Y2028142D02*
Y2027286D01*
G01Y2034442D02*
Y2033586D01*
G01Y2031292D02*
Y2030436D01*
G01Y2037591D02*
Y2036735D01*
G01Y2043891D02*
Y2043034D01*
G01Y2040741D02*
Y2039885D01*
G01Y2047040D02*
Y2046184D01*
G01Y2053339D02*
Y2052483D01*
G01Y2050190D02*
Y2049334D01*
G01Y2056489D02*
Y2055633D01*
G01Y2062788D02*
Y2061932D01*
G01Y2059639D02*
Y2058783D01*
G01Y2065938D02*
Y2065082D01*
G01Y2072237D02*
Y2071381D01*
G01Y2069087D02*
Y2068231D01*
G01Y2075387D02*
Y2074531D01*
G01Y2081686D02*
Y2080830D01*
G01Y2078536D02*
Y2077680D01*
G01Y2084835D02*
Y2083979D01*
G01X1436111Y2065149D02*
Y2064329D01*
G01Y2066625D02*
Y2065969D01*
G01Y2072531D02*
Y2071711D01*
G01Y2069250D02*
Y2068594D01*
G01Y2074991D02*
Y2074007D01*
G01Y2081225D02*
Y2080569D01*
G01X1433598Y2060392D02*
Y2059079D01*
G01Y2079092D02*
Y2078272D01*
G01X1441472Y2074007D02*
X1441305Y2073351D01*
G01X1440635Y2074007D02*
X1440467Y2073351D01*
G01X1436279Y2075648D02*
X1436111Y2074991D01*
G01X1436949Y2081225D02*
X1436781Y2080569D01*
G01X1436279Y2067117D02*
X1436111Y2066625D01*
G01X1436279Y2069742D02*
X1436111Y2069250D01*
G01X1436279Y2081717D02*
X1436111Y2081225D01*
G01X1440467Y2073351D02*
X1440132Y2072859D01*
G01X1436614Y2076140D02*
X1436279Y2075648D01*
G01X1436614Y2082209D02*
X1436279Y2081717D01*
G01X1441305Y2073351D02*
X1441137Y2073023D01*
G01X1436949Y2066625D02*
X1436781Y2066297D01*
G01X1436949Y2069250D02*
X1436781Y2068922D01*
G01X1437284Y2075648D02*
X1436949Y2074991D01*
G01X1437117Y2081553D02*
X1436949Y2081225D01*
G01X1441472Y2062032D02*
X1439462Y2061376D01*
G01X1438792Y2061212D02*
X1434268Y2059735D01*
G01X1438289Y2076140D02*
X1437787Y2075976D01*
G01X1441472Y2063016D02*
X1433598Y2060392D01*
G01X1437452Y2070398D02*
X1436614Y2070070D01*
G01X1437452Y2066953D02*
X1437117Y2066789D01*
G01X1437452Y2069578D02*
X1437117Y2069414D01*
G01X1440802Y2072695D02*
X1440467Y2072531D01*
G01X1437452Y2076796D02*
X1437117Y2076632D01*
G01X1437284Y2082701D02*
X1436949Y2082537D01*
G01X1440467Y2084670D02*
X1439797Y2084342D01*
G01X1440132Y2072859D02*
X1439629Y2072531D01*
G01X1437787Y2075976D02*
X1437284Y2075648D01*
G01X1437117Y2066789D02*
X1436949Y2066625D01*
G01X1436781Y2067609D02*
X1436279Y2067117D01*
G01X1441137Y2073023D02*
X1440802Y2072695D01*
G01X1437117Y2069414D02*
X1436949Y2069250D01*
G01X1436614Y2070070D02*
X1436279Y2069742D01*
G01X1437117Y2076632D02*
X1436614Y2076140D01*
G01X1440802Y2084998D02*
X1440467Y2084670D01*
G01X1437452Y2081881D02*
X1437117Y2081553D01*
G01X1436949Y2082537D02*
X1436614Y2082209D01*
G01X1469631Y2015707D02*
X1457535D01*
G01X1442772Y2015608D02*
X1442543D01*
G01X1470921Y2015451D02*
X1469507D01*
G01X1470921Y2014781D02*
X1469507D01*
G01X1442772Y2014624D02*
X1442543D01*
G01X1469631Y2014525D02*
X1457535D01*
G01X1444212Y2014329D02*
X1443073D01*
G01X1457732Y2013935D02*
X1457220D01*
G01X1457732Y2013148D02*
X1457220D01*
G01X1444212Y2012754D02*
X1443073D01*
G01X1469631Y2012557D02*
X1457535D01*
G01X1442772Y2012459D02*
X1442543D01*
G01X1470921Y2012301D02*
X1469507D01*
G01X1442684Y2014536D02*
X1443073Y2014329D01*
G01X1442772Y2014624D02*
X1443243Y2014329D01*
G01X1442543Y2014624D02*
X1442684Y2014536D01*
G01X1469278Y2015707D02*
X1469507Y2015451D01*
G01X1469278Y2012557D02*
X1469507Y2012301D01*
G01X1469636Y2015721D02*
X1469855Y2015451D01*
G01X1469636Y2012571D02*
X1469855Y2012301D01*
G01X1470921Y2015451D02*
Y2014781D01*
G01X1470574Y2015451D02*
Y2014781D01*
G01X1469631Y2015707D02*
Y2014525D01*
G01X1469278Y2015707D02*
Y2014525D01*
G01X1467296Y2015707D02*
Y2014525D01*
G01X1467186Y2015707D02*
Y2014525D01*
G01X1458405Y2015707D02*
Y2014525D01*
G01X1458295Y2015707D02*
Y2014525D01*
G01X1457929Y2015707D02*
Y2014525D01*
G01X1457732D02*
Y2013935D01*
G01Y2016297D02*
Y2015707D01*
G01Y2013148D02*
Y2012557D01*
G01X1457535Y2014525D02*
Y2013935D01*
G01Y2016297D02*
Y2015707D01*
G01Y2013148D02*
Y2012557D01*
G01X1444212Y2015903D02*
Y2014329D01*
G01X1442684Y2015696D02*
Y2014536D01*
G01X1443073Y2012754D02*
X1442684Y2012546D01*
G01X1443073Y2015903D02*
X1442684Y2015696D01*
G01X1469507Y2014781D02*
X1469278Y2014525D01*
G01X1469855Y2014781D02*
X1469636Y2014511D01*
G01X1443243Y2012754D02*
X1442772Y2012459D01*
G01X1442684Y2012546D02*
X1442543Y2012459D01*
G01X1443243Y2015903D02*
X1442772Y2015608D01*
G01X1442684Y2015696D02*
X1442543Y2015608D01*
G01X1470921Y2084742D02*
X1469507D01*
G01X1470921Y2084073D02*
X1469507D01*
G01X1442772Y2083915D02*
X1442543D01*
G01X1469631Y2083817D02*
X1457535D01*
G01X1444212Y2083620D02*
X1443073D01*
G01X1457732Y2083226D02*
X1457220D01*
G01X1457732Y2082439D02*
X1457220D01*
G01X1444212Y2082045D02*
X1443073D01*
G01X1469631Y2081848D02*
X1457535D01*
G01X1442772Y2081750D02*
X1442543D01*
G01X1470921Y2081592D02*
X1469507D01*
G01X1470921Y2080923D02*
X1469507D01*
G01X1442772Y2080766D02*
X1442543D01*
G01X1469631Y2080667D02*
X1457535D01*
G01X1444212Y2080470D02*
X1443073D01*
G01X1457732Y2080077D02*
X1457220D01*
G01X1457732Y2079289D02*
X1457220D01*
G01X1444212Y2078896D02*
X1443073D01*
G01X1469631Y2078699D02*
X1457535D01*
G01X1442772Y2078600D02*
X1442543D01*
G01X1470921Y2078443D02*
X1469507D01*
G01X1470921Y2077774D02*
X1469507D01*
G01X1442772Y2077616D02*
X1442543D01*
G01X1469631Y2077518D02*
X1457535D01*
G01X1444212Y2077321D02*
X1443073D01*
G01X1457732Y2076927D02*
X1457220D01*
G01X1457732Y2076140D02*
X1457220D01*
G01X1444212Y2075746D02*
X1443073D01*
G01X1469631Y2075549D02*
X1457535D01*
G01X1442772Y2075451D02*
X1442543D01*
G01X1470921Y2075293D02*
X1469507D01*
G01X1470921Y2074624D02*
X1469507D01*
G01X1442772Y2074466D02*
X1442543D01*
G01X1469631Y2074368D02*
X1457535D01*
G01X1444212Y2074171D02*
X1443073D01*
G01X1457732Y2073777D02*
X1457220D01*
G01X1457732Y2072990D02*
X1457220D01*
G01X1444212Y2072596D02*
X1443073D01*
G01X1469631Y2072400D02*
X1457535D01*
G01X1442772Y2072301D02*
X1442543D01*
G01X1470921Y2072144D02*
X1469507D01*
G01X1470921Y2071474D02*
X1469507D01*
G01X1442772Y2071317D02*
X1442543D01*
G01X1469631Y2071218D02*
X1457535D01*
G01X1444212Y2071022D02*
X1443073D01*
G01X1457732Y2070628D02*
X1457220D01*
G01X1457732Y2069840D02*
X1457220D01*
G01X1444212Y2069447D02*
X1443073D01*
G01X1469631Y2069250D02*
X1457535D01*
G01X1442772Y2069151D02*
X1442543D01*
G01X1470921Y2068994D02*
X1469507D01*
G01X1470921Y2068325D02*
X1469507D01*
G01X1442772Y2068167D02*
X1442543D01*
G01X1469631Y2068069D02*
X1457535D01*
G01X1444212Y2067872D02*
X1443073D01*
G01X1457732Y2067478D02*
X1457220D01*
G01X1457732Y2066691D02*
X1457220D01*
G01X1444212Y2066297D02*
X1443073D01*
G01X1469631Y2066100D02*
X1457535D01*
G01X1442772Y2066002D02*
X1442543D01*
G01X1470921Y2065844D02*
X1469507D01*
G01X1470921Y2065175D02*
X1469507D01*
G01X1442772Y2065018D02*
X1442543D01*
G01X1469631Y2064919D02*
X1457535D01*
G01X1444212Y2064722D02*
X1443073D01*
G01X1457732Y2064329D02*
X1457220D01*
G01X1457732Y2063541D02*
X1457220D01*
G01X1444212Y2063148D02*
X1443073D01*
G01X1469631Y2062951D02*
X1457535D01*
G01X1442772Y2062852D02*
X1442543D01*
G01X1470921Y2062695D02*
X1469507D01*
G01X1470921Y2062025D02*
X1469507D01*
G01X1442772Y2061868D02*
X1442543D01*
G01X1469631Y2061770D02*
X1457535D01*
G01X1444212Y2061573D02*
X1443073D01*
G01X1457732Y2061179D02*
X1457220D01*
G01X1457732Y2060392D02*
X1457220D01*
G01X1444212Y2059998D02*
X1443073D01*
G01X1469631Y2059801D02*
X1457535D01*
G01X1442772Y2059703D02*
X1442543D01*
G01X1470921Y2059545D02*
X1469507D01*
G01X1470921Y2058876D02*
X1469507D01*
G01X1442772Y2058718D02*
X1442543D01*
G01X1469631Y2058620D02*
X1457535D01*
G01X1444212Y2058423D02*
X1443073D01*
G01X1457732Y2058029D02*
X1457220D01*
G01X1457732Y2057242D02*
X1457220D01*
G01X1444212Y2056848D02*
X1443073D01*
G01X1469631Y2056651D02*
X1457535D01*
G01X1442772Y2056553D02*
X1442543D01*
G01X1470921Y2056396D02*
X1469507D01*
G01X1470921Y2055726D02*
X1469507D01*
G01X1442772Y2055569D02*
X1442543D01*
G01X1469631Y2055470D02*
X1457535D01*
G01X1444212Y2055274D02*
X1443073D01*
G01X1457732Y2054880D02*
X1457220D01*
G01X1457732Y2054092D02*
X1457220D01*
G01X1444212Y2053699D02*
X1443073D01*
G01X1469631Y2053502D02*
X1457535D01*
G01X1442772Y2053403D02*
X1442543D01*
G01X1470921Y2053246D02*
X1469507D01*
G01X1470921Y2052577D02*
X1469507D01*
G01X1442772Y2052419D02*
X1442543D01*
G01X1469631Y2052321D02*
X1457535D01*
G01X1444212Y2052124D02*
X1443073D01*
G01X1457732Y2051730D02*
X1457220D01*
G01X1457732Y2050943D02*
X1457220D01*
G01X1444212Y2050549D02*
X1443073D01*
G01X1469631Y2050352D02*
X1457535D01*
G01X1442772Y2050254D02*
X1442543D01*
G01X1470921Y2050096D02*
X1469507D01*
G01X1470921Y2049427D02*
X1469507D01*
G01X1442772Y2049270D02*
X1442543D01*
G01X1469631Y2049171D02*
X1457535D01*
G01X1444212Y2048974D02*
X1443073D01*
G01X1457732Y2048581D02*
X1457220D01*
G01X1457732Y2047793D02*
X1457220D01*
G01X1444212Y2047400D02*
X1443073D01*
G01X1469631Y2047203D02*
X1457535D01*
G01X1442772Y2047104D02*
X1442543D01*
G01X1470921Y2046947D02*
X1469507D01*
G01X1470921Y2046277D02*
X1469507D01*
G01X1442772Y2046120D02*
X1442543D01*
G01X1469631Y2046022D02*
X1457535D01*
G01X1444212Y2045825D02*
X1443073D01*
G01X1457732Y2045431D02*
X1457220D01*
G01X1457732Y2044644D02*
X1457220D01*
G01X1444212Y2044250D02*
X1443073D01*
G01X1469631Y2044053D02*
X1457535D01*
G01X1442772Y2043955D02*
X1442543D01*
G01X1470921Y2043797D02*
X1469507D01*
G01X1470921Y2043128D02*
X1469507D01*
G01X1442772Y2042970D02*
X1442543D01*
G01X1469631Y2042872D02*
X1457535D01*
G01X1444212Y2042675D02*
X1443073D01*
G01X1457732Y2042281D02*
X1457220D01*
G01X1457732Y2041494D02*
X1457220D01*
G01X1444212Y2041100D02*
X1443073D01*
G01X1469631Y2040903D02*
X1457535D01*
G01X1442772Y2040805D02*
X1442543D01*
G01X1470921Y2040648D02*
X1469507D01*
G01X1470921Y2039978D02*
X1469507D01*
G01X1442772Y2039821D02*
X1442543D01*
G01X1469631Y2039722D02*
X1457535D01*
G01X1444212Y2039525D02*
X1443073D01*
G01X1457732Y2039132D02*
X1457220D01*
G01X1457732Y2038344D02*
X1457220D01*
G01X1444212Y2037951D02*
X1443073D01*
G01X1469631Y2037754D02*
X1457535D01*
G01X1442772Y2037655D02*
X1442543D01*
G01X1470921Y2037498D02*
X1469507D01*
G01X1470921Y2036829D02*
X1469507D01*
G01X1442772Y2036671D02*
X1442543D01*
G01X1469631Y2036573D02*
X1457535D01*
G01X1444212Y2036376D02*
X1443073D01*
G01X1457732Y2035982D02*
X1457220D01*
G01X1457732Y2035195D02*
X1457220D01*
G01X1444212Y2034801D02*
X1443073D01*
G01X1469631Y2034604D02*
X1457535D01*
G01X1442772Y2034506D02*
X1442543D01*
G01X1470921Y2034348D02*
X1469507D01*
G01X1470921Y2033679D02*
X1469507D01*
G01X1442772Y2033522D02*
X1442543D01*
G01X1469631Y2033423D02*
X1457535D01*
G01X1444212Y2033226D02*
X1443073D01*
G01X1457732Y2032833D02*
X1457220D01*
G01X1457732Y2032045D02*
X1457220D01*
G01X1444212Y2031651D02*
X1443073D01*
G01X1469631Y2031455D02*
X1457535D01*
G01X1442772Y2031356D02*
X1442543D01*
G01X1470921Y2031199D02*
X1469507D01*
G01X1470921Y2030529D02*
X1469507D01*
G01X1442772Y2030372D02*
X1442543D01*
G01X1469631Y2030274D02*
X1457535D01*
G01X1444212Y2030077D02*
X1443073D01*
G01X1457732Y2029683D02*
X1457220D01*
G01X1457732Y2028896D02*
X1457220D01*
G01X1444212Y2028502D02*
X1443073D01*
G01X1469631Y2028305D02*
X1457535D01*
G01X1442772Y2028207D02*
X1442543D01*
G01X1470921Y2028049D02*
X1469507D01*
G01X1470921Y2027380D02*
X1469507D01*
G01X1442772Y2027222D02*
X1442543D01*
G01X1469631Y2027124D02*
X1457535D01*
G01X1444212Y2026927D02*
X1443073D01*
G01X1457732Y2026533D02*
X1457220D01*
G01X1457732Y2025746D02*
X1457220D01*
G01X1444212Y2025352D02*
X1443073D01*
G01X1469631Y2025155D02*
X1457535D01*
G01X1442772Y2025057D02*
X1442543D01*
G01X1470921Y2024900D02*
X1469507D01*
G01X1470921Y2024230D02*
X1469507D01*
G01X1442772Y2024073D02*
X1442543D01*
G01X1469631Y2023974D02*
X1457535D01*
G01X1444212Y2023777D02*
X1443073D01*
G01X1457732Y2023384D02*
X1457220D01*
G01X1457732Y2022596D02*
X1457220D01*
G01X1444212Y2022203D02*
X1443073D01*
G01X1469631Y2022006D02*
X1457535D01*
G01X1442772Y2021907D02*
X1442543D01*
G01X1470921Y2021750D02*
X1469507D01*
G01X1470921Y2021081D02*
X1469507D01*
G01X1442772Y2020923D02*
X1442543D01*
G01X1469631Y2020825D02*
X1457535D01*
G01X1444212Y2020628D02*
X1443073D01*
G01X1457732Y2020234D02*
X1457220D01*
G01X1457732Y2019447D02*
X1457220D01*
G01X1444212Y2019053D02*
X1443073D01*
G01X1469631Y2018856D02*
X1457535D01*
G01X1442772Y2018758D02*
X1442543D01*
G01X1470921Y2018600D02*
X1469507D01*
G01X1470921Y2017931D02*
X1469507D01*
G01X1442772Y2017774D02*
X1442543D01*
G01X1469631Y2017675D02*
X1457535D01*
G01X1444212Y2017478D02*
X1443073D01*
G01X1457732Y2017085D02*
X1457220D01*
G01X1457732Y2016297D02*
X1457220D01*
G01X1444212Y2015903D02*
X1443073D01*
G01X1442684Y2083827D02*
X1443073Y2083620D01*
G01X1442684Y2080678D02*
X1443073Y2080470D01*
G01X1442772Y2083915D02*
X1443243Y2083620D01*
G01X1442543Y2083915D02*
X1442684Y2083827D01*
G01X1442772Y2080766D02*
X1443243Y2080470D01*
G01X1442543Y2080766D02*
X1442684Y2080678D01*
G01X1442772Y2077616D02*
X1443243Y2077321D01*
G01X1442543Y2077616D02*
X1442684Y2077528D01*
G01X1442772Y2074466D02*
X1443243Y2074171D01*
G01X1442543Y2074466D02*
X1442684Y2074379D01*
G01X1442772Y2071317D02*
X1443243Y2071022D01*
G01X1442543Y2071317D02*
X1442684Y2071229D01*
G01X1442772Y2068167D02*
X1443243Y2067872D01*
G01X1442543Y2068167D02*
X1442684Y2068079D01*
G01X1442772Y2065018D02*
X1443243Y2064722D01*
G01X1442543Y2065018D02*
X1442684Y2064930D01*
G01X1442772Y2061868D02*
X1443243Y2061573D01*
G01X1442543Y2061868D02*
X1442684Y2061780D01*
G01X1442772Y2058718D02*
X1443243Y2058423D01*
G01X1442543Y2058718D02*
X1442684Y2058631D01*
G01X1496457Y2070561D02*
X1493047Y2072529D01*
G01X1442684Y2077528D02*
X1443073Y2077321D01*
G01X1442684Y2074379D02*
X1443073Y2074171D01*
G01X1442684Y2071229D02*
X1443073Y2071022D01*
G01X1442684Y2068079D02*
X1443073Y2067872D01*
G01X1442684Y2064930D02*
X1443073Y2064722D01*
G01X1442684Y2061780D02*
X1443073Y2061573D01*
G01X1442684Y2058631D02*
X1443073Y2058423D01*
G01X1442684Y2055481D02*
X1443073Y2055274D01*
G01X1442684Y2052331D02*
X1443073Y2052124D01*
G01X1442684Y2049182D02*
X1443073Y2048974D01*
G01X1442684Y2046032D02*
X1443073Y2045825D01*
G01X1442684Y2042883D02*
X1443073Y2042675D01*
G01X1442684Y2039733D02*
X1443073Y2039525D01*
G01X1442684Y2036583D02*
X1443073Y2036376D01*
G01X1442684Y2033434D02*
X1443073Y2033226D01*
G01X1442684Y2030284D02*
X1443073Y2030077D01*
G01X1442684Y2027135D02*
X1443073Y2026927D01*
G01X1442684Y2023985D02*
X1443073Y2023777D01*
G01X1442684Y2020835D02*
X1443073Y2020628D01*
G01X1442684Y2017686D02*
X1443073Y2017478D01*
G01X1442772Y2055569D02*
X1443243Y2055274D01*
G01X1442543Y2055569D02*
X1442684Y2055481D01*
G01X1442772Y2052419D02*
X1443243Y2052124D01*
G01X1442543Y2052419D02*
X1442684Y2052331D01*
G01X1442772Y2049270D02*
X1443243Y2048974D01*
G01X1442543Y2049270D02*
X1442684Y2049182D01*
G01X1442772Y2046120D02*
X1443243Y2045825D01*
G01X1442543Y2046120D02*
X1442684Y2046032D01*
G01X1442772Y2042970D02*
X1443243Y2042675D01*
G01X1442543Y2042970D02*
X1442684Y2042883D01*
G01X1442772Y2039821D02*
X1443243Y2039525D01*
G01X1442543Y2039821D02*
X1442684Y2039733D01*
G01X1442772Y2036671D02*
X1443243Y2036376D01*
G01X1442543Y2036671D02*
X1442684Y2036583D01*
G01X1442772Y2033522D02*
X1443243Y2033226D01*
G01X1442543Y2033522D02*
X1442684Y2033434D01*
G01X1442772Y2030372D02*
X1443243Y2030077D01*
G01X1442543Y2030372D02*
X1442684Y2030284D01*
G01X1442772Y2027222D02*
X1443243Y2026927D01*
G01X1442543Y2027222D02*
X1442684Y2027135D01*
G01X1442772Y2024073D02*
X1443243Y2023777D01*
G01X1442543Y2024073D02*
X1442684Y2023985D01*
G01X1442772Y2020923D02*
X1443243Y2020628D01*
G01X1442543Y2020923D02*
X1442684Y2020835D01*
G01X1442772Y2017774D02*
X1443243Y2017478D01*
G01X1442543Y2017774D02*
X1442684Y2017686D01*
G01X1469278Y2084998D02*
X1469507Y2084742D01*
G01X1469278Y2081848D02*
X1469507Y2081592D01*
G01X1469278Y2078699D02*
X1469507Y2078443D01*
G01X1469278Y2075549D02*
X1469507Y2075293D01*
G01X1469278Y2072400D02*
X1469507Y2072144D01*
G01X1469278Y2069250D02*
X1469507Y2068994D01*
G01X1469278Y2066100D02*
X1469507Y2065844D01*
G01X1469636Y2085012D02*
X1469855Y2084742D01*
G01X1469636Y2081862D02*
X1469855Y2081592D01*
G01X1469636Y2078713D02*
X1469855Y2078443D01*
G01X1469636Y2075563D02*
X1469855Y2075293D01*
G01X1469636Y2072414D02*
X1469855Y2072144D01*
G01X1469636Y2069264D02*
X1469855Y2068994D01*
G01X1469636Y2066114D02*
X1469855Y2065844D01*
G01X1469636Y2062965D02*
X1469855Y2062695D01*
G01X1469636Y2059815D02*
X1469855Y2059545D01*
G01X1469636Y2056666D02*
X1469855Y2056396D01*
G01X1469636Y2053516D02*
X1469855Y2053246D01*
G01X1469636Y2050366D02*
X1469855Y2050096D01*
G01X1469636Y2047217D02*
X1469855Y2046947D01*
G01X1469636Y2044067D02*
X1469855Y2043797D01*
G01X1469636Y2040918D02*
X1469855Y2040648D01*
G01X1469636Y2037768D02*
X1469855Y2037498D01*
G01X1469636Y2034618D02*
X1469855Y2034348D01*
G01X1469636Y2031469D02*
X1469855Y2031199D01*
G01X1469636Y2028319D02*
X1469855Y2028049D01*
G01X1469636Y2025170D02*
X1469855Y2024900D01*
G01X1469636Y2022020D02*
X1469855Y2021750D01*
G01X1469636Y2018870D02*
X1469855Y2018600D01*
G01X1469278Y2062951D02*
X1469507Y2062695D01*
G01X1469278Y2059801D02*
X1469507Y2059545D01*
G01X1469278Y2056651D02*
X1469507Y2056396D01*
G01X1469278Y2053502D02*
X1469507Y2053246D01*
G01X1469278Y2050352D02*
X1469507Y2050096D01*
G01X1469278Y2047203D02*
X1469507Y2046947D01*
G01X1469278Y2044053D02*
X1469507Y2043797D01*
G01X1469278Y2040903D02*
X1469507Y2040648D01*
G01X1469278Y2037754D02*
X1469507Y2037498D01*
G01X1469278Y2034604D02*
X1469507Y2034348D01*
G01X1469278Y2031455D02*
X1469507Y2031199D01*
G01X1469278Y2028305D02*
X1469507Y2028049D01*
G01X1469278Y2025155D02*
X1469507Y2024900D01*
G01X1469278Y2022006D02*
X1469507Y2021750D01*
G01X1469278Y2018856D02*
X1469507Y2018600D01*
G01X1493047Y2072529D02*
Y2074262D01*
G01X1470921Y2018600D02*
Y2017931D01*
G01Y2024900D02*
Y2024230D01*
G01Y2021750D02*
Y2021081D01*
G01Y2028049D02*
Y2027380D01*
G01Y2034348D02*
Y2033679D01*
G01Y2031199D02*
Y2030529D01*
G01Y2037498D02*
Y2036829D01*
G01Y2043797D02*
Y2043128D01*
G01Y2040648D02*
Y2039978D01*
G01Y2046947D02*
Y2046277D01*
G01Y2053246D02*
Y2052577D01*
G01Y2050096D02*
Y2049427D01*
G01Y2056396D02*
Y2055726D01*
G01Y2062695D02*
Y2062025D01*
G01Y2059545D02*
Y2058876D01*
G01Y2065844D02*
Y2065175D01*
G01Y2072144D02*
Y2071474D01*
G01Y2068994D02*
Y2068325D01*
G01Y2075293D02*
Y2074624D01*
G01Y2081592D02*
Y2080923D01*
G01Y2078443D02*
Y2077774D01*
G01Y2084742D02*
Y2084073D01*
G01X1470574Y2018600D02*
Y2017931D01*
G01Y2024900D02*
Y2024230D01*
G01Y2021750D02*
Y2021081D01*
G01Y2028049D02*
Y2027380D01*
G01Y2034348D02*
Y2033679D01*
G01Y2031199D02*
Y2030529D01*
G01Y2037498D02*
Y2036829D01*
G01Y2043797D02*
Y2043128D01*
G01Y2040648D02*
Y2039978D01*
G01Y2046947D02*
Y2046277D01*
G01Y2053246D02*
Y2052577D01*
G01Y2050096D02*
Y2049427D01*
G01Y2056396D02*
Y2055726D01*
G01Y2062695D02*
Y2062025D01*
G01Y2059545D02*
Y2058876D01*
G01Y2065844D02*
Y2065175D01*
G01Y2072144D02*
Y2071474D01*
G01Y2068994D02*
Y2068325D01*
G01Y2075293D02*
Y2074624D01*
G01Y2081592D02*
Y2080923D01*
G01Y2078443D02*
Y2077774D01*
G01Y2084742D02*
Y2084073D01*
G01X1469631Y2018856D02*
Y2017675D01*
G01Y2025155D02*
Y2023974D01*
G01Y2022006D02*
Y2020825D01*
G01Y2028305D02*
Y2027124D01*
G01Y2034604D02*
Y2033423D01*
G01Y2031455D02*
Y2030274D01*
G01Y2037754D02*
Y2036573D01*
G01Y2044053D02*
Y2042872D01*
G01Y2040903D02*
Y2039722D01*
G01Y2047203D02*
Y2046022D01*
G01Y2053502D02*
Y2052321D01*
G01Y2050352D02*
Y2049171D01*
G01Y2056651D02*
Y2055470D01*
G01Y2062951D02*
Y2061770D01*
G01Y2059801D02*
Y2058620D01*
G01Y2066100D02*
Y2064919D01*
G01Y2072400D02*
Y2071218D01*
G01Y2069250D02*
Y2068069D01*
G01Y2075549D02*
Y2074368D01*
G01Y2081848D02*
Y2080667D01*
G01Y2078699D02*
Y2077518D01*
G01Y2084998D02*
Y2083817D01*
G01X1469278Y2018856D02*
Y2017675D01*
G01Y2025155D02*
Y2023974D01*
G01Y2022006D02*
Y2020825D01*
G01Y2028305D02*
Y2027124D01*
G01Y2034604D02*
Y2033423D01*
G01Y2031455D02*
Y2030274D01*
G01Y2037754D02*
Y2036573D01*
G01Y2044053D02*
Y2042872D01*
G01Y2040903D02*
Y2039722D01*
G01Y2047203D02*
Y2046022D01*
G01Y2053502D02*
Y2052321D01*
G01Y2050352D02*
Y2049171D01*
G01Y2056651D02*
Y2055470D01*
G01Y2062951D02*
Y2061770D01*
G01Y2059801D02*
Y2058620D01*
G01Y2066100D02*
Y2064919D01*
G01Y2072400D02*
Y2071218D01*
G01Y2069250D02*
Y2068069D01*
G01Y2075549D02*
Y2074368D01*
G01Y2081848D02*
Y2080667D01*
G01Y2078699D02*
Y2077518D01*
G01Y2084998D02*
Y2083817D01*
G01X1467296Y2018856D02*
Y2017675D01*
G01Y2025155D02*
Y2023974D01*
G01Y2022006D02*
Y2020825D01*
G01Y2028305D02*
Y2027124D01*
G01Y2034604D02*
Y2033423D01*
G01Y2031455D02*
Y2030274D01*
G01Y2037754D02*
Y2036573D01*
G01Y2044053D02*
Y2042872D01*
G01Y2040903D02*
Y2039722D01*
G01Y2047203D02*
Y2046022D01*
G01Y2053502D02*
Y2052321D01*
G01Y2050352D02*
Y2049171D01*
G01Y2056651D02*
Y2055470D01*
G01Y2062951D02*
Y2061770D01*
G01Y2059801D02*
Y2058620D01*
G01Y2066100D02*
Y2064919D01*
G01Y2072400D02*
Y2071218D01*
G01Y2069250D02*
Y2068069D01*
G01Y2075549D02*
Y2074368D01*
G01Y2081848D02*
Y2080667D01*
G01Y2078699D02*
Y2077518D01*
G01Y2084998D02*
Y2083817D01*
G01X1467186Y2018856D02*
Y2017675D01*
G01Y2025155D02*
Y2023974D01*
G01Y2022006D02*
Y2020825D01*
G01Y2028305D02*
Y2027124D01*
G01Y2034604D02*
Y2033423D01*
G01Y2031455D02*
Y2030274D01*
G01Y2037754D02*
Y2036573D01*
G01Y2044053D02*
Y2042872D01*
G01Y2040903D02*
Y2039722D01*
G01Y2047203D02*
Y2046022D01*
G01Y2053502D02*
Y2052321D01*
G01Y2050352D02*
Y2049171D01*
G01Y2056651D02*
Y2055470D01*
G01Y2062951D02*
Y2061770D01*
G01Y2059801D02*
Y2058620D01*
G01Y2066100D02*
Y2064919D01*
G01Y2072400D02*
Y2071218D01*
G01Y2069250D02*
Y2068069D01*
G01Y2075549D02*
Y2074368D01*
G01Y2081848D02*
Y2080667D01*
G01Y2078699D02*
Y2077518D01*
G01Y2084998D02*
Y2083817D01*
G01X1458405Y2018856D02*
Y2017675D01*
G01Y2025155D02*
Y2023974D01*
G01Y2022006D02*
Y2020825D01*
G01Y2028305D02*
Y2027124D01*
G01Y2034604D02*
Y2033423D01*
G01Y2031455D02*
Y2030274D01*
G01Y2037754D02*
Y2036573D01*
G01Y2044053D02*
Y2042872D01*
G01Y2040903D02*
Y2039722D01*
G01Y2047203D02*
Y2046022D01*
G01Y2053502D02*
Y2052321D01*
G01Y2050352D02*
Y2049171D01*
G01Y2056651D02*
Y2055470D01*
G01Y2062951D02*
Y2061770D01*
G01Y2059801D02*
Y2058620D01*
G01Y2066100D02*
Y2064919D01*
G01Y2072400D02*
Y2071218D01*
G01Y2069250D02*
Y2068069D01*
G01Y2075549D02*
Y2074368D01*
G01Y2081848D02*
Y2080667D01*
G01Y2078699D02*
Y2077518D01*
G01Y2084998D02*
Y2083817D01*
G01X1458295Y2018856D02*
Y2017675D01*
G01Y2025155D02*
Y2023974D01*
G01Y2022006D02*
Y2020825D01*
G01Y2028305D02*
Y2027124D01*
G01Y2034604D02*
Y2033423D01*
G01Y2031455D02*
Y2030274D01*
G01Y2037754D02*
Y2036573D01*
G01Y2044053D02*
Y2042872D01*
G01Y2040903D02*
Y2039722D01*
G01Y2047203D02*
Y2046022D01*
G01Y2053502D02*
Y2052321D01*
G01Y2050352D02*
Y2049171D01*
G01Y2056651D02*
Y2055470D01*
G01Y2062951D02*
Y2061770D01*
G01Y2059801D02*
Y2058620D01*
G01Y2066100D02*
Y2064919D01*
G01Y2072400D02*
Y2071218D01*
G01Y2069250D02*
Y2068069D01*
G01Y2075549D02*
Y2074368D01*
G01Y2081848D02*
Y2080667D01*
G01Y2078699D02*
Y2077518D01*
G01Y2084998D02*
Y2083817D01*
G01X1457929Y2018856D02*
Y2017675D01*
G01Y2025155D02*
Y2023974D01*
G01Y2022006D02*
Y2020825D01*
G01Y2028305D02*
Y2027124D01*
G01Y2034604D02*
Y2033423D01*
G01Y2031455D02*
Y2030274D01*
G01Y2037754D02*
Y2036573D01*
G01Y2044053D02*
Y2042872D01*
G01Y2040903D02*
Y2039722D01*
G01Y2047203D02*
Y2046022D01*
G01Y2053502D02*
Y2052321D01*
G01Y2050352D02*
Y2049171D01*
G01Y2056651D02*
Y2055470D01*
G01Y2062951D02*
Y2061770D01*
G01Y2059801D02*
Y2058620D01*
G01Y2066100D02*
Y2064919D01*
G01Y2072400D02*
Y2071218D01*
G01Y2069250D02*
Y2068069D01*
G01Y2075549D02*
Y2074368D01*
G01Y2081848D02*
Y2080667D01*
G01Y2078699D02*
Y2077518D01*
G01Y2084998D02*
Y2083817D01*
G01X1457732Y2020825D02*
Y2020234D01*
G01Y2017675D02*
Y2017085D01*
G01Y2019447D02*
Y2018856D01*
G01Y2023974D02*
Y2023384D01*
G01Y2022596D02*
Y2022006D01*
G01Y2030274D02*
Y2029683D01*
G01Y2027124D02*
Y2026533D01*
G01Y2028896D02*
Y2028305D01*
G01Y2025746D02*
Y2025155D01*
G01Y2033423D02*
Y2032833D01*
G01Y2032045D02*
Y2031455D01*
G01Y2039722D02*
Y2039132D01*
G01Y2036573D02*
Y2035982D01*
G01Y2038344D02*
Y2037754D01*
G01Y2035195D02*
Y2034604D01*
G01Y2042872D02*
Y2042281D01*
G01Y2041494D02*
Y2040903D01*
G01Y2046022D02*
Y2045431D01*
G01Y2047793D02*
Y2047203D01*
G01Y2044644D02*
Y2044053D01*
G01Y2052321D02*
Y2051730D01*
G01Y2049171D02*
Y2048581D01*
G01Y2050943D02*
Y2050352D01*
G01Y2055470D02*
Y2054880D01*
G01Y2057242D02*
Y2056651D01*
G01Y2054092D02*
Y2053502D01*
G01Y2061770D02*
Y2061179D01*
G01Y2058620D02*
Y2058029D01*
G01Y2060392D02*
Y2059801D01*
G01Y2064919D02*
Y2064329D01*
G01Y2066691D02*
Y2066100D01*
G01Y2063541D02*
Y2062951D01*
G01Y2071218D02*
Y2070628D01*
G01Y2068069D02*
Y2067478D01*
G01Y2069840D02*
Y2069250D01*
G01Y2074368D02*
Y2073777D01*
G01Y2076140D02*
Y2075549D01*
G01Y2072990D02*
Y2072400D01*
G01Y2080667D02*
Y2080077D01*
G01Y2077518D02*
Y2076927D01*
G01Y2079289D02*
Y2078699D01*
G01Y2083817D02*
Y2083226D01*
G01Y2082439D02*
Y2081848D01*
G01X1457535Y2020825D02*
Y2020234D01*
G01Y2017675D02*
Y2017085D01*
G01Y2019447D02*
Y2018856D01*
G01Y2023974D02*
Y2023384D01*
G01Y2022596D02*
Y2022006D01*
G01Y2030274D02*
Y2029683D01*
G01Y2027124D02*
Y2026533D01*
G01Y2028896D02*
Y2028305D01*
G01Y2025746D02*
Y2025155D01*
G01Y2033423D02*
Y2032833D01*
G01Y2032045D02*
Y2031455D01*
G01Y2039722D02*
Y2039132D01*
G01Y2036573D02*
Y2035982D01*
G01Y2038344D02*
Y2037754D01*
G01Y2035195D02*
Y2034604D01*
G01Y2042872D02*
Y2042281D01*
G01Y2041494D02*
Y2040903D01*
G01Y2046022D02*
Y2045431D01*
G01Y2047793D02*
Y2047203D01*
G01Y2044644D02*
Y2044053D01*
G01Y2052321D02*
Y2051730D01*
G01Y2049171D02*
Y2048581D01*
G01Y2050943D02*
Y2050352D01*
G01Y2055470D02*
Y2054880D01*
G01Y2057242D02*
Y2056651D01*
G01Y2054092D02*
Y2053502D01*
G01Y2061770D02*
Y2061179D01*
G01Y2058620D02*
Y2058029D01*
G01Y2060392D02*
Y2059801D01*
G01Y2064919D02*
Y2064329D01*
G01Y2066691D02*
Y2066100D01*
G01Y2063541D02*
Y2062951D01*
G01Y2071218D02*
Y2070628D01*
G01Y2068069D02*
Y2067478D01*
G01Y2069840D02*
Y2069250D01*
G01Y2074368D02*
Y2073777D01*
G01Y2076140D02*
Y2075549D01*
G01Y2072990D02*
Y2072400D01*
G01Y2080667D02*
Y2080077D01*
G01Y2077518D02*
Y2076927D01*
G01Y2079289D02*
Y2078699D01*
G01Y2083817D02*
Y2083226D01*
G01Y2082439D02*
Y2081848D01*
G01X1444212Y2019053D02*
Y2017478D01*
G01Y2025352D02*
Y2023777D01*
G01Y2022203D02*
Y2020628D01*
G01Y2028502D02*
Y2026927D01*
G01Y2034801D02*
Y2033226D01*
G01Y2031651D02*
Y2030077D01*
G01Y2037951D02*
Y2036376D01*
G01Y2044250D02*
Y2042675D01*
G01Y2041100D02*
Y2039525D01*
G01Y2047400D02*
Y2045825D01*
G01Y2053699D02*
Y2052124D01*
G01Y2050549D02*
Y2048974D01*
G01Y2056848D02*
Y2055274D01*
G01Y2063148D02*
Y2061573D01*
G01Y2059998D02*
Y2058423D01*
G01Y2066297D02*
Y2064722D01*
G01Y2069447D02*
Y2067872D01*
G01Y2075746D02*
Y2074171D01*
G01Y2072596D02*
Y2071022D01*
G01Y2078896D02*
Y2077321D01*
G01Y2085195D02*
Y2083620D01*
G01Y2082045D02*
Y2080470D01*
G01X1444153Y2072531D02*
Y2071711D01*
G01X1442684Y2018846D02*
Y2017686D01*
G01Y2025145D02*
Y2023985D01*
G01Y2021995D02*
Y2020835D01*
G01Y2028294D02*
Y2027135D01*
G01Y2034594D02*
Y2033434D01*
G01Y2031444D02*
Y2030284D01*
G01Y2037743D02*
Y2036583D01*
G01Y2044042D02*
Y2042883D01*
G01Y2040893D02*
Y2039733D01*
G01Y2047192D02*
Y2046032D01*
G01Y2053491D02*
Y2052331D01*
G01Y2050342D02*
Y2049182D01*
G01Y2056641D02*
Y2055481D01*
G01Y2062940D02*
Y2061780D01*
G01Y2059790D02*
Y2058631D01*
G01Y2066090D02*
Y2064930D01*
G01Y2072389D02*
Y2071229D01*
G01Y2069239D02*
Y2068079D01*
G01Y2075539D02*
Y2074379D01*
G01Y2081838D02*
Y2080678D01*
G01Y2078688D02*
Y2077528D01*
G01Y2084987D02*
Y2083827D01*
G01X1441472Y2057439D02*
Y2056455D01*
G01Y2063016D02*
Y2062032D01*
G01Y2067774D02*
Y2066953D01*
G01Y2065149D02*
Y2064329D01*
G01Y2070398D02*
Y2069578D01*
G01Y2074991D02*
Y2074007D01*
G01Y2079092D02*
Y2078272D01*
G01Y2082865D02*
Y2082045D01*
G01X1497767Y2077800D02*
X1493047Y2073158D01*
G01Y2074262D02*
X1497772Y2078907D01*
G01X1469507Y2017931D02*
X1469278Y2017675D01*
G01X1469507Y2021081D02*
X1469278Y2020825D01*
G01X1469507Y2024230D02*
X1469278Y2023974D01*
G01X1469507Y2027380D02*
X1469278Y2027124D01*
G01X1469507Y2030529D02*
X1469278Y2030274D01*
G01X1469507Y2033679D02*
X1469278Y2033423D01*
G01X1469507Y2036829D02*
X1469278Y2036573D01*
G01X1469507Y2039978D02*
X1469278Y2039722D01*
G01X1469507Y2043128D02*
X1469278Y2042872D01*
G01X1469507Y2046277D02*
X1469278Y2046022D01*
G01X1469507Y2049427D02*
X1469278Y2049171D01*
G01X1469507Y2052577D02*
X1469278Y2052321D01*
G01X1469507Y2055726D02*
X1469278Y2055470D01*
G01X1469507Y2058876D02*
X1469278Y2058620D01*
G01X1469507Y2062025D02*
X1469278Y2061770D01*
G01X1469507Y2065175D02*
X1469278Y2064919D01*
G01X1469507Y2068325D02*
X1469278Y2068069D01*
G01X1469507Y2071474D02*
X1469278Y2071218D01*
G01X1469507Y2074624D02*
X1469278Y2074368D01*
G01X1469855Y2017931D02*
X1469636Y2017661D01*
G01X1469855Y2021081D02*
X1469636Y2020811D01*
G01X1469855Y2024230D02*
X1469636Y2023960D01*
G01X1469855Y2027380D02*
X1469636Y2027110D01*
G01X1469855Y2030529D02*
X1469636Y2030259D01*
G01X1469855Y2033679D02*
X1469636Y2033409D01*
G01X1469855Y2036829D02*
X1469636Y2036559D01*
G01X1469855Y2039978D02*
X1469636Y2039708D01*
G01X1469855Y2043128D02*
X1469636Y2042858D01*
G01X1469855Y2046277D02*
X1469636Y2046007D01*
G01X1469855Y2049427D02*
X1469636Y2049157D01*
G01X1469855Y2052577D02*
X1469636Y2052307D01*
G01X1469855Y2055726D02*
X1469636Y2055456D01*
G01X1469855Y2058876D02*
X1469636Y2058606D01*
G01X1469855Y2062025D02*
X1469636Y2061755D01*
G01X1469855Y2065175D02*
X1469636Y2064905D01*
G01X1469855Y2068325D02*
X1469636Y2068055D01*
G01X1469855Y2071474D02*
X1469636Y2071204D01*
G01X1469855Y2074624D02*
X1469636Y2074354D01*
G01X1469855Y2077774D02*
X1469636Y2077503D01*
G01X1469855Y2080923D02*
X1469636Y2080653D01*
G01X1469855Y2084073D02*
X1469636Y2083803D01*
G01X1443073Y2019053D02*
X1442684Y2018846D01*
G01X1443073Y2022203D02*
X1442684Y2021995D01*
G01X1443073Y2025352D02*
X1442684Y2025145D01*
G01X1443073Y2028502D02*
X1442684Y2028294D01*
G01X1443073Y2031651D02*
X1442684Y2031444D01*
G01X1443073Y2034801D02*
X1442684Y2034594D01*
G01X1443073Y2037951D02*
X1442684Y2037743D01*
G01X1443073Y2041100D02*
X1442684Y2040893D01*
G01X1443073Y2044250D02*
X1442684Y2044042D01*
G01X1443073Y2047400D02*
X1442684Y2047192D01*
G01X1443073Y2050549D02*
X1442684Y2050342D01*
G01X1443073Y2053699D02*
X1442684Y2053491D01*
G01X1443073Y2056848D02*
X1442684Y2056641D01*
G01X1443073Y2059998D02*
X1442684Y2059790D01*
G01X1443073Y2063148D02*
X1442684Y2062940D01*
G01X1443073Y2066297D02*
X1442684Y2066090D01*
G01X1443073Y2069447D02*
X1442684Y2069239D01*
G01X1443073Y2072596D02*
X1442684Y2072389D01*
G01X1443073Y2075746D02*
X1442684Y2075539D01*
G01X1443073Y2078896D02*
X1442684Y2078688D01*
G01X1443073Y2082045D02*
X1442684Y2081838D01*
G01X1443243Y2019053D02*
X1442772Y2018758D01*
G01X1442684Y2018846D02*
X1442543Y2018758D01*
G01X1443243Y2022203D02*
X1442772Y2021907D01*
G01X1442684Y2021995D02*
X1442543Y2021907D01*
G01X1443243Y2025352D02*
X1442772Y2025057D01*
G01X1442684Y2025145D02*
X1442543Y2025057D01*
G01X1443243Y2028502D02*
X1442772Y2028207D01*
G01X1442684Y2028294D02*
X1442543Y2028207D01*
G01X1443243Y2031651D02*
X1442772Y2031356D01*
G01X1442684Y2031444D02*
X1442543Y2031356D01*
G01X1443243Y2034801D02*
X1442772Y2034506D01*
G01X1442684Y2034594D02*
X1442543Y2034506D01*
G01X1443243Y2037951D02*
X1442772Y2037655D01*
G01X1442684Y2037743D02*
X1442543Y2037655D01*
G01X1443243Y2041100D02*
X1442772Y2040805D01*
G01X1442684Y2040893D02*
X1442543Y2040805D01*
G01X1443243Y2044250D02*
X1442772Y2043955D01*
G01X1442684Y2044042D02*
X1442543Y2043955D01*
G01X1443243Y2047400D02*
X1442772Y2047104D01*
G01X1442684Y2047192D02*
X1442543Y2047104D01*
G01X1443243Y2050549D02*
X1442772Y2050254D01*
G01X1442684Y2050342D02*
X1442543Y2050254D01*
G01X1443243Y2053699D02*
X1442772Y2053403D01*
G01X1442684Y2053491D02*
X1442543Y2053403D01*
G01X1443243Y2056848D02*
X1442772Y2056553D01*
G01X1442684Y2056641D02*
X1442543Y2056553D01*
G01X1443243Y2059998D02*
X1442772Y2059703D01*
G01X1442684Y2059790D02*
X1442543Y2059703D01*
G01X1443243Y2063148D02*
X1442772Y2062852D01*
G01X1442684Y2062940D02*
X1442543Y2062852D01*
G01X1443243Y2066297D02*
X1442772Y2066002D01*
G01X1442684Y2066090D02*
X1442543Y2066002D01*
G01X1443243Y2069447D02*
X1442772Y2069151D01*
G01X1442684Y2069239D02*
X1442543Y2069151D01*
G01X1443243Y2072596D02*
X1442772Y2072301D01*
G01X1442684Y2072389D02*
X1442543Y2072301D01*
G01X1443243Y2075746D02*
X1442772Y2075451D01*
G01X1442684Y2075539D02*
X1442543Y2075451D01*
G01X1443243Y2078896D02*
X1442772Y2078600D01*
G01X1442684Y2078688D02*
X1442543Y2078600D01*
G01X1443243Y2082045D02*
X1442772Y2081750D01*
G01X1442684Y2081838D02*
X1442543Y2081750D01*
G01X1469507Y2077774D02*
X1469278Y2077518D01*
G01X1469507Y2080923D02*
X1469278Y2080667D01*
G01X1469507Y2084073D02*
X1469278Y2083817D01*
G01X1439047Y2087103D02*
X1442543Y2087065D01*
G01X1437751Y2087117D02*
X1441007Y2087081D01*
G01X1438785Y2087103D02*
X1436420Y2087129D01*
G01X1441235Y2087081D02*
X1442772Y2087065D01*
G01X1441235Y2087081D02*
X1438785Y2087103D01*
G01X1437751Y2087117D02*
X1436420Y2087129D01*
G01X1438122Y2088607D02*
X1437787D01*
G01X1441235Y2088033D02*
X1441007D01*
G01X1439047Y2088011D02*
X1438785D01*
G01X1439047Y2087103D02*
X1438785D01*
G01X1441235Y2087081D02*
X1441007D01*
G01X1438122Y2085162D02*
X1437954D01*
G01X1439127Y2084998D02*
X1438792D01*
G01X1441235Y2084883D02*
X1441007D01*
G01X1439047Y2084861D02*
X1438785D01*
G01X1440094Y2088023D02*
X1438785Y2088011D01*
G01X1441235Y2088033D02*
X1440094Y2088023D01*
G01Y2084873D02*
X1438785Y2084861D01*
G01X1441235Y2084883D02*
X1440094Y2084873D01*
G01X1437751Y2087997D02*
X1436420Y2087985D01*
G01X1437751Y2084847D02*
X1436420Y2084835D01*
G01X1442543Y2088049D02*
X1441007Y2088033D01*
G01X1442543Y2088049D02*
X1439047Y2088011D01*
G01X1441235Y2088033D02*
X1442772Y2088049D01*
G01X1442543Y2084900D02*
X1441007Y2084883D01*
G01X1442543Y2084900D02*
X1439047Y2084862D01*
G01X1441235Y2084883D02*
X1442772Y2084900D01*
G01X1439047Y2088011D02*
X1440094Y2088023D01*
G01X1438785Y2088011D02*
X1436420Y2087985D01*
G01X1437751Y2087997D02*
X1439047Y2088011D01*
G01Y2084861D02*
X1440094Y2084873D01*
G01X1438785Y2084861D02*
X1436420Y2084835D01*
G01X1437751Y2084847D02*
X1439047Y2084861D01*
G01X1439797Y2088607D02*
X1440300Y2088443D01*
G01X1437619Y2085326D02*
X1437954Y2085162D01*
G01X1437117Y2085818D02*
X1437619Y2085326D01*
G01X1440300Y2088443D02*
X1440635Y2087951D01*
G01X1436446Y2085490D02*
X1436781Y2084998D01*
G01X1440970Y2088771D02*
X1441305Y2088115D01*
G01X1436949Y2086146D02*
X1437117Y2085818D01*
G01X1436279Y2085982D02*
X1436446Y2085490D01*
G01X1436781Y2086802D02*
X1436949Y2086146D01*
G01X1441305Y2088115D02*
X1441472Y2086966D01*
G01X1440635Y2087951D02*
X1440802Y2086802D01*
G01X1436111Y2086966D02*
X1436279Y2085982D01*
G01X1441235Y2088033D02*
Y2087081D01*
G01X1441007Y2088033D02*
Y2087081D01*
G01X1439797Y2089427D02*
Y2088607D01*
G01X1439047Y2088011D02*
Y2087103D01*
G01X1438792Y2089427D02*
Y2084998D01*
G01X1438785Y2088011D02*
Y2087103D01*
G01X1438122Y2088607D02*
Y2085162D01*
G01X1437751Y2087991D02*
Y2087123D01*
G01X1436420Y2087985D02*
Y2087129D01*
G01X1441472Y2086966D02*
X1441305Y2085982D01*
G01X1436949Y2087787D02*
X1436781Y2086802D01*
G01X1436279Y2087951D02*
X1436111Y2086966D01*
G01X1440802Y2086802D02*
X1440635Y2086146D01*
G01X1441305Y2085982D02*
X1441137Y2085490D01*
G01D02*
X1440802Y2084998D01*
G01X1437284Y2088279D02*
X1436949Y2087787D01*
G01X1436781Y2088771D02*
X1436279Y2087951D01*
G01X1440635Y2086146D02*
X1440467Y2085818D01*
G01X1439629Y2085162D02*
X1439127Y2084998D01*
G01X1439965Y2085326D02*
X1439629Y2085162D01*
G01X1437787Y2088607D02*
X1437284Y2088279D01*
G01X1440467Y2085818D02*
X1439965Y2085326D01*
G01X1438457Y2101894D02*
X1437787Y2101730D01*
G01X1438457Y2101074D02*
X1437787Y2100910D01*
G01X1439797Y2097629D02*
X1439127Y2097465D01*
G01X1440300Y2096973D02*
X1439127Y2096645D01*
G01X1438289Y2095333D02*
X1437452Y2095169D01*
G01X1438289Y2094512D02*
X1437452Y2094348D01*
G01X1438122Y2089427D02*
X1437452Y2089263D01*
G01X1439047Y2109150D02*
X1442543Y2109112D01*
G01X1437751Y2109164D02*
X1441007Y2109129D01*
G01X1439047Y2106000D02*
X1442543Y2105963D01*
G01X1437751Y2106015D02*
X1441007Y2105979D01*
G01X1439047Y2102851D02*
X1442543Y2102813D01*
G01X1437751Y2102865D02*
X1441007Y2102829D01*
G01X1439047Y2099701D02*
X1442543Y2099663D01*
G01X1437751Y2099716D02*
X1441007Y2099680D01*
G01X1439047Y2096552D02*
X1442543Y2096514D01*
G01X1437751Y2096566D02*
X1441007Y2096530D01*
G01X1439047Y2093402D02*
X1442543Y2093364D01*
G01X1437751Y2093416D02*
X1441007Y2093381D01*
G01X1439047Y2090252D02*
X1442543Y2090214D01*
G01X1437751Y2090267D02*
X1441007Y2090231D01*
G01X1438785Y2109150D02*
X1436420Y2109176D01*
G01X1438785Y2106001D02*
X1436420Y2106027D01*
G01X1438785Y2102851D02*
X1436420Y2102877D01*
G01X1438785Y2099701D02*
X1436420Y2099727D01*
G01X1438785Y2096552D02*
X1436420Y2096578D01*
G01X1438785Y2093402D02*
X1436420Y2093428D01*
G01X1438785Y2090253D02*
X1436420Y2090279D01*
G01X1441235Y2109129D02*
X1442772Y2109112D01*
G01X1441235Y2105979D02*
X1442772Y2105963D01*
G01X1441235Y2102829D02*
X1442772Y2102813D01*
G01X1441235Y2099680D02*
X1442772Y2099663D01*
G01X1441235Y2096530D02*
X1442772Y2096514D01*
G01X1441235Y2093381D02*
X1442772Y2093364D01*
G01X1441235Y2090231D02*
X1442772Y2090214D01*
G01X1441235Y2109129D02*
X1438785Y2109150D01*
G01X1437751Y2109164D02*
X1436420Y2109176D01*
G01X1441235Y2105979D02*
X1438785Y2106001D01*
G01X1437751Y2106015D02*
X1436420Y2106027D01*
G01X1441235Y2102829D02*
X1438785Y2102851D01*
G01X1437751Y2102865D02*
X1436420Y2102877D01*
G01X1441235Y2099680D02*
X1438785Y2099701D01*
G01X1437751Y2099716D02*
X1436420Y2099727D01*
G01X1441235Y2096530D02*
X1438785Y2096552D01*
G01X1437751Y2096566D02*
X1436420Y2096578D01*
G01X1441235Y2093381D02*
X1438785Y2093402D01*
G01X1437751Y2093416D02*
X1436420Y2093428D01*
G01X1441235Y2090231D02*
X1438785Y2090253D01*
G01X1437751Y2090267D02*
X1436420Y2090279D01*
G01X1449937Y2113541D02*
X1430449D01*
G01X1441235Y2110080D02*
X1441007D01*
G01X1439047Y2110058D02*
X1438785D01*
G01X1439047Y2109150D02*
X1438785D01*
G01X1441235Y2109129D02*
X1441007D01*
G01X1441235Y2106930D02*
X1441007D01*
G01X1439047Y2106909D02*
X1438785D01*
G01X1439047Y2106001D02*
X1438785D01*
G01X1441235Y2105979D02*
X1441007D01*
G01X1441472Y2104027D02*
X1433598D01*
G01X1441235Y2103781D02*
X1441007D01*
G01X1439047Y2103759D02*
X1438785D01*
G01X1441472Y2103207D02*
X1433598D01*
G01X1439047Y2102851D02*
X1438785D01*
G01X1441235Y2102829D02*
X1441007D01*
G01X1439127Y2101894D02*
X1438457D01*
G01X1439127Y2101074D02*
X1438457D01*
G01X1441235Y2100631D02*
X1441007D01*
G01X1439047Y2100610D02*
X1438785D01*
G01X1439047Y2099701D02*
X1438785D01*
G01X1441235Y2099680D02*
X1441007D01*
G01X1441235Y2097481D02*
X1441007D01*
G01X1439127Y2097465D02*
X1438457D01*
G01X1439047Y2097460D02*
X1438785D01*
G01X1439127Y2096645D02*
X1438457D01*
G01X1439047Y2096552D02*
X1438785D01*
G01X1441235Y2096530D02*
X1441007D01*
G01X1441472Y2095333D02*
X1438289D01*
G01X1441472Y2094512D02*
X1438289D01*
G01X1441235Y2094332D02*
X1441007D01*
G01X1439047Y2094310D02*
X1438785D01*
G01X1439047Y2093402D02*
X1438785D01*
G01X1441235Y2093381D02*
X1441007D01*
G01X1436949Y2091560D02*
X1436111D01*
G01X1441472D02*
X1437619D01*
G01X1441235Y2091182D02*
X1441007D01*
G01X1439047Y2091161D02*
X1438785D01*
G01X1441472Y2090739D02*
X1436111D01*
G01X1439047Y2090253D02*
X1438785D01*
G01X1441235Y2090231D02*
X1441007D01*
G01X1438792Y2089427D02*
X1438122D01*
G01X1440094Y2110070D02*
X1438785Y2110058D01*
G01X1441235Y2110080D02*
X1440094Y2110070D01*
G01Y2106920D02*
X1438785Y2106909D01*
G01X1441235Y2106930D02*
X1440094Y2106920D01*
G01Y2103771D02*
X1438785Y2103759D01*
G01X1441235Y2103781D02*
X1440094Y2103771D01*
G01Y2100621D02*
X1438785Y2100610D01*
G01X1441235Y2100631D02*
X1440094Y2100621D01*
G01Y2097471D02*
X1438785Y2097460D01*
G01X1441235Y2097481D02*
X1440094Y2097471D01*
G01Y2094322D02*
X1438785Y2094310D01*
G01X1441235Y2094332D02*
X1440094Y2094322D01*
G01Y2091172D02*
X1438785Y2091161D01*
G01X1441235Y2091182D02*
X1440094Y2091172D01*
G01X1437751Y2110044D02*
X1436420Y2110032D01*
G01X1437751Y2106894D02*
X1436420Y2106883D01*
G01X1437751Y2103745D02*
X1436420Y2103733D01*
G01X1437751Y2100595D02*
X1436420Y2100583D01*
G01X1437751Y2097446D02*
X1436420Y2097434D01*
G01X1437751Y2094296D02*
X1436420Y2094284D01*
G01X1437751Y2091146D02*
X1436420Y2091135D01*
G01X1442543Y2110096D02*
X1441007Y2110080D01*
G01X1442543Y2110096D02*
X1439047Y2110058D01*
G01X1441235Y2110080D02*
X1442772Y2110096D01*
G01X1442543Y2106947D02*
X1441007Y2106930D01*
G01X1442543Y2106947D02*
X1439047Y2106909D01*
G01X1441235Y2106930D02*
X1442772Y2106947D01*
G01X1442543Y2103797D02*
X1441007Y2103781D01*
G01X1442543Y2103797D02*
X1439047Y2103759D01*
G01X1441235Y2103781D02*
X1442772Y2103797D01*
G01X1442543Y2100648D02*
X1441007Y2100631D01*
G01X1442543Y2100648D02*
X1439047Y2100610D01*
G01X1441235Y2100631D02*
X1442772Y2100648D01*
G01X1442543Y2097498D02*
X1441007Y2097481D01*
G01X1442543Y2097498D02*
X1439047Y2097460D01*
G01X1441235Y2097481D02*
X1442772Y2097498D01*
G01X1442543Y2094348D02*
X1441007Y2094332D01*
G01X1442543Y2094348D02*
X1439047Y2094310D01*
G01X1441235Y2094332D02*
X1442772Y2094348D01*
G01X1442543Y2091199D02*
X1441007Y2091182D01*
G01X1442543Y2091199D02*
X1439047Y2091161D01*
G01X1441235Y2091182D02*
X1442772Y2091199D01*
G01X1439047Y2110058D02*
X1440094Y2110070D01*
G01X1438785Y2110058D02*
X1436420Y2110032D01*
G01X1437751Y2110044D02*
X1439047Y2110058D01*
G01Y2106909D02*
X1440094Y2106920D01*
G01X1438785Y2106909D02*
X1436420Y2106883D01*
G01X1437751Y2106894D02*
X1439047Y2106909D01*
G01Y2103759D02*
X1440094Y2103771D01*
G01X1438785Y2103759D02*
X1436420Y2103733D01*
G01X1437751Y2103745D02*
X1439047Y2103759D01*
G01Y2100610D02*
X1440094Y2100621D01*
G01X1438785Y2100610D02*
X1436420Y2100583D01*
G01X1437751Y2100595D02*
X1439047Y2100610D01*
G01Y2097460D02*
X1440094Y2097471D01*
G01X1438785Y2097460D02*
X1436420Y2097434D01*
G01X1437751Y2097446D02*
X1439047Y2097460D01*
G01Y2094310D02*
X1440094Y2094322D01*
G01X1438785Y2094310D02*
X1436420Y2094284D01*
G01X1437751Y2094296D02*
X1439047Y2094310D01*
G01Y2091161D02*
X1440094Y2091172D01*
G01X1438785Y2091161D02*
X1436420Y2091135D01*
G01X1437751Y2091146D02*
X1439047Y2091161D01*
G01X1437284Y2096973D02*
X1437787Y2096809D01*
G01X1439127Y2101894D02*
X1440300Y2101566D01*
G01X1439797Y2100910D02*
X1439127Y2101074D01*
G01X1438457Y2097465D02*
X1437787Y2097629D01*
G01X1438457Y2096645D02*
X1437787Y2096809D01*
G01X1440467Y2089263D02*
X1439797Y2089427D01*
G01X1426512Y2115510D02*
X1430449Y2113541D01*
G01X1440300Y2101566D02*
X1440802Y2101238D01*
G01X1439797Y2100910D02*
X1440300Y2100582D01*
G01X1437284Y2097957D02*
X1437787Y2097629D01*
G01X1436781Y2097301D02*
X1437284Y2096973D01*
G01X1440802Y2101238D02*
X1441137Y2100910D01*
G01X1440300Y2100582D02*
X1440635Y2100254D01*
G01X1436949Y2098285D02*
X1437284Y2097957D01*
G01X1436446Y2097629D02*
X1436781Y2097301D01*
G01X1440467Y2089263D02*
X1440970Y2088771D01*
G01X1437284Y2091888D02*
X1437619Y2091560D01*
G01X1436614Y2091888D02*
X1436949Y2091560D01*
G01Y2092380D02*
X1437284Y2091888D01*
G01X1436279Y2092380D02*
X1436614Y2091888D01*
G01X1441137Y2100910D02*
X1441305Y2100582D01*
G01X1436279Y2097957D02*
X1436446Y2097629D01*
G01X1441305Y2100582D02*
X1441472Y2099926D01*
G01X1440635Y2100254D02*
X1440802Y2099598D01*
G01X1436781Y2098942D02*
X1436949Y2098285D01*
G01X1436111Y2098613D02*
X1436279Y2097957D01*
G01X1436781Y2093036D02*
X1436949Y2092380D01*
G01X1436111Y2093036D02*
X1436279Y2092380D01*
G01X1441235Y2091182D02*
Y2090231D01*
G01Y2094332D02*
Y2093381D01*
G01Y2097481D02*
Y2096530D01*
G01Y2103781D02*
Y2102829D01*
G01Y2100631D02*
Y2099680D01*
G01Y2106930D02*
Y2105979D01*
G01Y2110080D02*
Y2109129D01*
G01X1441007Y2091182D02*
Y2090231D01*
G01Y2094332D02*
Y2093381D01*
G01Y2097481D02*
Y2096530D01*
G01Y2103781D02*
Y2102829D01*
G01Y2100631D02*
Y2099680D01*
G01Y2106930D02*
Y2105979D01*
G01Y2110080D02*
Y2109129D01*
G01X1440802Y2099598D02*
Y2098942D01*
G01X1439047Y2091161D02*
Y2090252D01*
G01Y2094310D02*
Y2093402D01*
G01Y2100610D02*
Y2099701D01*
G01Y2097460D02*
Y2096552D01*
G01Y2103759D02*
Y2102851D01*
G01Y2106909D02*
Y2106000D01*
G01Y2110058D02*
Y2109150D01*
G01X1438785Y2091161D02*
Y2090253D01*
G01Y2094310D02*
Y2093402D01*
G01Y2100610D02*
Y2099701D01*
G01Y2097460D02*
Y2096552D01*
G01Y2103759D02*
Y2102851D01*
G01Y2106909D02*
Y2106001D01*
G01Y2110058D02*
Y2109150D01*
G01X1437751Y2091141D02*
Y2090273D01*
G01Y2094290D02*
Y2093422D01*
G01Y2100589D02*
Y2099721D01*
G01Y2097440D02*
Y2096572D01*
G01Y2103739D02*
Y2102871D01*
G01Y2106889D02*
Y2106021D01*
G01Y2110038D02*
Y2109170D01*
G01X1436781Y2099598D02*
Y2098942D01*
G01X1436420Y2091135D02*
Y2090279D01*
G01Y2094284D02*
Y2093428D01*
G01Y2100583D02*
Y2099727D01*
G01Y2097434D02*
Y2096578D01*
G01Y2103733D02*
Y2102877D01*
G01Y2106883D02*
Y2106027D01*
G01Y2110032D02*
Y2109176D01*
G01X1436111Y2091560D02*
Y2090739D01*
G01Y2093692D02*
Y2093036D01*
G01Y2099926D02*
Y2098613D01*
G01X1433598Y2104027D02*
Y2103207D01*
G01X1426512Y2120628D02*
Y2115510D01*
G01X1441472Y2098613D02*
X1441305Y2097957D01*
G01X1440802Y2098942D02*
X1440635Y2098285D01*
G01X1436949Y2093692D02*
X1436781Y2093036D01*
G01X1436949Y2100254D02*
X1436781Y2099598D01*
G01X1436279Y2100582D02*
X1436111Y2099926D01*
G01X1436279Y2094184D02*
X1436111Y2093692D01*
G01X1436614Y2094676D02*
X1436279Y2094184D01*
G01X1441305Y2097957D02*
X1441137Y2097629D01*
G01X1437117Y2094020D02*
X1436949Y2093692D01*
G01X1436446Y2100910D02*
X1436279Y2100582D01*
G01X1437452Y2095169D02*
X1436949Y2095005D01*
G01X1437787Y2101730D02*
X1437284Y2101566D01*
G01X1440802Y2097301D02*
X1440300Y2096973D01*
G01Y2097957D02*
X1439797Y2097629D01*
G01X1437452Y2089263D02*
X1436781Y2088771D01*
G01X1441137Y2097629D02*
X1440802Y2097301D01*
G01X1437452Y2094348D02*
X1437117Y2094020D01*
G01X1440635Y2098285D02*
X1440300Y2097957D01*
G01X1436949Y2095005D02*
X1436614Y2094676D01*
G01X1437284Y2100582D02*
X1436949Y2100254D01*
G01X1436781Y2101238D02*
X1436446Y2100910D01*
G01X1437787D02*
X1437284Y2100582D01*
G01Y2101566D02*
X1436781Y2101238D01*
G01X1444212Y2088344D02*
X1443073D01*
G01X1469631Y2088148D02*
X1457535D01*
G01X1442772Y2088049D02*
X1442543D01*
G01X1470921Y2087892D02*
X1469507D01*
G01X1470921Y2087222D02*
X1469507D01*
G01X1442772Y2087065D02*
X1442543D01*
G01X1469631Y2086966D02*
X1457535D01*
G01X1444212Y2086770D02*
X1443073D01*
G01X1457732Y2086376D02*
X1457220D01*
G01X1457732Y2085588D02*
X1457220D01*
G01X1444212Y2085195D02*
X1443073D01*
G01X1469631Y2084998D02*
X1457535D01*
G01X1442772Y2084900D02*
X1442543D01*
G01X1442684Y2086977D02*
X1443073Y2086770D01*
G01X1442772Y2087065D02*
X1443243Y2086770D01*
G01X1442543Y2087065D02*
X1442684Y2086977D01*
G01X1469278Y2088148D02*
X1469507Y2087892D01*
G01X1469636Y2088162D02*
X1469855Y2087892D01*
G01X1470921D02*
Y2087222D01*
G01X1470574Y2087892D02*
Y2087222D01*
G01X1469631Y2088148D02*
Y2086966D01*
G01X1469278Y2088148D02*
Y2086966D01*
G01X1467296Y2088148D02*
Y2086966D01*
G01X1467186Y2088148D02*
Y2086966D01*
G01X1458405Y2088148D02*
Y2086966D01*
G01X1458295Y2088148D02*
Y2086966D01*
G01X1457929Y2088148D02*
Y2086966D01*
G01X1457732Y2085588D02*
Y2084998D01*
G01Y2086966D02*
Y2086376D01*
G01Y2088738D02*
Y2088148D01*
G01X1457535Y2085588D02*
Y2084998D01*
G01Y2086966D02*
Y2086376D01*
G01Y2088738D02*
Y2088148D01*
G01X1444212Y2088344D02*
Y2086770D01*
G01X1442684Y2088137D02*
Y2086977D01*
G01X1469855Y2087222D02*
X1469636Y2086952D01*
G01X1443073Y2085195D02*
X1442684Y2084987D01*
G01X1443073Y2088344D02*
X1442684Y2088137D01*
G01X1443243Y2085195D02*
X1442772Y2084900D01*
G01X1442684Y2084987D02*
X1442543Y2084900D01*
G01X1443243Y2088344D02*
X1442772Y2088049D01*
G01X1442684Y2088137D02*
X1442543Y2088049D01*
G01X1469507Y2087222D02*
X1469278Y2086966D01*
G01X1469048Y2140707D02*
G03Y2132045I-17J-4331D01*
G01X1469081D02*
G03Y2140706I-50J4331D01*
G01X1473362Y2136376D02*
G03I-4331J0D01*
G01X1469113Y2140706D02*
X1448165Y2141100D01*
G01D02*
X1469034Y2140707D01*
G01X1479661Y2150155D02*
X1448165D01*
G01X1479661Y2140707D02*
X1469031D01*
G01X1479661Y2132045D02*
X1469031D01*
G01X1479661Y2120628D02*
X1461157D01*
G01X1469038Y2132045D02*
X1448165Y2131651D01*
G01X1469113Y2132046D02*
X1448165Y2131651D01*
G01X1457732Y2110785D02*
X1457220D01*
G01X1444212Y2110392D02*
X1443073D01*
G01X1469631Y2110195D02*
X1457535D01*
G01X1442772Y2110096D02*
X1442543D01*
G01X1470921Y2109939D02*
X1469507D01*
G01X1470921Y2109270D02*
X1469507D01*
G01X1442772Y2109112D02*
X1442543D01*
G01X1469631Y2109014D02*
X1457535D01*
G01X1444212Y2108817D02*
X1443073D01*
G01X1457732Y2108423D02*
X1457220D01*
G01X1457732Y2107636D02*
X1457220D01*
G01X1444212Y2107242D02*
X1443073D01*
G01X1469631Y2107045D02*
X1457535D01*
G01X1442772Y2106947D02*
X1442543D01*
G01X1470921Y2106789D02*
X1469507D01*
G01X1470921Y2106120D02*
X1469507D01*
G01X1442772Y2105963D02*
X1442543D01*
G01X1469631Y2105864D02*
X1457535D01*
G01X1444212Y2105667D02*
X1443073D01*
G01X1457732Y2105274D02*
X1457220D01*
G01X1457732Y2104486D02*
X1457220D01*
G01X1444212Y2104092D02*
X1443073D01*
G01X1469631Y2103896D02*
X1457535D01*
G01X1442772Y2103797D02*
X1442543D01*
G01X1470921Y2103640D02*
X1469507D01*
G01X1470921Y2102970D02*
X1469507D01*
G01X1442772Y2102813D02*
X1442543D01*
G01X1469631Y2102714D02*
X1457535D01*
G01X1444212Y2102518D02*
X1443073D01*
G01X1457732Y2102124D02*
X1457220D01*
G01X1457732Y2101337D02*
X1457220D01*
G01X1444212Y2100943D02*
X1443073D01*
G01X1469631Y2100746D02*
X1457535D01*
G01X1442772Y2100648D02*
X1442543D01*
G01X1470921Y2100490D02*
X1469507D01*
G01X1470921Y2099821D02*
X1469507D01*
G01X1442772Y2099663D02*
X1442543D01*
G01X1469631Y2099565D02*
X1457535D01*
G01X1444212Y2099368D02*
X1443073D01*
G01X1457732Y2098974D02*
X1457220D01*
G01X1457732Y2098187D02*
X1457220D01*
G01X1444212Y2097793D02*
X1443073D01*
G01X1469631Y2097596D02*
X1457535D01*
G01X1442772Y2097498D02*
X1442543D01*
G01X1470921Y2097340D02*
X1469507D01*
G01X1470921Y2096671D02*
X1469507D01*
G01X1442772Y2096514D02*
X1442543D01*
G01X1469631Y2096415D02*
X1457535D01*
G01X1444212Y2096218D02*
X1443073D01*
G01X1457732Y2095825D02*
X1457220D01*
G01X1457732Y2095037D02*
X1457220D01*
G01X1444212Y2094644D02*
X1443073D01*
G01X1469631Y2094447D02*
X1457535D01*
G01X1442772Y2094348D02*
X1442543D01*
G01X1470921Y2094191D02*
X1469507D01*
G01X1470921Y2093522D02*
X1469507D01*
G01X1442772Y2093364D02*
X1442543D01*
G01X1469631Y2093266D02*
X1457535D01*
G01X1444212Y2093069D02*
X1443073D01*
G01X1457732Y2092675D02*
X1457220D01*
G01X1457732Y2091888D02*
X1457220D01*
G01X1444212Y2091494D02*
X1443073D01*
G01X1469631Y2091297D02*
X1457535D01*
G01X1442772Y2091199D02*
X1442543D01*
G01X1470921Y2091041D02*
X1469507D01*
G01X1470921Y2090372D02*
X1469507D01*
G01X1442772Y2090214D02*
X1442543D01*
G01X1469631Y2090116D02*
X1457535D01*
G01X1444212Y2089919D02*
X1443073D01*
G01X1457732Y2089525D02*
X1457220D01*
G01X1457732Y2088738D02*
X1457220D01*
G01X1442684Y2109024D02*
X1443073Y2108817D01*
G01X1442684Y2105875D02*
X1443073Y2105667D01*
G01X1442684Y2102725D02*
X1443073Y2102518D01*
G01X1442684Y2099575D02*
X1443073Y2099368D01*
G01X1442684Y2096426D02*
X1443073Y2096218D01*
G01X1442684Y2093276D02*
X1443073Y2093069D01*
G01X1442684Y2090127D02*
X1443073Y2089919D01*
G01X1442772Y2109112D02*
X1443243Y2108817D01*
G01X1442543Y2109112D02*
X1442684Y2109024D01*
G01X1442772Y2105963D02*
X1443243Y2105667D01*
G01X1442543Y2105963D02*
X1442684Y2105875D01*
G01X1442772Y2102813D02*
X1443243Y2102518D01*
G01X1442543Y2102813D02*
X1442684Y2102725D01*
G01X1442772Y2099663D02*
X1443243Y2099368D01*
G01X1442543Y2099663D02*
X1442684Y2099575D01*
G01X1442772Y2096514D02*
X1443243Y2096218D01*
G01X1442543Y2096514D02*
X1442684Y2096426D01*
G01X1442772Y2093364D02*
X1443243Y2093069D01*
G01X1442543Y2093364D02*
X1442684Y2093276D01*
G01X1442772Y2090214D02*
X1443243Y2089919D01*
G01X1442543Y2090214D02*
X1442684Y2090127D01*
G01X1469278Y2110195D02*
X1469507Y2109939D01*
G01X1469278Y2107045D02*
X1469507Y2106789D01*
G01X1469278Y2103896D02*
X1469507Y2103640D01*
G01X1469278Y2100746D02*
X1469507Y2100490D01*
G01X1469278Y2097596D02*
X1469507Y2097340D01*
G01X1469278Y2094447D02*
X1469507Y2094191D01*
G01X1469278Y2091297D02*
X1469507Y2091041D01*
G01X1469636Y2110209D02*
X1469855Y2109939D01*
G01X1469636Y2107059D02*
X1469855Y2106789D01*
G01X1469636Y2103910D02*
X1469855Y2103640D01*
G01X1469636Y2100760D02*
X1469855Y2100490D01*
G01X1469636Y2097610D02*
X1469855Y2097340D01*
G01X1469636Y2094461D02*
X1469855Y2094191D01*
G01X1469636Y2091311D02*
X1469855Y2091041D01*
G01X1479661Y2150155D02*
Y2120628D01*
G01X1470921Y2091041D02*
Y2090372D01*
G01Y2094191D02*
Y2093522D01*
G01Y2100490D02*
Y2099821D01*
G01Y2097340D02*
Y2096671D01*
G01Y2103640D02*
Y2102970D01*
G01Y2109939D02*
Y2109270D01*
G01Y2106789D02*
Y2106120D01*
G01X1470574Y2091041D02*
Y2090372D01*
G01Y2094191D02*
Y2093522D01*
G01Y2100490D02*
Y2099821D01*
G01Y2097340D02*
Y2096671D01*
G01Y2103640D02*
Y2102970D01*
G01Y2109939D02*
Y2109270D01*
G01Y2106789D02*
Y2106120D01*
G01X1469631Y2094447D02*
Y2093266D01*
G01Y2091297D02*
Y2090116D01*
G01Y2097596D02*
Y2096415D01*
G01Y2103896D02*
Y2102714D01*
G01Y2100746D02*
Y2099565D01*
G01Y2107045D02*
Y2105864D01*
G01Y2110195D02*
Y2109014D01*
G01X1469278Y2094447D02*
Y2093266D01*
G01Y2091297D02*
Y2090116D01*
G01Y2097596D02*
Y2096415D01*
G01Y2103896D02*
Y2102714D01*
G01Y2100746D02*
Y2099565D01*
G01Y2107045D02*
Y2105864D01*
G01Y2110195D02*
Y2109014D01*
G01X1467296Y2094447D02*
Y2093266D01*
G01Y2091297D02*
Y2090116D01*
G01Y2097596D02*
Y2096415D01*
G01Y2103896D02*
Y2102714D01*
G01Y2100746D02*
Y2099565D01*
G01Y2107045D02*
Y2105864D01*
G01Y2110195D02*
Y2109014D01*
G01X1467186Y2094447D02*
Y2093266D01*
G01Y2091297D02*
Y2090116D01*
G01Y2097596D02*
Y2096415D01*
G01Y2103896D02*
Y2102714D01*
G01Y2100746D02*
Y2099565D01*
G01Y2107045D02*
Y2105864D01*
G01Y2110195D02*
Y2109014D01*
G01X1458405Y2094447D02*
Y2093266D01*
G01Y2091297D02*
Y2090116D01*
G01Y2097596D02*
Y2096415D01*
G01Y2103896D02*
Y2102714D01*
G01Y2100746D02*
Y2099565D01*
G01Y2107045D02*
Y2105864D01*
G01Y2110195D02*
Y2109014D01*
G01X1458295Y2094447D02*
Y2093266D01*
G01Y2091297D02*
Y2090116D01*
G01Y2097596D02*
Y2096415D01*
G01Y2103896D02*
Y2102714D01*
G01Y2100746D02*
Y2099565D01*
G01Y2107045D02*
Y2105864D01*
G01Y2110195D02*
Y2109014D01*
G01X1457929Y2094447D02*
Y2093266D01*
G01Y2091297D02*
Y2090116D01*
G01Y2097596D02*
Y2096415D01*
G01Y2103896D02*
Y2102714D01*
G01Y2100746D02*
Y2099565D01*
G01Y2107045D02*
Y2105864D01*
G01Y2110195D02*
Y2109014D01*
G01X1457732Y2090116D02*
Y2089525D01*
G01Y2093266D02*
Y2092675D01*
G01Y2095037D02*
Y2094447D01*
G01Y2091888D02*
Y2091297D01*
G01Y2099565D02*
Y2098974D01*
G01Y2096415D02*
Y2095825D01*
G01Y2098187D02*
Y2097596D01*
G01Y2102714D02*
Y2102124D01*
G01Y2104486D02*
Y2103896D01*
G01Y2101337D02*
Y2100746D01*
G01Y2109014D02*
Y2108423D01*
G01Y2105864D02*
Y2105274D01*
G01Y2107636D02*
Y2107045D01*
G01Y2110785D02*
Y2110195D01*
G01X1457535Y2090116D02*
Y2089525D01*
G01Y2093266D02*
Y2092675D01*
G01Y2095037D02*
Y2094447D01*
G01Y2091888D02*
Y2091297D01*
G01Y2099565D02*
Y2098974D01*
G01Y2096415D02*
Y2095825D01*
G01Y2098187D02*
Y2097596D01*
G01Y2102714D02*
Y2102124D01*
G01Y2104486D02*
Y2103896D01*
G01Y2101337D02*
Y2100746D01*
G01Y2109014D02*
Y2108423D01*
G01Y2105864D02*
Y2105274D01*
G01Y2107636D02*
Y2107045D01*
G01Y2110785D02*
Y2110195D01*
G01X1448165Y2150155D02*
Y2129289D01*
G01X1444212Y2094644D02*
Y2093069D01*
G01Y2091494D02*
Y2089919D01*
G01Y2097793D02*
Y2096218D01*
G01Y2104092D02*
Y2102518D01*
G01Y2100943D02*
Y2099368D01*
G01Y2107242D02*
Y2105667D01*
G01Y2110392D02*
Y2108817D01*
G01X1442684Y2094436D02*
Y2093276D01*
G01Y2091287D02*
Y2090127D01*
G01Y2097586D02*
Y2096426D01*
G01Y2103885D02*
Y2102725D01*
G01Y2100735D02*
Y2099575D01*
G01Y2107035D02*
Y2105875D01*
G01Y2110184D02*
Y2109024D01*
G01X1441472Y2095333D02*
Y2094512D01*
G01Y2091560D02*
Y2090739D01*
G01Y2099926D02*
Y2098613D01*
G01Y2104027D02*
Y2103207D01*
G01X1469855Y2090372D02*
X1469636Y2090102D01*
G01X1469855Y2093522D02*
X1469636Y2093252D01*
G01X1469855Y2096671D02*
X1469636Y2096401D01*
G01X1443073Y2091494D02*
X1442684Y2091287D01*
G01X1443073Y2094644D02*
X1442684Y2094436D01*
G01X1443073Y2097793D02*
X1442684Y2097586D01*
G01X1443073Y2100943D02*
X1442684Y2100735D01*
G01X1443073Y2104092D02*
X1442684Y2103885D01*
G01X1443243Y2091494D02*
X1442772Y2091199D01*
G01X1442684Y2091287D02*
X1442543Y2091199D01*
G01X1443243Y2094644D02*
X1442772Y2094348D01*
G01X1442684Y2094436D02*
X1442543Y2094348D01*
G01X1443243Y2097793D02*
X1442772Y2097498D01*
G01X1442684Y2097586D02*
X1442543Y2097498D01*
G01X1443243Y2100943D02*
X1442772Y2100648D01*
G01X1442684Y2100735D02*
X1442543Y2100648D01*
G01X1461157Y2120628D02*
X1457220Y2116691D01*
G01X1469507Y2090372D02*
X1469278Y2090116D01*
G01X1469507Y2093522D02*
X1469278Y2093266D01*
G01X1469507Y2096671D02*
X1469278Y2096415D01*
G01X1469507Y2099821D02*
X1469278Y2099565D01*
G01X1469507Y2102970D02*
X1469278Y2102714D01*
G01X1469507Y2106120D02*
X1469278Y2105864D01*
G01X1469507Y2109270D02*
X1469278Y2109014D01*
G01X1469855Y2099821D02*
X1469636Y2099551D01*
G01X1469855Y2102970D02*
X1469636Y2102700D01*
G01X1469855Y2106120D02*
X1469636Y2105850D01*
G01X1469855Y2109270D02*
X1469636Y2109000D01*
G01X1443073Y2107242D02*
X1442684Y2107035D01*
G01X1443073Y2110392D02*
X1442684Y2110184D01*
G01X1443243Y2104092D02*
X1442772Y2103797D01*
G01X1442684Y2103885D02*
X1442543Y2103797D01*
G01X1443243Y2107242D02*
X1442772Y2106947D01*
G01X1442684Y2107035D02*
X1442543Y2106947D01*
G01X1443243Y2110392D02*
X1442772Y2110096D01*
G01X1442684Y2110184D02*
X1442543Y2110096D01*
G01X1488553Y2201466D02*
G03I-985J0D01*
G01X1484878Y2205141D02*
G03I-984J0D01*
G01X1487024Y2224124D02*
G03I-4292J0D01*
G01X1489898Y2196447D02*
G03I-985J0D01*
G01X1484779Y2192311D02*
G03X1485904Y2189556I3937J1D01*
G01X1484779Y2196447D02*
G03X1472968I-5906J0D01*
G01X1484779D02*
G03X1472968I-5906J0D01*
G01X1485173D02*
G03I-6299J0D01*
G01X1486748D02*
G03X1471000I-7874J0D01*
G01X1492653D02*
G03X1465094I-13780J0D01*
G01X1494622D02*
G03X1463126I-15748J0D01*
G01X1494622D02*
G03X1463126I-15748J0D01*
G01X1494622D02*
G03X1463126I-15748J0D01*
G01X1471844Y2189556D02*
G03X1485904I7030J-6889D01*
G01X1463126Y2182667D02*
G03X1494622I15748J0D01*
G01X1463126D02*
G03X1494622I15748J0D01*
G01X1463126D02*
G03X1494622I15748J0D01*
G01X1474838Y2205141D02*
G03I-984J0D01*
G01X1471164Y2201466D02*
G03I-984J0D01*
G01X1469819Y2196447D02*
G03I-984J0D01*
G01X1471844Y2189556D02*
G03X1472968Y2192311I-2813J2754D01*
G01X1484779Y2194085D02*
X1492653D01*
G01X1465094D02*
X1472968D01*
G01X1492653D02*
Y2196447D01*
G01X1486748Y2194085D02*
Y2196447D01*
G01X1484779Y2192311D02*
Y2196447D01*
G01D02*
Y2194085D01*
G01X1472968D02*
Y2196447D01*
G01D02*
Y2192311D01*
G01X1471000Y2196447D02*
Y2194085D01*
G01X1465094Y2196447D02*
Y2194085D01*
G01X1463126Y2182667D02*
Y2196447D01*
G01Y2182667D02*
Y2196447D01*
G01Y2182667D02*
Y2196447D01*
G01X1482732Y2228061D02*
Y2300777D01*
G01X1478874Y2196705D02*
Y2280621D01*
G01X1461157Y2265738D02*
G03X1457220Y2261801I0J-3937D01*
G01X1461157Y2265738D02*
X2490685D01*
G01X1478874Y2280621D02*
X1454283Y2300777D01*
G01X1477680Y2307057D02*
X1476236Y2307544D01*
X1475514Y2309006D01*
X1476236Y2310467D01*
X1477680Y2310955D01*
X1479123Y2310467D01*
X1479845Y2309980D01*
X1480567Y2309006D01*
X1479845Y2308031D01*
X1479123Y2307544D01*
X1477680Y2307057D01*
X1474793D01*
X1473349Y2307544D01*
X1472627Y2308031D01*
X1471905Y2309006D01*
X1472627Y2309980D01*
X1473349Y2310467D01*
G01X1443304Y2310955D02*
Y2308031D01*
X1446913Y2307544D01*
X1446191Y2308519D01*
Y2309493D01*
X1446913Y2310467D01*
X1447635Y2310955D01*
X1449079Y2311442D01*
X1450522Y2310955D01*
X1451244Y2310467D01*
X1451966Y2309493D01*
Y2308519D01*
X1451244Y2307544D01*
X1450522Y2307057D01*
G01X1477680Y2334828D02*
X1478401D01*
X1479845Y2333853D01*
G01X1478401Y2329955D02*
X1477680D01*
X1476236Y2330930D01*
G01X1480567Y2326058D02*
X1471905D01*
X1478401Y2322648D01*
Y2327032D01*
G01X1479845Y2333853D02*
X1480567Y2332879D01*
Y2331904D01*
G01X1476236Y2330930D02*
X1475514Y2331904D01*
Y2332879D01*
X1476236Y2333853D01*
X1477680Y2334828D01*
G01X1480567Y2316801D02*
Y2316314D01*
X1479845D01*
X1480567Y2316801D01*
G01X1451966D02*
Y2316314D01*
X1451244D01*
X1451966Y2316801D01*
G01X1443304Y2326545D02*
Y2323622D01*
X1446913Y2323135D01*
X1446191Y2324109D01*
Y2325084D01*
X1446913Y2326058D01*
X1447635Y2326545D01*
X1449079Y2327032D01*
X1450522Y2326545D01*
X1451244Y2326058D01*
X1451966Y2325084D01*
Y2324109D01*
X1451244Y2323135D01*
X1450522Y2322648D01*
G01X1480567Y2331904D02*
X1479845Y2330930D01*
X1478401Y2329955D01*
G01X1475514Y2331904D02*
X1474793Y2330930D01*
X1474071Y2330443D01*
X1473349D01*
X1472627Y2330930D01*
X1471905Y2331904D01*
Y2332879D01*
X1472627Y2333853D01*
X1473349Y2334340D01*
X1474071D01*
X1474793Y2333853D01*
X1475514Y2332879D01*
G01X1451966Y2332392D02*
X1451244Y2331417D01*
X1450522Y2330930D01*
X1449079Y2330443D01*
X1446191D01*
X1444748Y2330930D01*
X1444026Y2331417D01*
X1443304Y2332392D01*
X1444026Y2333366D01*
X1444748Y2333853D01*
X1446191Y2334340D01*
X1449079D01*
X1450522Y2333853D01*
X1451244Y2333366D01*
X1451966Y2332392D01*
G01X1494330Y-172119D02*
Y-191056D01*
G01X1513323Y187352D02*
X1521984D01*
G01X1552365Y188814D02*
X1553808Y186865D01*
X1555252Y185891D01*
X1557417Y185403D01*
Y189301D01*
G01X1550199Y185403D02*
X1549478Y185891D01*
X1548756Y186865D01*
Y187839D01*
X1549478Y188814D01*
X1550199Y189301D01*
X1551643D01*
X1552365Y188814D01*
G01X1513323Y197096D02*
Y193199D01*
G01X1521984Y210738D02*
X1521262Y209764D01*
X1520541Y209276D01*
X1519097Y208789D01*
X1516210D01*
X1514766Y209276D01*
X1514044Y209764D01*
X1513323Y210738D01*
X1514044Y211713D01*
X1514766Y212200D01*
X1516210Y212687D01*
X1519097D01*
X1520541Y212200D01*
X1521262Y211713D01*
X1521984Y210738D01*
G01Y218533D02*
X1521262Y217559D01*
X1520541Y217072D01*
X1519097Y216585D01*
X1516210D01*
X1514766Y217072D01*
X1514044Y217559D01*
X1513323Y218533D01*
X1514044Y219508D01*
X1514766Y219995D01*
X1516210Y220482D01*
X1519097D01*
X1520541Y219995D01*
X1521262Y219508D01*
X1521984Y218533D01*
G01Y195148D02*
X1518375Y195635D01*
X1516210Y196122D01*
X1513323Y197096D01*
G01X1554530Y193199D02*
X1553087Y193686D01*
X1552365Y195148D01*
X1553087Y196609D01*
X1554530Y197096D01*
X1555974Y196609D01*
X1556695Y196122D01*
X1557417Y195148D01*
X1556695Y194173D01*
X1555974Y193686D01*
X1554530Y193199D01*
X1551643D01*
X1550199Y193686D01*
X1549478Y194173D01*
X1548756Y195148D01*
X1549478Y196122D01*
X1550199Y196609D01*
G01X1557417Y218533D02*
X1556695Y217559D01*
X1555974Y217072D01*
X1554530Y216585D01*
X1551643D01*
X1550199Y217072D01*
X1549478Y217559D01*
X1548756Y218533D01*
X1549478Y219508D01*
X1550199Y219995D01*
X1551643Y220482D01*
X1554530D01*
X1555974Y219995D01*
X1556695Y219508D01*
X1557417Y218533D01*
G01Y210738D02*
X1556695Y209764D01*
X1555974Y209276D01*
X1554530Y208789D01*
X1551643D01*
X1550199Y209276D01*
X1549478Y209764D01*
X1548756Y210738D01*
X1549478Y211713D01*
X1550199Y212200D01*
X1551643Y212687D01*
X1554530D01*
X1555974Y212200D01*
X1556695Y211713D01*
X1557417Y210738D01*
G01Y202943D02*
Y202456D01*
X1556695D01*
X1557417Y202943D01*
G01X1521984D02*
Y202456D01*
X1521262D01*
X1521984Y202943D01*
G01X1559583Y311676D02*
Y226762D01*
G01X1524149Y471755D02*
Y226762D01*
G01X1501709Y310955D02*
X1499740Y308986D01*
G01X1509749Y313986D02*
X1510176Y314577D01*
G01X1509749Y318986D02*
X1510176Y319577D01*
G01X1509749Y323986D02*
X1510176Y324577D01*
G01X1507781Y328986D02*
X1508207Y329577D01*
G01X1509749Y333986D02*
X1510176Y334577D01*
G01X1504004Y315561D02*
X1503865Y315365D01*
X1503727Y315168D01*
X1503590Y314970D01*
G01X1504004Y320561D02*
X1503865Y320365D01*
X1503727Y320168D01*
X1503590Y319970D01*
G01X1504004Y325561D02*
X1503865Y325365D01*
X1503727Y325168D01*
X1503590Y324970D01*
G01X1502036Y330561D02*
X1501896Y330365D01*
X1501758Y330168D01*
X1501621Y329970D01*
G01X1504004Y335561D02*
X1503865Y335365D01*
X1503727Y335168D01*
X1503590Y334970D01*
G01X1509332Y314577D02*
X1509060Y313986D01*
G01X1509332Y319577D02*
X1509060Y318986D01*
G01X1509332Y324577D02*
X1509060Y323986D01*
G01X1507364Y329577D02*
X1507091Y328986D01*
G01X1509332Y334577D02*
X1509060Y333986D01*
G01X1503727Y328179D02*
X1503760Y328278D01*
X1503848Y328349D01*
X1503974Y328376D01*
G01X1497714Y298417D02*
X1497767Y298794D01*
G01X1508208Y314577D02*
X1508130Y313986D01*
G01Y318986D02*
X1508208Y319577D01*
G01Y324577D02*
X1508130Y323986D01*
G01X1508208Y334577D02*
X1508130Y333986D01*
G01X1506239Y329577D02*
X1506161Y328986D01*
G01X1497714Y298419D02*
X1497677Y298095D01*
X1497683Y297854D01*
X1497740Y297718D01*
G01X1508648Y315187D02*
X1508638Y315089D01*
X1508610Y315016D01*
X1508572Y314990D01*
G01X1508648Y318337D02*
X1508638Y318238D01*
X1508610Y318166D01*
X1508572Y318140D01*
G01X1508648Y321486D02*
X1508638Y321388D01*
X1508610Y321316D01*
X1508572Y321289D01*
G01X1508648Y324636D02*
X1508638Y324537D01*
X1508610Y324465D01*
X1508572Y324439D01*
G01X1508648Y327785D02*
X1508638Y327687D01*
X1508610Y327615D01*
X1508572Y327588D01*
G01X1508648Y330935D02*
X1508638Y330837D01*
X1508610Y330765D01*
X1508572Y330738D01*
G01X1508648Y334085D02*
X1508638Y333986D01*
X1508610Y333914D01*
X1508572Y333888D01*
G01X1508648Y337234D02*
X1508638Y337136D01*
X1508610Y337064D01*
X1508572Y337037D01*
G01X1510338Y337234D02*
Y337628D01*
G01Y334085D02*
Y334478D01*
G01Y330935D02*
Y331329D01*
G01Y327785D02*
Y328179D01*
G01Y324636D02*
Y325029D01*
G01Y321486D02*
Y321880D01*
G01Y318337D02*
Y318730D01*
G01Y315187D02*
Y315581D01*
G01X1510176Y314970D02*
Y314577D01*
G01Y319970D02*
Y319577D01*
G01Y324970D02*
Y324577D01*
G01Y334970D02*
Y334577D01*
G01X1509332Y314970D02*
Y314577D01*
G01Y319970D02*
Y319577D01*
G01Y324970D02*
Y324577D01*
G01Y334970D02*
Y334577D01*
G01X1509161Y337234D02*
Y337628D01*
G01Y334085D02*
Y334478D01*
G01Y330935D02*
Y331329D01*
G01Y327785D02*
Y328179D01*
G01Y324636D02*
Y325029D01*
G01Y321486D02*
Y321880D01*
G01Y318337D02*
Y318730D01*
G01Y315187D02*
Y315581D01*
G01X1508648D02*
Y315187D01*
G01Y318730D02*
Y318337D01*
G01Y325029D02*
Y324636D01*
G01Y321880D02*
Y321486D01*
G01Y328179D02*
Y327785D01*
G01Y334478D02*
Y334085D01*
G01Y331329D02*
Y330935D01*
G01Y337628D02*
Y337234D01*
G01X1508208Y334577D02*
Y334970D01*
G01Y324577D02*
Y324970D01*
G01Y314577D02*
Y314970D01*
G01Y319970D02*
Y319577D01*
G01X1508207Y329970D02*
Y329577D01*
G01X1507364Y329970D02*
Y329577D01*
G01X1506239D02*
Y329970D01*
G01X1503727Y315581D02*
Y315187D01*
G01Y318730D02*
Y318337D01*
G01Y325029D02*
Y324636D01*
G01Y321880D02*
Y321486D01*
G01Y328179D02*
Y327785D01*
G01Y334478D02*
Y334085D01*
G01Y331329D02*
Y330935D01*
G01Y337628D02*
Y337234D01*
G01X1503590Y334577D02*
Y334970D01*
G01Y324577D02*
Y324970D01*
G01Y319577D02*
Y319970D01*
G01Y314577D02*
Y314970D01*
G01X1501709Y443592D02*
Y310955D01*
G01X1501621Y329577D02*
Y329970D01*
G01X1500921Y310167D02*
Y381073D01*
G01X1500862Y310561D02*
Y443986D01*
G01X1499740Y448514D02*
Y306033D01*
G01X1497772D02*
Y298868D01*
G01X1509161Y337628D02*
X1509158Y337666D01*
X1509151Y337703D01*
X1509138Y337737D01*
X1509121Y337767D01*
X1509100Y337791D01*
X1509076Y337810D01*
X1509050Y337821D01*
X1509023Y337825D01*
G01X1509161Y334478D02*
X1509158Y334516D01*
X1509151Y334553D01*
X1509138Y334587D01*
X1509121Y334617D01*
X1509100Y334642D01*
X1509076Y334660D01*
X1509050Y334671D01*
X1509023Y334675D01*
G01X1509161Y331329D02*
X1509158Y331367D01*
X1509151Y331404D01*
X1509138Y331438D01*
X1509121Y331468D01*
X1509100Y331492D01*
X1509076Y331510D01*
X1509050Y331522D01*
X1509023Y331525D01*
G01X1509161Y328179D02*
X1509158Y328217D01*
X1509151Y328254D01*
X1509138Y328288D01*
X1509121Y328318D01*
X1509100Y328343D01*
X1509076Y328361D01*
X1509050Y328372D01*
X1509023Y328376D01*
G01X1509161Y325029D02*
X1509158Y325068D01*
X1509151Y325104D01*
X1509138Y325138D01*
X1509121Y325169D01*
X1509100Y325193D01*
X1509076Y325211D01*
X1509050Y325222D01*
X1509023Y325226D01*
G01X1509161Y321880D02*
X1509158Y321918D01*
X1509151Y321955D01*
X1509138Y321989D01*
X1509121Y322019D01*
X1509100Y322043D01*
X1509076Y322062D01*
X1509050Y322073D01*
X1509023Y322077D01*
G01X1509161Y318730D02*
X1509158Y318768D01*
X1509151Y318805D01*
X1509138Y318839D01*
X1509121Y318869D01*
X1509100Y318894D01*
X1509076Y318912D01*
X1509050Y318923D01*
X1509023Y318927D01*
G01X1509161Y315581D02*
X1509158Y315619D01*
X1509151Y315656D01*
X1509138Y315690D01*
X1509121Y315720D01*
X1509100Y315744D01*
X1509076Y315762D01*
X1509050Y315774D01*
X1509023Y315777D01*
G01X1508208Y334970D02*
X1508130Y335561D01*
G01X1508208Y324970D02*
X1508130Y325561D01*
G01Y320561D02*
X1508208Y319970D01*
G01X1506239Y329970D02*
X1506161Y330561D01*
G01X1508208Y314970D02*
X1508130Y315561D01*
G01X1503727Y337234D02*
X1503758Y337137D01*
X1503847Y337065D01*
X1503974Y337037D01*
G01X1503727Y334085D02*
X1503758Y333988D01*
X1503847Y333915D01*
X1503974Y333888D01*
G01X1503727Y330935D02*
X1503758Y330838D01*
X1503847Y330766D01*
X1503974Y330738D01*
G01X1503727Y324636D02*
X1503758Y324539D01*
X1503847Y324467D01*
X1503974Y324439D01*
G01X1503727Y321486D02*
X1503758Y321389D01*
X1503847Y321317D01*
X1503974Y321289D01*
G01X1503727Y318337D02*
X1503758Y318240D01*
X1503847Y318167D01*
X1503974Y318140D01*
G01X1503727Y315187D02*
X1503758Y315090D01*
X1503847Y315018D01*
X1503974Y314990D01*
G01X1497740Y297718D02*
X1497682Y297858D01*
X1497677Y298098D01*
G01X1509060Y335561D02*
X1509332Y334970D01*
G01X1507091Y330561D02*
X1507364Y329970D01*
G01X1509060Y325561D02*
X1509332Y324970D01*
G01X1509060Y320561D02*
X1509332Y319970D01*
G01X1509060Y315561D02*
X1509332Y314970D01*
G01X1503974Y337825D02*
X1503846Y337797D01*
X1503758Y337724D01*
X1503727Y337628D01*
G01X1503974Y334675D02*
X1503846Y334647D01*
X1503758Y334574D01*
X1503727Y334478D01*
G01X1503974Y331525D02*
X1503846Y331498D01*
X1503758Y331425D01*
X1503727Y331329D01*
G01X1503974Y325226D02*
X1503846Y325199D01*
X1503758Y325126D01*
X1503727Y325029D01*
G01X1503974Y322077D02*
X1503846Y322049D01*
X1503758Y321976D01*
X1503727Y321880D01*
G01X1503974Y318927D02*
X1503846Y318899D01*
X1503758Y318826D01*
X1503727Y318730D01*
G01X1503974Y315777D02*
X1503846Y315750D01*
X1503758Y315677D01*
X1503727Y315581D01*
G01X1503590Y334577D02*
X1503727Y334379D01*
X1503865Y334182D01*
X1504004Y333986D01*
G01X1509023Y337037D02*
X1509050Y337041D01*
X1509075Y337052D01*
X1509099Y337070D01*
X1509121Y337095D01*
X1509138Y337125D01*
X1509150Y337159D01*
X1509158Y337195D01*
X1509161Y337234D01*
G01X1509023Y333888D02*
X1509050Y333891D01*
X1509075Y333903D01*
X1509099Y333921D01*
X1509121Y333945D01*
X1509138Y333975D01*
X1509150Y334009D01*
X1509158Y334046D01*
X1509161Y334085D01*
G01X1509023Y330738D02*
X1509050Y330742D01*
X1509075Y330753D01*
X1509099Y330771D01*
X1509121Y330796D01*
X1509138Y330825D01*
X1509150Y330859D01*
X1509158Y330896D01*
X1509161Y330935D01*
G01X1509023Y327588D02*
X1509050Y327592D01*
X1509075Y327603D01*
X1509099Y327621D01*
X1509121Y327646D01*
X1509138Y327676D01*
X1509150Y327710D01*
X1509158Y327746D01*
X1509161Y327785D01*
G01X1509023Y324439D02*
X1509050Y324443D01*
X1509075Y324454D01*
X1509099Y324472D01*
X1509121Y324497D01*
X1509138Y324526D01*
X1509150Y324560D01*
X1509158Y324597D01*
X1509161Y324636D01*
G01X1509023Y321289D02*
X1509050Y321293D01*
X1509075Y321304D01*
X1509099Y321322D01*
X1509121Y321347D01*
X1509138Y321377D01*
X1509150Y321410D01*
X1509158Y321447D01*
X1509161Y321486D01*
G01X1509023Y318140D02*
X1509050Y318143D01*
X1509075Y318155D01*
X1509099Y318173D01*
X1509121Y318197D01*
X1509138Y318227D01*
X1509150Y318261D01*
X1509158Y318298D01*
X1509161Y318337D01*
G01X1509023Y314990D02*
X1509050Y314994D01*
X1509075Y315005D01*
X1509099Y315023D01*
X1509121Y315048D01*
X1509138Y315077D01*
X1509150Y315111D01*
X1509158Y315148D01*
X1509161Y315187D01*
G01X1501621Y329577D02*
X1501758Y329379D01*
X1501896Y329182D01*
X1502036Y328986D01*
G01X1503590Y324577D02*
X1503727Y324379D01*
X1503865Y324182D01*
X1504004Y323986D01*
G01X1503590Y319577D02*
X1503727Y319379D01*
X1503865Y319182D01*
X1504004Y318986D01*
G01X1503590Y314577D02*
X1503727Y314379D01*
X1503865Y314182D01*
X1504004Y313986D01*
G01X1509749Y335561D02*
X1510176Y334970D01*
G01X1507781Y330561D02*
X1508207Y329970D01*
G01X1509749Y325561D02*
X1510176Y324970D01*
G01X1509749Y320561D02*
X1510176Y319970D01*
G01X1509749Y315561D02*
X1510176Y314970D01*
G01X1503974Y337825D02*
X1510058D01*
G01X1503727Y337628D02*
X1510338D01*
G01Y337234D02*
X1503727D01*
G01X1503974Y337037D02*
X1510058D01*
G01X1509749Y335561D02*
X1504004D01*
G01X1510176Y334970D02*
X1503590D01*
G01X1503974Y334675D02*
X1510058D01*
G01X1503590Y334577D02*
X1510176D01*
G01X1503727Y334478D02*
X1510338D01*
G01Y334085D02*
X1503727D01*
G01X1504004Y333986D02*
X1509749D01*
G01X1503974Y333888D02*
X1510058D01*
G01X1503974Y331525D02*
X1510058D01*
G01X1503727Y331329D02*
X1510338D01*
G01X1501709Y331033D02*
X1528401D01*
G01X1510338Y330935D02*
X1503727D01*
G01X1503974Y330738D02*
X1510058D01*
G01X1507781Y330561D02*
X1502036D01*
G01X1508207Y329970D02*
X1501621D01*
G01Y329577D02*
X1508207D01*
G01X1502036Y328986D02*
X1507781D01*
G01X1528401Y328671D02*
X1501709D01*
G01X1503974Y328376D02*
X1510058D01*
G01X1503727Y328179D02*
X1510338D01*
G01Y327785D02*
X1503727D01*
G01X1503974Y327588D02*
X1510058D01*
G01X1509749Y325561D02*
X1504004D01*
G01X1503974Y325226D02*
X1510058D01*
G01X1503727Y325029D02*
X1510338D01*
G01X1510176Y324970D02*
X1503590D01*
G01X1510338Y324636D02*
X1503727D01*
G01X1503590Y324577D02*
X1510176D01*
G01X1503974Y324439D02*
X1510058D01*
G01X1504004Y323986D02*
X1509749D01*
G01X1503974Y322077D02*
X1510058D01*
G01X1503727Y321880D02*
X1510338D01*
G01Y321486D02*
X1503727D01*
G01X1503974Y321289D02*
X1510058D01*
G01X1509749Y320561D02*
X1504004D01*
G01X1510176Y319970D02*
X1503590D01*
G01Y319577D02*
X1510176D01*
G01X1504004Y318986D02*
X1509749D01*
G01X1503974Y318927D02*
X1510058D01*
G01X1503727Y318730D02*
X1510338D01*
G01Y318337D02*
X1503727D01*
G01X1503974Y318140D02*
X1510058D01*
G01X1503974Y315777D02*
X1510058D01*
G01X1503727Y315581D02*
X1510338D01*
G01X1509749Y315561D02*
X1504004D01*
G01X1510338Y315187D02*
X1503727D01*
G01X1503974Y314990D02*
X1510058D01*
G01X1510176Y314970D02*
X1503590D01*
G01Y314577D02*
X1510176D01*
G01X1504004Y313986D02*
X1509749D01*
G01X1501709Y310955D02*
X1520212D01*
G01X1499740Y310561D02*
X1530449D01*
G01X1501709Y306033D02*
X1551709D01*
G01X1499740D02*
X1496457D01*
G01X1497772Y298868D02*
X1524149D01*
G01X1551709Y297687D02*
X1497772D01*
G01X1499740Y308002D02*
X1501709Y306033D01*
G01X1508572Y337825D02*
X1508610Y337798D01*
X1508638Y337726D01*
X1508648Y337628D01*
G01X1508572Y334675D02*
X1508610Y334649D01*
X1508638Y334577D01*
X1508648Y334478D01*
G01X1508572Y331525D02*
X1508610Y331499D01*
X1508638Y331427D01*
X1508648Y331329D01*
G01X1508572Y328376D02*
X1508610Y328349D01*
X1508638Y328277D01*
X1508648Y328179D01*
G01X1508572Y325226D02*
X1508610Y325200D01*
X1508638Y325128D01*
X1508648Y325029D01*
G01X1508572Y322077D02*
X1508610Y322050D01*
X1508638Y321978D01*
X1508648Y321880D01*
G01X1508572Y318927D02*
X1508610Y318901D01*
X1508638Y318829D01*
X1508648Y318730D01*
G01X1508572Y315777D02*
X1508610Y315751D01*
X1508638Y315679D01*
X1508648Y315581D01*
G01X1503974Y327588D02*
X1503847Y327616D01*
X1503758Y327689D01*
X1503727Y327785D01*
G01X1543875Y301514D02*
G03X1542450I-713J82D01*
G01X1542889Y298889D02*
G03X1544475Y299176I263J3073D01*
G01X1543223Y299880D02*
G03X1543814Y300245I10J645D01*
G01X1542450Y300688D02*
G03X1543223Y299880I791J-17D01*
G01X1544475Y299176D02*
G03X1545318Y300245I-704J1422D01*
G01X1545109Y302131D02*
G03X1543875Y303104I-1735J-931D01*
G01X1542232Y303061D02*
G03X1541068Y301922I730J-1911D01*
G01X1541154Y299906D02*
G03X1542893Y298889I1807J1094D01*
G01X1543875Y303104D02*
G03X1542232Y303061I-757J-2475D01*
G01X1540894Y300766D02*
G03X1541156Y299904I2970J432D01*
G01X1545448Y300688D02*
G03X1545109Y302131I-3015J53D01*
G01X1540894Y301262D02*
G03Y300765I3524J-248D01*
G01X1541068Y301922D02*
G03X1540894Y301262I4018J-1412D01*
G01X1541472Y302470D02*
G03I-2165J0D01*
G01X1541261Y299754D02*
G03Y305187I-1954J2717D01*
G01X1537353D02*
G03Y299754I1954J-2717D01*
G01X1542811Y302470D02*
G03I-3504J0D01*
G01X1537003Y306368D02*
G03Y298573I2304J-3897D01*
G01X1541611D02*
G03Y306368I-2304J3897D01*
G01X1531551Y335955D02*
G03X1531945Y335561I394J0D01*
G01Y338986D02*
G03X1531551Y338592I0J-394D01*
G01X1535250Y300198D02*
G03X1536723I736J277D01*
G01Y301882D02*
G03X1535250I-737J-277D01*
G01X1533978Y299863D02*
G03X1534499Y299298I1351J723D01*
G01X1537545Y299299D02*
G03X1538065Y299865I-832J1287D01*
G01Y302177D02*
G03X1537544Y302742I-1351J-723D01*
G01X1534498D02*
G03X1533977Y302176I831J-1288D01*
G01X1535250Y301882D02*
G03Y300198I2236J-842D01*
G01X1533977Y302176D02*
G03X1533978Y299863I2163J-1156D01*
G01X1538065Y299865D02*
G03Y302177I-2163J1156D01*
G01X1534499Y299297D02*
G03X1537545Y299299I1521J2363D01*
G01X1537544Y302742D02*
G03X1534498I-1523J-2362D01*
G01X1531945Y333986D02*
G03X1531551Y333592I0J-394D01*
G01X1531945Y313986D02*
G03X1531551Y313592I0J-394D01*
G01Y315955D02*
G03X1531945Y315561I394J0D01*
G01Y323986D02*
G03X1531551Y323592I0J-394D01*
G01Y325955D02*
G03X1531945Y325561I394J0D01*
G01Y318986D02*
G03X1531551Y318592I0J-394D01*
G01Y320955D02*
G03X1531945Y320561I394J0D01*
G01X1533043Y302018D02*
G03X1532749Y302689I-913J0D01*
G01X1532220Y289085D02*
G03Y292234I0J1574D01*
G01X1532749Y302689D02*
G03X1530114Y302544I-1247J-1352D01*
G01X1536723Y300198D02*
G03Y301882I-2237J842D01*
G01X1528761Y301614D02*
G03X1527330I-716J0D01*
G01X1531651D02*
G03X1530220I-716J0D01*
G01X1527890Y292234D02*
G03Y289085I0J-1575D01*
G01X1530114Y302544D02*
G03X1527333Y302539I-1388J-1207D01*
G01X1549942Y303096D02*
X1548647Y301244D01*
G01X1548560Y303096D02*
X1547870Y302109D01*
G01X1546917Y301236D02*
X1545474Y299089D01*
G01X1536549Y308396D02*
X1536804Y308789D01*
G01X1547673Y300366D02*
X1546882Y299089D01*
G01X1541261Y305187D02*
X1541279Y305243D01*
X1541331Y305408D01*
X1541410Y305666D01*
X1541506Y305994D01*
X1541611Y306368D01*
G01X1537003Y298573D02*
X1537106Y298942D01*
X1537203Y299271D01*
X1537283Y299534D01*
X1537335Y299699D01*
X1537353Y299754D01*
G01X1559583Y475692D02*
Y315613D01*
G01X1551709Y297687D02*
Y311565D01*
G01X1551391Y306033D02*
Y311565D01*
G01X1550916Y308789D02*
Y311565D01*
G01X1549937Y315777D02*
Y314990D01*
G01Y318927D02*
Y318140D01*
G01Y325226D02*
Y324439D01*
G01Y322077D02*
Y321289D01*
G01Y328376D02*
Y327588D01*
G01Y334675D02*
Y333888D01*
G01Y331525D02*
Y330738D01*
G01Y337825D02*
Y337037D01*
G01X1548163Y315777D02*
Y314990D01*
G01Y318927D02*
Y318140D01*
G01Y325226D02*
Y324439D01*
G01Y322077D02*
Y321289D01*
G01Y328376D02*
Y327588D01*
G01Y334675D02*
Y333888D01*
G01Y331525D02*
Y330738D01*
G01Y337825D02*
Y337037D01*
G01X1547975D02*
Y337825D01*
G01Y333888D02*
Y334675D01*
G01Y330738D02*
Y331525D01*
G01Y327588D02*
Y328376D01*
G01Y324439D02*
Y325226D01*
G01Y321289D02*
Y322077D01*
G01Y318140D02*
Y318927D01*
G01Y314990D02*
Y315777D01*
G01X1545138Y337037D02*
Y337825D01*
G01Y333888D02*
Y334675D01*
G01Y330738D02*
Y331525D01*
G01Y327588D02*
Y328376D01*
G01Y324439D02*
Y325226D01*
G01Y321289D02*
Y322077D01*
G01Y318140D02*
Y318927D01*
G01Y314990D02*
Y315777D01*
G01X1545062Y308789D02*
Y306033D01*
G01X1544551Y308789D02*
Y445758D01*
G01X1544197Y315777D02*
Y314990D01*
G01Y318927D02*
Y318140D01*
G01Y325226D02*
Y324439D01*
G01Y322077D02*
Y321289D01*
G01Y328376D02*
Y327588D01*
G01Y334675D02*
Y333888D01*
G01Y331525D02*
Y330738D01*
G01Y337825D02*
Y337037D01*
G01X1542605Y315777D02*
Y314990D01*
G01Y318927D02*
Y318140D01*
G01Y325226D02*
Y324439D01*
G01Y322077D02*
Y321289D01*
G01Y328376D02*
Y327588D01*
G01Y334675D02*
Y333888D01*
G01Y331525D02*
Y330738D01*
G01Y337825D02*
Y337037D01*
G01X1542457Y315777D02*
Y314990D01*
G01Y318927D02*
Y318140D01*
G01Y325226D02*
Y324439D01*
G01Y322077D02*
Y321289D01*
G01Y328376D02*
Y327588D01*
G01Y334675D02*
Y333888D01*
G01Y331525D02*
Y330738D01*
G01Y337825D02*
Y337037D01*
G01X1541519Y337825D02*
Y340187D01*
G01Y334675D02*
Y337037D01*
G01Y331525D02*
Y333888D01*
G01Y328376D02*
Y330738D01*
G01Y325226D02*
Y327588D01*
G01Y322077D02*
Y324439D01*
G01Y318927D02*
Y321289D01*
G01Y315777D02*
Y318140D01*
G01Y313317D02*
Y314990D01*
G01X1540303Y304843D02*
Y299089D01*
G01X1539791Y315777D02*
Y314990D01*
G01Y318927D02*
Y318140D01*
G01Y325226D02*
Y324439D01*
G01Y322077D02*
Y321289D01*
G01Y328376D02*
Y327588D01*
G01Y334675D02*
Y333888D01*
G01Y331525D02*
Y330738D01*
G01Y337825D02*
Y337037D01*
G01X1539110Y333986D02*
Y335561D01*
G01Y323986D02*
Y325561D01*
G01Y318986D02*
Y320561D01*
G01Y313986D02*
Y315561D01*
G01X1538843Y299089D02*
Y304843D01*
G01X1538244Y297687D02*
Y284754D01*
G01X1538139Y337037D02*
Y337825D01*
G01Y333888D02*
Y334675D01*
G01Y330738D02*
Y331525D01*
G01Y327588D02*
Y328376D01*
G01Y324439D02*
Y325226D01*
G01Y321289D02*
Y322077D01*
G01Y318140D02*
Y318927D01*
G01Y314990D02*
Y315777D01*
G01X1537188Y308789D02*
Y306033D01*
G01X1537142Y328986D02*
Y330561D01*
G01X1536549Y308337D02*
Y308396D01*
G01X1536156Y337037D02*
Y337825D01*
G01Y333888D02*
Y334675D01*
G01Y330738D02*
Y331525D01*
G01Y327588D02*
Y328376D01*
G01Y324439D02*
Y325226D01*
G01Y321289D02*
Y322077D01*
G01Y318140D02*
Y318927D01*
G01Y314990D02*
Y315777D01*
G01X1536021Y443179D02*
Y311565D01*
G01X1535961Y315561D02*
Y313986D01*
G01Y320561D02*
Y318986D01*
G01Y325561D02*
Y323986D01*
G01Y335561D02*
Y333986D01*
G01X1535567Y445758D02*
Y308789D01*
G01X1534976Y316348D02*
Y313199D01*
G01Y321348D02*
Y318199D01*
G01Y326348D02*
Y323199D01*
G01Y336348D02*
Y333199D01*
G01Y341348D02*
Y338199D01*
G01X1533992Y306033D02*
Y308337D01*
G01Y316348D02*
Y313199D01*
G01Y321348D02*
Y318199D01*
G01Y326348D02*
Y323199D01*
G01Y330561D02*
Y328986D01*
G01Y336348D02*
Y333199D01*
G01Y341348D02*
Y338199D01*
G01X1533043Y302018D02*
Y299089D01*
G01X1533008Y315561D02*
Y313986D01*
G01Y320561D02*
Y318986D01*
G01Y325561D02*
Y323986D01*
G01Y335561D02*
Y333986D01*
G01Y331348D02*
Y328199D01*
G01X1532846Y289872D02*
Y291447D01*
G01X1532811D02*
Y289872D01*
G01X1532793Y315777D02*
Y314990D01*
G01Y318927D02*
Y318140D01*
G01Y325226D02*
Y324439D01*
G01Y322077D02*
Y321289D01*
G01Y328376D02*
Y327588D01*
G01Y334675D02*
Y333888D01*
G01Y331525D02*
Y330738D01*
G01Y337825D02*
Y337037D01*
G01X1532787Y291447D02*
Y289872D01*
G01X1532417Y315777D02*
Y314990D01*
G01Y318927D02*
Y318140D01*
G01Y325226D02*
Y324439D01*
G01Y322077D02*
Y321289D01*
G01Y328376D02*
Y327588D01*
G01Y334675D02*
Y333888D01*
G01Y331525D02*
Y330738D01*
G01Y337825D02*
Y337037D01*
G01X1532391Y315777D02*
Y314990D01*
G01Y318927D02*
Y318140D01*
G01Y325226D02*
Y324439D01*
G01Y322077D02*
Y321289D01*
G01Y328376D02*
Y327588D01*
G01Y334675D02*
Y333888D01*
G01Y331525D02*
Y330738D01*
G01Y337825D02*
Y337037D01*
G01X1532024Y331348D02*
Y328199D01*
G01X1531651Y299089D02*
Y301614D01*
G01X1531551Y445758D02*
Y308789D01*
G01X1531464Y289872D02*
Y291447D01*
G01X1531094D02*
Y289872D01*
G01X1530449Y308337D02*
Y446211D01*
G01X1530220Y301614D02*
Y299089D01*
G01X1529016Y289872D02*
Y291447D01*
G01X1528761Y299089D02*
Y301614D01*
G01X1528646Y291447D02*
Y289872D01*
G01X1528401Y443396D02*
Y311151D01*
G01X1528087Y303435D02*
Y299655D01*
G01Y307805D02*
Y305403D01*
G01X1527333Y303096D02*
Y302539D01*
G01X1527330Y301614D02*
Y299089D01*
G01X1527324Y289872D02*
Y291447D01*
G01X1527299Y289872D02*
Y291447D01*
G01X1527264D02*
Y289872D01*
G01X1526433Y328671D02*
Y311151D01*
G01Y347569D02*
Y331033D01*
G01X1525890Y303096D02*
Y299089D01*
G01X1524149Y297687D02*
Y306033D01*
G01X1522181Y311742D02*
Y309970D01*
G01X1521866Y311151D02*
Y284754D01*
G01X1520212Y310955D02*
Y443592D01*
G01X1541261Y299754D02*
X1541279Y299698D01*
X1541331Y299532D01*
X1541410Y299274D01*
X1541506Y298947D01*
X1541611Y298573D01*
G01X1537353Y305187D02*
X1537335Y305243D01*
X1537283Y305408D01*
X1537204Y305667D01*
X1537108Y305994D01*
X1537003Y306368D01*
G01X1547673Y300366D02*
X1548419Y299089D01*
G01X1548647Y301244D02*
X1549968Y299089D01*
G01X1547265Y303096D02*
X1547870Y302109D01*
G01X1545648Y303096D02*
X1546917Y301236D01*
G01X1534976Y338396D02*
X1533992D01*
G01X1534976Y338199D02*
X1533992D01*
G01X1542605Y337825D02*
X1549937D01*
G01X1542457D02*
X1530449D01*
G01X1542457Y337037D02*
X1530449D01*
G01X1549937D02*
X1542605D01*
G01X1534976Y336348D02*
X1533992D01*
G01X1534976Y336151D02*
X1533992D01*
G01X1534976Y335758D02*
X1533992D01*
G01X1531945Y335561D02*
X1539110D01*
G01X1542605Y334675D02*
X1549937D01*
G01X1542457D02*
X1530449D01*
G01X1531945Y333986D02*
X1539110D01*
G01X1542457Y333888D02*
X1530449D01*
G01X1549937D02*
X1542605D01*
G01X1534976Y333789D02*
X1533992D01*
G01X1534976Y333396D02*
X1533992D01*
G01X1534976Y333199D02*
X1533992D01*
G01X1530449Y331978D02*
X1531551D01*
G01X1542605Y331525D02*
X1549937D01*
G01X1542457D02*
X1530449D01*
G01X1533008Y331348D02*
X1532024D01*
G01X1533008Y331151D02*
X1532024D01*
G01X1533008Y330758D02*
X1532024D01*
G01X1542457Y330738D02*
X1530449D01*
G01X1549937D02*
X1542605D01*
G01X1531551Y330561D02*
X1537142D01*
G01X1531551Y328986D02*
X1537142D01*
G01X1533008Y328789D02*
X1532024D01*
G01X1533008Y328396D02*
X1532024D01*
G01X1542605Y328376D02*
X1549937D01*
G01X1542457D02*
X1530449D01*
G01X1533008Y328199D02*
X1532024D01*
G01X1542457Y327588D02*
X1530449D01*
G01X1549937D02*
X1542605D01*
G01X1530449Y327569D02*
X1531551D01*
G01X1534976Y326348D02*
X1533992D01*
G01X1534976Y326151D02*
X1533992D01*
G01X1534976Y325758D02*
X1533992D01*
G01X1531945Y325561D02*
X1539110D01*
G01X1542605Y325226D02*
X1549937D01*
G01X1542457D02*
X1530449D01*
G01X1542457Y324439D02*
X1530449D01*
G01X1549937D02*
X1542605D01*
G01X1531945Y323986D02*
X1539110D01*
G01X1534976Y323789D02*
X1533992D01*
G01X1534976Y323396D02*
X1533992D01*
G01X1534976Y323199D02*
X1533992D01*
G01X1542605Y322077D02*
X1549937D01*
G01X1542457D02*
X1530449D01*
G01X1534976Y321348D02*
X1533992D01*
G01X1542457Y321289D02*
X1530449D01*
G01X1549937D02*
X1542605D01*
G01X1534976Y321151D02*
X1533992D01*
G01X1534976Y320758D02*
X1533992D01*
G01X1539110Y320561D02*
X1531945D01*
G01X1539110Y318986D02*
X1531945D01*
G01X1542605Y318927D02*
X1549937D01*
G01X1542457D02*
X1530449D01*
G01X1534976Y318789D02*
X1533992D01*
G01X1534976Y318396D02*
X1533992D01*
G01X1534976Y318199D02*
X1533992D01*
G01X1542457Y318140D02*
X1530449D01*
G01X1549937D02*
X1542605D01*
G01X1534976Y316348D02*
X1533992D01*
G01X1534976Y316151D02*
X1533992D01*
G01X1542605Y315777D02*
X1549937D01*
G01X1542457D02*
X1530449D01*
G01X1534976Y315758D02*
X1533992D01*
G01X1634386Y315613D02*
X1559583D01*
G01X1531945Y315561D02*
X1539110D01*
G01X1542457Y314990D02*
X1530449D01*
G01X1549937D02*
X1542605D01*
G01X1531945Y313986D02*
X1539110D01*
G01X1534976Y313789D02*
X1533992D01*
G01X1534976Y313396D02*
X1533992D01*
G01X1544551Y313317D02*
X1535567D01*
G01X1534976Y313199D02*
X1533992D01*
G01X1531551Y311742D02*
X1522181D01*
G01X1551709Y311565D02*
X1531551D01*
G01X1521866Y311151D02*
X1528401D01*
G01X1531551Y309970D02*
X1522181D01*
G01X1550916Y308789D02*
X1530449D01*
G01X1536549Y308396D02*
X1530449D01*
G01X1536549Y308337D02*
X1530449D01*
G01X1551709Y307805D02*
X1528087D01*
G01X1541611Y306368D02*
X1537003D01*
G01X1551709Y305403D02*
X1528087D01*
G01X1537353Y305187D02*
X1541261D01*
G01X1540303Y304843D02*
X1538843D01*
G01X1551709Y303435D02*
X1528087D01*
G01X1527333Y303096D02*
X1525890D01*
G01X1549942D02*
X1548560D01*
G01X1547265D02*
X1545648D01*
G01X1543875Y301514D02*
X1542450D01*
G01X1545448Y300688D02*
X1542449D01*
G01X1545318Y300245D02*
X1543814D01*
G01X1541261Y299754D02*
X1537353D01*
G01X1551709Y299655D02*
X1528087D01*
G01X1527330Y299089D02*
X1525890D01*
G01X1530220D02*
X1528761D01*
G01X1533043D02*
X1531651D01*
G01X1540303D02*
X1538843D01*
G01X1549968D02*
X1548419D01*
G01X1546882D02*
X1545474D01*
G01X1537003Y298573D02*
X1541611D01*
G01X1538244Y294931D02*
X1521866D01*
G01X1527890Y292234D02*
X1532220D01*
G01X1527264Y291447D02*
X1532846D01*
G01Y289872D02*
X1527264D01*
G01X1532220Y289085D02*
X1527890D01*
G01X1521866Y284754D02*
X1538244D01*
G01X1509749Y338986D02*
X1510176Y339577D01*
G01X1509332D02*
X1509060Y338986D01*
G01X1508208Y339577D02*
X1508130Y338986D01*
G01X1503590Y339577D02*
X1503727Y339379D01*
X1503865Y339182D01*
X1504004Y338986D01*
G01D02*
X1509749D01*
G01X1508572Y393730D02*
X1508610Y393757D01*
X1508638Y393829D01*
X1508648Y393927D01*
G01X1508572Y409478D02*
X1508610Y409505D01*
X1508638Y409577D01*
X1508648Y409675D01*
G01X1499740Y385541D02*
X1501709Y387510D01*
G01X1509749Y343986D02*
X1510176Y344577D01*
G01X1509749Y348986D02*
X1510176Y349577D01*
G01X1509749Y353986D02*
X1510176Y354577D01*
G01X1509749Y358986D02*
X1510176Y359577D01*
G01X1509749Y363986D02*
X1510176Y364577D01*
G01X1507781Y368986D02*
X1508207Y369577D01*
G01X1509749Y373986D02*
X1510176Y374577D01*
G01X1509749Y378986D02*
X1510176Y379577D01*
G01X1509817Y383986D02*
X1510241Y384577D01*
G01X1509817Y408986D02*
X1510241Y409577D01*
G01X1504004Y340561D02*
X1503865Y340365D01*
X1503727Y340168D01*
X1503590Y339970D01*
G01X1504004Y345561D02*
X1503865Y345365D01*
X1503727Y345168D01*
X1503590Y344970D01*
G01X1504004Y350561D02*
X1503865Y350365D01*
X1503727Y350168D01*
X1503590Y349970D01*
G01X1504004Y355561D02*
X1503865Y355365D01*
X1503727Y355168D01*
X1503590Y354970D01*
G01X1504004Y360561D02*
X1503865Y360365D01*
X1503727Y360168D01*
X1503590Y359970D01*
G01X1504004Y365561D02*
X1503865Y365365D01*
X1503727Y365168D01*
X1503590Y364970D01*
G01X1502036Y370561D02*
X1501896Y370365D01*
X1501758Y370168D01*
X1501621Y369970D01*
G01X1504004Y375561D02*
X1503865Y375365D01*
X1503727Y375168D01*
X1503590Y374970D01*
G01X1504004Y380561D02*
X1503865Y380365D01*
X1503727Y380168D01*
X1503590Y379970D01*
G01X1503904Y385561D02*
X1503768Y385365D01*
X1503633Y385168D01*
X1503499Y384970D01*
G01X1503904Y410561D02*
X1503768Y410365D01*
X1503633Y410168D01*
X1503499Y409970D01*
G01X1509332Y344577D02*
X1509060Y343986D01*
G01X1509332Y349577D02*
X1509060Y348986D01*
G01X1509332Y354577D02*
X1509060Y353986D01*
G01X1509332Y359577D02*
X1509060Y358986D01*
G01X1509332Y364577D02*
X1509060Y363986D01*
G01X1507364Y369577D02*
X1507091Y368986D01*
G01X1509332Y374577D02*
X1509060Y373986D01*
G01X1509332Y379577D02*
X1509060Y378986D01*
G01X1509332Y384577D02*
X1509060Y383986D01*
G01X1509332Y409577D02*
X1509060Y408986D01*
G01X1503727Y356525D02*
X1503760Y356625D01*
X1503848Y356695D01*
X1503974Y356722D01*
G01X1508208Y344577D02*
X1508130Y343986D01*
G01X1508208Y349577D02*
X1508130Y348986D01*
G01X1508208Y354577D02*
X1508130Y353986D01*
G01X1508208Y359577D02*
X1508130Y358986D01*
G01X1508208Y364577D02*
X1508130Y363986D01*
G01X1508208Y374577D02*
X1508130Y373986D01*
G01X1508208Y379577D02*
X1508130Y378986D01*
G01X1506239Y369577D02*
X1506161Y368986D01*
G01X1508208Y384577D02*
X1508130Y383986D01*
G01X1508208Y409577D02*
X1508130Y408986D01*
G01X1508648Y340384D02*
X1508638Y340285D01*
X1508610Y340213D01*
X1508572Y340187D01*
G01X1508648Y343533D02*
X1508638Y343435D01*
X1508610Y343363D01*
X1508572Y343337D01*
G01X1508648Y346683D02*
X1508638Y346585D01*
X1508610Y346513D01*
X1508572Y346486D01*
G01X1508648Y349833D02*
X1508638Y349734D01*
X1508610Y349662D01*
X1508572Y349636D01*
G01X1508648Y352982D02*
X1508638Y352884D01*
X1508610Y352812D01*
X1508572Y352785D01*
G01X1508648Y356132D02*
X1508638Y356033D01*
X1508610Y355961D01*
X1508572Y355935D01*
G01X1508648Y359281D02*
X1508638Y359183D01*
X1508610Y359111D01*
X1508572Y359085D01*
G01X1508648Y362431D02*
X1508638Y362333D01*
X1508610Y362261D01*
X1508572Y362234D01*
G01X1508648Y365581D02*
X1508638Y365482D01*
X1508610Y365410D01*
X1508572Y365384D01*
G01X1508648Y368730D02*
X1508638Y368632D01*
X1508610Y368560D01*
X1508572Y368533D01*
G01X1508648Y371880D02*
X1508638Y371781D01*
X1508610Y371709D01*
X1508572Y371683D01*
G01X1508648Y375029D02*
X1508638Y374931D01*
X1508610Y374859D01*
X1508572Y374833D01*
G01X1508648Y378179D02*
X1508638Y378081D01*
X1508610Y378009D01*
X1508572Y377982D01*
G01X1508648Y381329D02*
X1508638Y381230D01*
X1508610Y381158D01*
X1508572Y381132D01*
G01X1508648Y384478D02*
X1508638Y384380D01*
X1508610Y384308D01*
X1508572Y384281D01*
G01X1508648Y387628D02*
X1508638Y387530D01*
X1508610Y387457D01*
X1508572Y387431D01*
G01X1508648Y390777D02*
X1508638Y390679D01*
X1508610Y390607D01*
X1508572Y390581D01*
G01X1508648Y397077D02*
X1508638Y396978D01*
X1508610Y396906D01*
X1508572Y396880D01*
G01X1508648Y400226D02*
X1508638Y400128D01*
X1508610Y400056D01*
X1508572Y400029D01*
G01X1508648Y403376D02*
X1508638Y403278D01*
X1508610Y403205D01*
X1508572Y403179D01*
G01X1508648Y406525D02*
X1508638Y406427D01*
X1508610Y406355D01*
X1508572Y406329D01*
G01X1509093Y388905D02*
X1509090Y388867D01*
X1509081Y388830D01*
X1509068Y388796D01*
X1509049Y388766D01*
X1509027Y388742D01*
X1509002Y388723D01*
X1508974Y388712D01*
X1508945Y388708D01*
G01X1509093Y392055D02*
X1509090Y392017D01*
X1509081Y391980D01*
X1509068Y391946D01*
X1509049Y391916D01*
X1509027Y391891D01*
X1509002Y391873D01*
X1508974Y391862D01*
X1508945Y391858D01*
G01X1509093Y395204D02*
X1509090Y395166D01*
X1509081Y395129D01*
X1509068Y395095D01*
X1509049Y395065D01*
X1509027Y395041D01*
X1509002Y395023D01*
X1508974Y395011D01*
X1508945Y395008D01*
G01X1509093Y398354D02*
X1509090Y398316D01*
X1509081Y398279D01*
X1509068Y398245D01*
X1509049Y398215D01*
X1509027Y398190D01*
X1509002Y398172D01*
X1508974Y398161D01*
X1508945Y398157D01*
G01X1509093Y401504D02*
X1509090Y401465D01*
X1509081Y401429D01*
X1509068Y401395D01*
X1509049Y401364D01*
X1509027Y401340D01*
X1509002Y401322D01*
X1508974Y401311D01*
X1508945Y401307D01*
G01X1509093Y404653D02*
X1509090Y404615D01*
X1509081Y404578D01*
X1509068Y404544D01*
X1509049Y404514D01*
X1509027Y404490D01*
X1509002Y404472D01*
X1508974Y404460D01*
X1508945Y404456D01*
G01X1507941Y388905D02*
X1507940Y388867D01*
X1507938Y388830D01*
X1507935Y388796D01*
X1507931Y388766D01*
X1507926Y388742D01*
X1507921Y388723D01*
X1507915Y388712D01*
X1507908Y388708D01*
G01X1507941Y392055D02*
X1507940Y392017D01*
X1507938Y391980D01*
X1507935Y391946D01*
X1507931Y391916D01*
X1507926Y391891D01*
X1507921Y391873D01*
X1507915Y391862D01*
X1507908Y391858D01*
G01X1507941Y395204D02*
X1507940Y395166D01*
X1507938Y395129D01*
X1507935Y395095D01*
X1507931Y395065D01*
X1507926Y395041D01*
X1507921Y395023D01*
X1507915Y395011D01*
X1507908Y395008D01*
G01X1507941Y398354D02*
X1507940Y398316D01*
X1507938Y398279D01*
X1507935Y398245D01*
X1507931Y398215D01*
X1507926Y398190D01*
X1507921Y398172D01*
X1507915Y398161D01*
X1507908Y398157D01*
G01X1507941Y401504D02*
X1507940Y401465D01*
X1507938Y401429D01*
X1507935Y401395D01*
X1507931Y401364D01*
X1507926Y401340D01*
X1507921Y401322D01*
X1507915Y401311D01*
X1507908Y401307D01*
G01X1507941Y404653D02*
X1507940Y404615D01*
X1507938Y404578D01*
X1507935Y404544D01*
X1507931Y404514D01*
X1507926Y404490D01*
X1507921Y404472D01*
X1507915Y404460D01*
X1507908Y404456D01*
G01X1510338Y409675D02*
Y410069D01*
G01Y406525D02*
Y406919D01*
G01Y403376D02*
Y403770D01*
G01Y397077D02*
Y397470D01*
G01Y400226D02*
Y400620D01*
G01Y393927D02*
Y394321D01*
G01Y387628D02*
Y388022D01*
G01Y390777D02*
Y391171D01*
G01Y384478D02*
Y384872D01*
G01Y378179D02*
Y378573D01*
G01Y381329D02*
Y381722D01*
G01Y375029D02*
Y375423D01*
G01Y368730D02*
Y369124D01*
G01Y371880D02*
Y372274D01*
G01Y365581D02*
Y365974D01*
G01Y362431D02*
Y362825D01*
G01Y359281D02*
Y359675D01*
G01Y356132D02*
Y356525D01*
G01Y349833D02*
Y350226D01*
G01Y352982D02*
Y353376D01*
G01Y346683D02*
Y347077D01*
G01Y343533D02*
Y343927D01*
G01Y340384D02*
Y340777D01*
G01X1510241Y384970D02*
Y384577D01*
G01Y409970D02*
Y409577D01*
G01X1510176Y339970D02*
Y339577D01*
G01Y344970D02*
Y344577D01*
G01Y349970D02*
Y349577D01*
G01Y354970D02*
Y354577D01*
G01Y359970D02*
Y359577D01*
G01Y364970D02*
Y364577D01*
G01Y374970D02*
Y374577D01*
G01Y379970D02*
Y379577D01*
G01X1510035Y389889D02*
Y388905D01*
G01Y396189D02*
Y395204D01*
G01Y393039D02*
Y392055D01*
G01Y399338D02*
Y398354D01*
G01Y405638D02*
Y404653D01*
G01Y402488D02*
Y401504D01*
G01X1509332Y339970D02*
Y339577D01*
G01Y344970D02*
Y344577D01*
G01Y349970D02*
Y349577D01*
G01Y354970D02*
Y354577D01*
G01Y359970D02*
Y359577D01*
G01Y364970D02*
Y364577D01*
G01Y374970D02*
Y374577D01*
G01Y379970D02*
Y379577D01*
G01Y384970D02*
Y384577D01*
G01Y409970D02*
Y409577D01*
G01X1509161Y409675D02*
Y410069D01*
G01Y406525D02*
Y406919D01*
G01Y403376D02*
Y403770D01*
G01Y397077D02*
Y397470D01*
G01Y400226D02*
Y400620D01*
G01Y393927D02*
Y394321D01*
G01Y387628D02*
Y388022D01*
G01Y390777D02*
Y391171D01*
G01Y384478D02*
Y384872D01*
G01Y378179D02*
Y378573D01*
G01Y381329D02*
Y381722D01*
G01Y375029D02*
Y375423D01*
G01Y368730D02*
Y369124D01*
G01Y371880D02*
Y372274D01*
G01Y365581D02*
Y365974D01*
G01Y362431D02*
Y362825D01*
G01Y359281D02*
Y359675D01*
G01Y356132D02*
Y356525D01*
G01Y349833D02*
Y350226D01*
G01Y352982D02*
Y353376D01*
G01Y346683D02*
Y347077D01*
G01Y343533D02*
Y343927D01*
G01Y340384D02*
Y340777D01*
G01X1509093Y389889D02*
Y388905D01*
G01Y396189D02*
Y395204D01*
G01Y393039D02*
Y392055D01*
G01Y399338D02*
Y398354D01*
G01Y405638D02*
Y404653D01*
G01Y402488D02*
Y401504D01*
G01X1508648Y343927D02*
Y343533D01*
G01Y340777D02*
Y340384D01*
G01Y347077D02*
Y346683D01*
G01Y350226D02*
Y349833D01*
G01Y353376D02*
Y352982D01*
G01Y356525D02*
Y356132D01*
G01Y362825D02*
Y362431D01*
G01Y359675D02*
Y359281D01*
G01Y365974D02*
Y365581D01*
G01Y369124D02*
Y368730D01*
G01Y372274D02*
Y371880D01*
G01Y375423D02*
Y375029D01*
G01Y378573D02*
Y378179D01*
G01Y381722D02*
Y381329D01*
G01Y384872D02*
Y384478D01*
G01Y388022D02*
Y387628D01*
G01Y391171D02*
Y390777D01*
G01Y394321D02*
Y393927D01*
G01Y397470D02*
Y397077D01*
G01Y400620D02*
Y400226D01*
G01Y403770D02*
Y403376D01*
G01Y410069D02*
Y409675D01*
G01Y406919D02*
Y406525D01*
G01X1508208Y409577D02*
Y409970D01*
G01Y384577D02*
Y384970D01*
G01Y379577D02*
Y379970D01*
G01Y374577D02*
Y374970D01*
G01Y364577D02*
Y364970D01*
G01Y359577D02*
Y359970D01*
G01Y354577D02*
Y354970D01*
G01Y349577D02*
Y349970D01*
G01Y344577D02*
Y344970D01*
G01Y339577D02*
Y339970D01*
G01X1508207Y369970D02*
Y369577D01*
G01X1507941Y389889D02*
Y388905D01*
G01Y396189D02*
Y395204D01*
G01Y393039D02*
Y392055D01*
G01Y399338D02*
Y398354D01*
G01Y405638D02*
Y404653D01*
G01Y402488D02*
Y401504D01*
G01X1507364Y369970D02*
Y369577D01*
G01X1506239D02*
Y369970D01*
G01X1506209Y407018D02*
Y408199D01*
G01Y386348D02*
Y387529D01*
G01X1503727Y343927D02*
Y343533D01*
G01Y340777D02*
Y340384D01*
G01Y347077D02*
Y346683D01*
G01Y350226D02*
Y349833D01*
G01Y353376D02*
Y352982D01*
G01Y356525D02*
Y356132D01*
G01Y362825D02*
Y362431D01*
G01Y359675D02*
Y359281D01*
G01Y365974D02*
Y365581D01*
G01Y369124D02*
Y368730D01*
G01Y372274D02*
Y371880D01*
G01Y375423D02*
Y375029D01*
G01Y378573D02*
Y378179D01*
G01Y381722D02*
Y381329D01*
G01Y384872D02*
Y384478D01*
G01Y388022D02*
Y387628D01*
G01Y391171D02*
Y390777D01*
G01Y394321D02*
Y393927D01*
G01Y397470D02*
Y397077D01*
G01Y400620D02*
Y400226D01*
G01Y403770D02*
Y403376D01*
G01Y410069D02*
Y409675D01*
G01Y406919D02*
Y406525D01*
G01X1503717Y404653D02*
Y405638D01*
G01Y401504D02*
Y402488D01*
G01Y398354D02*
Y399338D01*
G01Y395204D02*
Y396189D01*
G01Y392055D02*
Y393039D01*
G01Y388905D02*
Y389889D01*
G01X1503590Y379577D02*
Y379970D01*
G01Y374577D02*
Y374970D01*
G01Y364577D02*
Y364970D01*
G01Y359577D02*
Y359970D01*
G01Y354577D02*
Y354970D01*
G01Y349577D02*
Y349970D01*
G01Y344577D02*
Y344970D01*
G01Y339577D02*
Y339970D01*
G01X1503499Y409577D02*
Y409970D01*
G01Y384577D02*
Y384970D01*
G01X1501621Y369577D02*
Y369970D01*
G01X1500921Y408199D02*
Y386348D01*
G01X1500751Y407995D02*
Y413376D01*
G01Y381073D02*
Y386553D01*
G01X1509161Y410069D02*
X1509158Y410107D01*
X1509151Y410144D01*
X1509138Y410178D01*
X1509121Y410208D01*
X1509100Y410232D01*
X1509076Y410251D01*
X1509050Y410262D01*
X1509023Y410266D01*
G01X1509161Y406919D02*
X1509158Y406957D01*
X1509151Y406994D01*
X1509138Y407028D01*
X1509121Y407058D01*
X1509100Y407083D01*
X1509076Y407101D01*
X1509050Y407112D01*
X1509023Y407116D01*
G01X1509161Y403770D02*
X1509158Y403808D01*
X1509151Y403845D01*
X1509138Y403879D01*
X1509121Y403909D01*
X1509100Y403933D01*
X1509076Y403951D01*
X1509050Y403963D01*
X1509023Y403966D01*
G01X1509161Y400620D02*
X1509158Y400658D01*
X1509151Y400695D01*
X1509138Y400729D01*
X1509121Y400759D01*
X1509100Y400784D01*
X1509076Y400802D01*
X1509050Y400813D01*
X1509023Y400817D01*
G01X1509161Y397470D02*
X1509158Y397509D01*
X1509151Y397545D01*
X1509138Y397579D01*
X1509121Y397610D01*
X1509100Y397634D01*
X1509076Y397652D01*
X1509050Y397663D01*
X1509023Y397667D01*
G01X1509161Y394321D02*
X1509158Y394359D01*
X1509151Y394396D01*
X1509138Y394430D01*
X1509121Y394460D01*
X1509100Y394484D01*
X1509076Y394503D01*
X1509050Y394514D01*
X1509023Y394518D01*
G01X1509161Y391171D02*
X1509158Y391209D01*
X1509151Y391246D01*
X1509138Y391280D01*
X1509121Y391310D01*
X1509100Y391335D01*
X1509076Y391353D01*
X1509050Y391364D01*
X1509023Y391368D01*
G01X1509161Y388022D02*
X1509158Y388060D01*
X1509151Y388097D01*
X1509138Y388130D01*
X1509121Y388161D01*
X1509100Y388185D01*
X1509076Y388203D01*
X1509050Y388215D01*
X1509023Y388218D01*
G01X1509161Y384872D02*
X1509158Y384910D01*
X1509151Y384947D01*
X1509138Y384981D01*
X1509121Y385011D01*
X1509100Y385036D01*
X1509076Y385054D01*
X1509050Y385065D01*
X1509023Y385069D01*
G01X1509161Y381722D02*
X1509158Y381761D01*
X1509151Y381797D01*
X1509138Y381831D01*
X1509121Y381862D01*
X1509100Y381886D01*
X1509076Y381904D01*
X1509050Y381915D01*
X1509023Y381919D01*
G01X1509161Y378573D02*
X1509158Y378611D01*
X1509151Y378648D01*
X1509138Y378682D01*
X1509121Y378712D01*
X1509100Y378736D01*
X1509076Y378754D01*
X1509050Y378766D01*
X1509023Y378770D01*
G01X1509161Y375423D02*
X1509158Y375461D01*
X1509151Y375498D01*
X1509138Y375532D01*
X1509121Y375562D01*
X1509100Y375587D01*
X1509076Y375605D01*
X1509050Y375616D01*
X1509023Y375620D01*
G01X1509161Y372274D02*
X1509158Y372312D01*
X1509151Y372349D01*
X1509138Y372382D01*
X1509121Y372413D01*
X1509100Y372437D01*
X1509076Y372455D01*
X1509050Y372466D01*
X1509023Y372470D01*
G01X1509161Y369124D02*
X1509158Y369162D01*
X1509151Y369199D01*
X1509138Y369233D01*
X1509121Y369263D01*
X1509100Y369287D01*
X1509076Y369306D01*
X1509050Y369317D01*
X1509023Y369321D01*
G01X1509161Y365974D02*
X1509158Y366013D01*
X1509151Y366049D01*
X1509138Y366083D01*
X1509121Y366114D01*
X1509100Y366138D01*
X1509076Y366156D01*
X1509050Y366167D01*
X1509023Y366171D01*
G01X1509161Y362825D02*
X1509158Y362863D01*
X1509151Y362900D01*
X1509138Y362934D01*
X1509121Y362964D01*
X1509100Y362988D01*
X1509076Y363006D01*
X1509050Y363018D01*
X1509023Y363022D01*
G01X1509161Y359675D02*
X1509158Y359713D01*
X1509151Y359750D01*
X1509138Y359784D01*
X1509121Y359814D01*
X1509100Y359839D01*
X1509076Y359857D01*
X1509050Y359868D01*
X1509023Y359872D01*
G01X1509161Y356525D02*
X1509158Y356564D01*
X1509151Y356601D01*
X1509138Y356634D01*
X1509121Y356665D01*
X1509100Y356689D01*
X1509076Y356707D01*
X1509050Y356718D01*
X1509023Y356722D01*
G01X1509161Y353376D02*
X1509158Y353414D01*
X1509151Y353451D01*
X1509138Y353485D01*
X1509121Y353515D01*
X1509100Y353539D01*
X1509076Y353558D01*
X1509050Y353569D01*
X1509023Y353573D01*
G01X1509161Y350226D02*
X1509158Y350265D01*
X1509151Y350301D01*
X1509138Y350335D01*
X1509121Y350365D01*
X1509100Y350390D01*
X1509076Y350408D01*
X1509050Y350419D01*
X1509023Y350423D01*
G01X1509161Y347077D02*
X1509158Y347115D01*
X1509151Y347152D01*
X1509138Y347186D01*
X1509121Y347216D01*
X1509100Y347240D01*
X1509076Y347258D01*
X1509050Y347270D01*
X1509023Y347274D01*
G01X1509161Y343927D02*
X1509158Y343965D01*
X1509151Y344002D01*
X1509138Y344036D01*
X1509121Y344066D01*
X1509100Y344091D01*
X1509076Y344109D01*
X1509050Y344120D01*
X1509023Y344124D01*
G01X1509161Y340777D02*
X1509158Y340816D01*
X1509151Y340852D01*
X1509138Y340886D01*
X1509121Y340917D01*
X1509100Y340941D01*
X1509076Y340959D01*
X1509050Y340970D01*
X1509023Y340974D01*
G01X1508208Y409970D02*
X1508130Y410561D01*
G01X1508208Y384970D02*
X1508130Y385561D01*
G01X1508208Y379970D02*
X1508130Y380561D01*
G01X1508208Y374970D02*
X1508130Y375561D01*
G01X1508208Y364970D02*
X1508130Y365561D01*
G01X1508208Y359970D02*
X1508130Y360561D01*
G01X1506239Y369970D02*
X1506161Y370561D01*
G01X1508208Y354970D02*
X1508130Y355561D01*
G01X1508208Y349970D02*
X1508130Y350561D01*
G01X1508208Y344970D02*
X1508130Y345561D01*
G01X1508208Y339970D02*
X1508130Y340561D01*
G01X1503727Y409675D02*
X1503758Y409578D01*
X1503847Y409506D01*
X1503974Y409478D01*
G01X1503727Y406525D02*
X1503758Y406428D01*
X1503847Y406356D01*
X1503974Y406329D01*
G01X1503727Y403376D02*
X1503758Y403279D01*
X1503847Y403207D01*
X1503974Y403179D01*
G01X1503727Y400226D02*
X1503758Y400129D01*
X1503847Y400057D01*
X1503974Y400029D01*
G01X1503727Y397077D02*
X1503758Y396980D01*
X1503847Y396907D01*
X1503974Y396880D01*
G01X1503727Y393927D02*
X1503758Y393830D01*
X1503847Y393758D01*
X1503974Y393730D01*
G01X1503727Y390777D02*
X1503758Y390680D01*
X1503847Y390608D01*
X1503974Y390581D01*
G01X1503727Y387628D02*
X1503758Y387531D01*
X1503847Y387459D01*
X1503974Y387431D01*
G01X1503727Y384478D02*
X1503758Y384381D01*
X1503847Y384309D01*
X1503974Y384281D01*
G01X1503727Y381329D02*
X1503758Y381232D01*
X1503847Y381159D01*
X1503974Y381132D01*
G01X1503727Y378179D02*
X1503758Y378082D01*
X1503847Y378010D01*
X1503974Y377982D01*
G01X1503727Y375029D02*
X1503758Y374932D01*
X1503847Y374860D01*
X1503974Y374833D01*
G01X1503727Y371880D02*
X1503758Y371783D01*
X1503847Y371711D01*
X1503974Y371683D01*
G01X1503727Y368730D02*
X1503758Y368633D01*
X1503847Y368561D01*
X1503974Y368533D01*
G01X1503727Y365581D02*
X1503758Y365484D01*
X1503847Y365411D01*
X1503974Y365384D01*
G01X1503727Y362431D02*
X1503758Y362334D01*
X1503847Y362262D01*
X1503974Y362234D01*
G01X1503727Y359281D02*
X1503758Y359184D01*
X1503847Y359112D01*
X1503974Y359085D01*
G01X1503727Y352982D02*
X1503758Y352885D01*
X1503847Y352813D01*
X1503974Y352785D01*
G01X1503727Y349833D02*
X1503758Y349736D01*
X1503847Y349663D01*
X1503974Y349636D01*
G01X1503727Y346683D02*
X1503758Y346586D01*
X1503847Y346514D01*
X1503974Y346486D01*
G01X1503727Y343533D02*
X1503758Y343436D01*
X1503847Y343364D01*
X1503974Y343337D01*
G01X1503727Y340384D02*
X1503758Y340287D01*
X1503847Y340215D01*
X1503974Y340187D01*
G01X1503717Y404653D02*
X1503750Y404554D01*
X1503838Y404483D01*
X1503964Y404456D01*
G01X1503717Y401504D02*
X1503750Y401405D01*
X1503838Y401334D01*
X1503964Y401307D01*
G01X1503717Y398354D02*
X1503750Y398255D01*
X1503838Y398184D01*
X1503964Y398157D01*
G01X1503717Y395204D02*
X1503750Y395105D01*
X1503838Y395035D01*
X1503964Y395008D01*
G01X1503717Y392055D02*
X1503750Y391956D01*
X1503838Y391885D01*
X1503964Y391858D01*
G01X1503717Y388905D02*
X1503750Y388806D01*
X1503838Y388735D01*
X1503964Y388708D01*
G01Y405834D02*
X1503838Y405807D01*
X1503748Y405734D01*
X1503717Y405638D01*
G01X1503964Y402685D02*
X1503838Y402657D01*
X1503748Y402585D01*
X1503717Y402488D01*
G01X1503964Y399535D02*
X1503838Y399508D01*
X1503748Y399435D01*
X1503717Y399338D01*
G01X1503964Y396386D02*
X1503838Y396358D01*
X1503748Y396285D01*
X1503717Y396189D01*
G01X1503964Y393236D02*
X1503838Y393209D01*
X1503748Y393136D01*
X1503717Y393039D01*
G01X1503964Y390086D02*
X1503838Y390059D01*
X1503748Y389986D01*
X1503717Y389889D01*
G01X1503974Y410266D02*
X1503846Y410238D01*
X1503758Y410165D01*
X1503727Y410069D01*
G01X1503974Y407116D02*
X1503846Y407088D01*
X1503758Y407015D01*
X1503727Y406919D01*
G01X1503974Y403966D02*
X1503846Y403939D01*
X1503758Y403866D01*
X1503727Y403770D01*
G01X1503974Y400817D02*
X1503846Y400789D01*
X1503758Y400716D01*
X1503727Y400620D01*
G01X1503974Y397667D02*
X1503846Y397639D01*
X1503758Y397567D01*
X1503727Y397470D01*
G01X1503974Y394518D02*
X1503846Y394490D01*
X1503758Y394417D01*
X1503727Y394321D01*
G01X1503974Y391368D02*
X1503846Y391340D01*
X1503758Y391267D01*
X1503727Y391171D01*
G01X1503974Y388218D02*
X1503846Y388191D01*
X1503758Y388118D01*
X1503727Y388022D01*
G01X1509060Y410561D02*
X1509332Y409970D01*
G01X1509060Y385561D02*
X1509332Y384970D01*
G01X1509060Y380561D02*
X1509332Y379970D01*
G01X1509060Y375561D02*
X1509332Y374970D01*
G01X1507091Y370561D02*
X1507364Y369970D01*
G01X1509060Y365561D02*
X1509332Y364970D01*
G01X1509060Y360561D02*
X1509332Y359970D01*
G01X1509060Y355561D02*
X1509332Y354970D01*
G01X1509060Y350561D02*
X1509332Y349970D01*
G01X1509060Y345561D02*
X1509332Y344970D01*
G01X1509060Y340561D02*
X1509332Y339970D01*
G01X1509023Y409478D02*
X1509050Y409482D01*
X1509075Y409493D01*
X1509099Y409511D01*
X1509121Y409536D01*
X1509138Y409566D01*
X1509150Y409599D01*
X1509158Y409636D01*
X1509161Y409675D01*
G01X1509023Y406329D02*
X1509050Y406332D01*
X1509075Y406343D01*
X1509099Y406362D01*
X1509121Y406386D01*
X1509138Y406416D01*
X1509150Y406450D01*
X1509158Y406487D01*
X1509161Y406525D01*
G01X1509023Y403179D02*
X1509050Y403183D01*
X1509075Y403194D01*
X1509099Y403212D01*
X1509121Y403237D01*
X1509138Y403266D01*
X1509150Y403300D01*
X1509158Y403337D01*
X1509161Y403376D01*
G01X1509023Y400029D02*
X1509050Y400033D01*
X1509075Y400044D01*
X1509099Y400062D01*
X1509121Y400087D01*
X1509138Y400117D01*
X1509150Y400151D01*
X1509158Y400187D01*
X1509161Y400226D01*
G01X1509023Y396880D02*
X1509050Y396884D01*
X1509075Y396895D01*
X1509099Y396913D01*
X1509121Y396937D01*
X1509138Y396967D01*
X1509150Y397001D01*
X1509158Y397038D01*
X1509161Y397077D01*
G01X1509023Y393730D02*
X1509050Y393734D01*
X1509075Y393745D01*
X1509099Y393763D01*
X1509121Y393788D01*
X1509138Y393818D01*
X1509150Y393851D01*
X1509158Y393888D01*
X1509161Y393927D01*
G01X1509023Y390581D02*
X1509050Y390584D01*
X1509075Y390595D01*
X1509099Y390613D01*
X1509121Y390638D01*
X1509138Y390668D01*
X1509150Y390702D01*
X1509158Y390739D01*
X1509161Y390777D01*
G01X1509023Y387431D02*
X1509050Y387435D01*
X1509075Y387446D01*
X1509099Y387464D01*
X1509121Y387489D01*
X1509138Y387518D01*
X1509150Y387552D01*
X1509158Y387589D01*
X1509161Y387628D01*
G01X1509023Y384281D02*
X1509050Y384285D01*
X1509075Y384296D01*
X1509099Y384314D01*
X1509121Y384339D01*
X1509138Y384369D01*
X1509150Y384403D01*
X1509158Y384439D01*
X1509161Y384478D01*
G01X1509023Y381132D02*
X1509050Y381136D01*
X1509075Y381147D01*
X1509099Y381165D01*
X1509121Y381189D01*
X1509138Y381219D01*
X1509150Y381253D01*
X1509158Y381290D01*
X1509161Y381329D01*
G01X1509023Y377982D02*
X1509050Y377986D01*
X1509075Y377997D01*
X1509099Y378015D01*
X1509121Y378040D01*
X1509138Y378070D01*
X1509150Y378103D01*
X1509158Y378140D01*
X1509161Y378179D01*
G01X1509023Y374833D02*
X1509050Y374836D01*
X1509075Y374847D01*
X1509099Y374865D01*
X1509121Y374890D01*
X1509138Y374920D01*
X1509150Y374954D01*
X1509158Y374991D01*
X1509161Y375029D01*
G01X1509023Y371683D02*
X1509050Y371687D01*
X1509075Y371698D01*
X1509099Y371716D01*
X1509121Y371741D01*
X1509138Y371770D01*
X1509150Y371804D01*
X1509158Y371841D01*
X1509161Y371880D01*
G01X1509023Y368533D02*
X1509050Y368537D01*
X1509075Y368548D01*
X1509099Y368566D01*
X1509121Y368591D01*
X1509138Y368621D01*
X1509150Y368655D01*
X1509158Y368691D01*
X1509161Y368730D01*
G01X1509023Y365384D02*
X1509050Y365388D01*
X1509075Y365399D01*
X1509099Y365417D01*
X1509121Y365441D01*
X1509138Y365471D01*
X1509150Y365505D01*
X1509158Y365542D01*
X1509161Y365581D01*
G01X1509023Y362234D02*
X1509050Y362238D01*
X1509075Y362249D01*
X1509099Y362267D01*
X1509121Y362292D01*
X1509138Y362321D01*
X1509150Y362355D01*
X1509158Y362392D01*
X1509161Y362431D01*
G01X1509023Y359085D02*
X1509050Y359088D01*
X1509075Y359099D01*
X1509099Y359117D01*
X1509121Y359142D01*
X1509138Y359172D01*
X1509150Y359206D01*
X1509158Y359242D01*
X1509161Y359281D01*
G01X1509023Y355935D02*
X1509050Y355939D01*
X1509075Y355950D01*
X1509099Y355968D01*
X1509121Y355993D01*
X1509138Y356022D01*
X1509150Y356056D01*
X1509158Y356093D01*
X1509161Y356132D01*
G01X1503974Y385069D02*
X1503846Y385041D01*
X1503758Y384968D01*
X1503727Y384872D01*
G01X1503974Y381919D02*
X1503846Y381891D01*
X1503758Y381819D01*
X1503727Y381722D01*
G01X1503974Y378770D02*
X1503846Y378742D01*
X1503758Y378669D01*
X1503727Y378573D01*
G01X1503974Y375620D02*
X1503846Y375592D01*
X1503758Y375519D01*
X1503727Y375423D01*
G01X1503974Y372470D02*
X1503846Y372443D01*
X1503758Y372370D01*
X1503727Y372274D01*
G01X1503974Y369321D02*
X1503846Y369293D01*
X1503758Y369220D01*
X1503727Y369124D01*
G01X1503974Y366171D02*
X1503846Y366143D01*
X1503758Y366071D01*
X1503727Y365974D01*
G01X1503974Y363022D02*
X1503846Y362994D01*
X1503758Y362921D01*
X1503727Y362825D01*
G01X1503974Y359872D02*
X1503846Y359844D01*
X1503758Y359771D01*
X1503727Y359675D01*
G01X1503974Y353573D02*
X1503846Y353545D01*
X1503758Y353472D01*
X1503727Y353376D01*
G01X1503974Y350423D02*
X1503846Y350395D01*
X1503758Y350323D01*
X1503727Y350226D01*
G01X1503974Y347274D02*
X1503846Y347246D01*
X1503758Y347173D01*
X1503727Y347077D01*
G01X1503974Y344124D02*
X1503846Y344096D01*
X1503758Y344023D01*
X1503727Y343927D01*
G01X1503974Y340974D02*
X1503846Y340947D01*
X1503758Y340874D01*
X1503727Y340777D01*
G01X1503499Y409577D02*
X1503633Y409379D01*
X1503768Y409182D01*
X1503904Y408986D01*
G01X1503499Y384577D02*
X1503633Y384379D01*
X1503768Y384182D01*
X1503904Y383986D01*
G01X1503590Y379577D02*
X1503727Y379379D01*
X1503865Y379182D01*
X1504004Y378986D01*
G01X1503590Y374577D02*
X1503727Y374379D01*
X1503865Y374182D01*
X1504004Y373986D01*
G01X1501621Y369577D02*
X1501758Y369379D01*
X1501896Y369182D01*
X1502036Y368986D01*
G01X1503590Y364577D02*
X1503727Y364379D01*
X1503865Y364182D01*
X1504004Y363986D01*
G01X1503590Y359577D02*
X1503727Y359379D01*
X1503865Y359182D01*
X1504004Y358986D01*
G01X1503590Y354577D02*
X1503727Y354379D01*
X1503865Y354182D01*
X1504004Y353986D01*
G01X1503590Y349577D02*
X1503727Y349379D01*
X1503865Y349182D01*
X1504004Y348986D01*
G01X1503590Y344577D02*
X1503727Y344379D01*
X1503865Y344182D01*
X1504004Y343986D01*
G01X1509817Y410561D02*
X1510241Y409970D01*
G01X1509817Y385561D02*
X1510241Y384970D01*
G01X1509749Y380561D02*
X1510176Y379970D01*
G01X1509749Y375561D02*
X1510176Y374970D01*
G01X1507781Y370561D02*
X1508207Y369970D01*
G01X1509749Y365561D02*
X1510176Y364970D01*
G01X1509749Y360561D02*
X1510176Y359970D01*
G01X1509749Y355561D02*
X1510176Y354970D01*
G01X1509749Y350561D02*
X1510176Y349970D01*
G01X1509749Y345561D02*
X1510176Y344970D01*
G01X1509749Y340561D02*
X1510176Y339970D01*
G01X1508945Y405834D02*
X1508974Y405831D01*
X1509001Y405820D01*
X1509027Y405801D01*
X1509049Y405777D01*
X1509068Y405747D01*
X1509081Y405713D01*
X1509090Y405676D01*
X1509093Y405638D01*
G01X1509817Y410561D02*
X1503904D01*
G01X1503974Y410266D02*
X1510058D01*
G01X1503727Y410069D02*
X1510338D01*
G01X1510241Y409970D02*
X1503499D01*
G01X1510338Y409675D02*
X1503727D01*
G01X1503499Y409577D02*
X1510241D01*
G01X1503974Y409478D02*
X1510058D01*
G01X1501709Y409380D02*
X1528401D01*
G01X1509817Y408986D02*
X1503904D01*
G01X1499740Y408199D02*
X1506209D01*
G01X1503974Y407116D02*
X1510058D01*
G01X1520212Y407037D02*
X1501709D01*
G01X1528401Y407018D02*
X1506209D01*
G01X1503727Y406919D02*
X1510338D01*
G01Y406525D02*
X1503727D01*
G01X1503974Y406329D02*
X1510058D01*
G01X1509772Y405834D02*
X1503964D01*
G01X1510035Y405638D02*
X1503717D01*
G01Y404653D02*
X1510035D01*
G01X1509772Y404456D02*
X1503964D01*
G01X1503974Y403966D02*
X1510058D01*
G01X1503727Y403770D02*
X1510338D01*
G01Y403376D02*
X1503727D01*
G01X1503974Y403179D02*
X1510058D01*
G01X1509772Y402685D02*
X1503964D01*
G01X1510035Y402488D02*
X1503717D01*
G01Y401504D02*
X1510035D01*
G01X1509772Y401307D02*
X1503964D01*
G01X1503974Y400817D02*
X1510058D01*
G01X1503727Y400620D02*
X1510338D01*
G01Y400226D02*
X1503727D01*
G01X1503974Y400029D02*
X1510058D01*
G01X1509772Y399535D02*
X1503964D01*
G01X1510035Y399338D02*
X1503717D01*
G01Y398354D02*
X1510035D01*
G01X1509772Y398157D02*
X1503964D01*
G01X1503974Y397667D02*
X1510058D01*
G01X1503727Y397470D02*
X1510338D01*
G01Y397077D02*
X1503727D01*
G01X1503974Y396880D02*
X1510058D01*
G01X1509772Y396386D02*
X1503964D01*
G01X1510035Y396189D02*
X1503717D01*
G01Y395204D02*
X1510035D01*
G01X1509772Y395008D02*
X1503964D01*
G01X1503974Y394518D02*
X1510058D01*
G01X1503727Y394321D02*
X1510338D01*
G01Y393927D02*
X1503727D01*
G01X1503974Y393730D02*
X1510058D01*
G01X1509772Y393236D02*
X1503964D01*
G01X1510035Y393039D02*
X1503717D01*
G01Y392055D02*
X1510035D01*
G01X1509772Y391858D02*
X1503964D01*
G01X1503974Y391368D02*
X1510058D01*
G01X1503727Y391171D02*
X1510338D01*
G01Y390777D02*
X1503727D01*
G01X1503974Y390581D02*
X1510058D01*
G01X1509772Y390086D02*
X1503964D01*
G01X1510035Y389889D02*
X1503717D01*
G01Y388905D02*
X1510035D01*
G01X1509772Y388708D02*
X1503964D01*
G01X1503974Y388218D02*
X1510058D01*
G01X1503727Y388022D02*
X1510338D01*
G01Y387628D02*
X1503727D01*
G01X1506209Y387529D02*
X1528401D01*
G01X1520212Y387510D02*
X1501709D01*
G01X1503974Y387431D02*
X1510058D01*
G01X1506209Y386348D02*
X1499740D01*
G01X1509817Y385561D02*
X1503904D01*
G01X1528401Y385167D02*
X1501709D01*
G01X1503974Y385069D02*
X1510058D01*
G01X1510241Y384970D02*
X1503499D01*
G01X1503727Y384872D02*
X1510338D01*
G01X1503499Y384577D02*
X1510241D01*
G01X1510338Y384478D02*
X1503727D01*
G01X1503974Y384281D02*
X1510058D01*
G01X1509817Y383986D02*
X1503904D01*
G01X1503974Y381919D02*
X1510058D01*
G01X1503727Y381722D02*
X1510338D01*
G01Y381329D02*
X1503727D01*
G01X1503974Y381132D02*
X1510058D01*
G01X1500751Y381073D02*
X1520212D01*
G01X1509749Y380561D02*
X1504004D01*
G01X1510176Y379970D02*
X1503590D01*
G01Y379577D02*
X1510176D01*
G01X1504004Y378986D02*
X1509749D01*
G01X1503974Y378770D02*
X1510058D01*
G01X1503727Y378573D02*
X1510338D01*
G01Y378179D02*
X1503727D01*
G01X1503974Y377982D02*
X1510058D01*
G01X1503974Y375620D02*
X1510058D01*
G01X1509749Y375561D02*
X1504004D01*
G01X1503727Y375423D02*
X1510338D01*
G01Y375029D02*
X1503727D01*
G01X1510176Y374970D02*
X1503590D01*
G01X1503974Y374833D02*
X1510058D01*
G01X1503590Y374577D02*
X1510176D01*
G01X1504004Y373986D02*
X1509749D01*
G01X1503974Y372470D02*
X1510058D01*
G01X1503727Y372274D02*
X1510338D01*
G01Y371880D02*
X1503727D01*
G01X1503974Y371683D02*
X1510058D01*
G01X1507781Y370561D02*
X1502036D01*
G01X1508207Y369970D02*
X1501621D01*
G01Y369577D02*
X1508207D01*
G01X1503974Y369321D02*
X1510058D01*
G01X1503727Y369124D02*
X1510338D01*
G01X1502036Y368986D02*
X1507781D01*
G01X1501709Y368829D02*
X1528401D01*
G01X1510338Y368730D02*
X1503727D01*
G01X1503974Y368533D02*
X1510058D01*
G01X1528401Y366466D02*
X1501709D01*
G01X1503974Y366171D02*
X1510058D01*
G01X1503727Y365974D02*
X1510338D01*
G01Y365581D02*
X1503727D01*
G01X1509749Y365561D02*
X1504004D01*
G01X1503974Y365384D02*
X1510058D01*
G01X1510176Y364970D02*
X1503590D01*
G01Y364577D02*
X1510176D01*
G01X1504004Y363986D02*
X1509749D01*
G01X1503974Y363022D02*
X1510058D01*
G01X1503727Y362825D02*
X1510338D01*
G01Y362431D02*
X1503727D01*
G01X1503974Y362234D02*
X1510058D01*
G01X1509749Y360561D02*
X1504004D01*
G01X1510176Y359970D02*
X1503590D01*
G01X1503974Y359872D02*
X1510058D01*
G01X1503727Y359675D02*
X1510338D01*
G01X1503590Y359577D02*
X1510176D01*
G01X1510338Y359281D02*
X1503727D01*
G01X1503974Y359085D02*
X1510058D01*
G01X1504004Y358986D02*
X1509749D01*
G01X1503974Y356722D02*
X1510058D01*
G01X1503727Y356525D02*
X1510338D01*
G01Y356132D02*
X1503727D01*
G01X1503974Y355935D02*
X1510058D01*
G01X1509749Y355561D02*
X1504004D01*
G01X1510176Y354970D02*
X1503590D01*
G01Y354577D02*
X1510176D01*
G01X1504004Y353986D02*
X1509749D01*
G01X1503974Y353573D02*
X1510058D01*
G01X1503727Y353376D02*
X1510338D01*
G01Y352982D02*
X1503727D01*
G01X1503974Y352785D02*
X1510058D01*
G01X1509023D02*
X1509050Y352789D01*
X1509075Y352800D01*
X1509099Y352818D01*
X1509121Y352843D01*
X1509138Y352873D01*
X1509150Y352907D01*
X1509158Y352943D01*
X1509161Y352982D01*
G01X1509023Y349636D02*
X1509050Y349639D01*
X1509075Y349651D01*
X1509099Y349669D01*
X1509121Y349693D01*
X1509138Y349723D01*
X1509150Y349757D01*
X1509158Y349794D01*
X1509161Y349833D01*
G01X1509023Y346486D02*
X1509050Y346490D01*
X1509075Y346501D01*
X1509099Y346519D01*
X1509121Y346544D01*
X1509138Y346573D01*
X1509150Y346607D01*
X1509158Y346644D01*
X1509161Y346683D01*
G01X1509023Y343337D02*
X1509050Y343340D01*
X1509075Y343351D01*
X1509099Y343369D01*
X1509121Y343394D01*
X1509138Y343424D01*
X1509150Y343458D01*
X1509158Y343494D01*
X1509161Y343533D01*
G01X1509023Y340187D02*
X1509050Y340191D01*
X1509075Y340202D01*
X1509099Y340220D01*
X1509121Y340245D01*
X1509138Y340274D01*
X1509150Y340308D01*
X1509158Y340345D01*
X1509161Y340384D01*
G01X1501709Y407037D02*
X1499740Y409006D01*
G01X1508572Y410266D02*
X1508610Y410239D01*
X1508638Y410167D01*
X1508648Y410069D01*
G01X1508572Y407116D02*
X1508610Y407090D01*
X1508638Y407018D01*
X1508648Y406919D01*
G01X1508572Y403966D02*
X1508610Y403940D01*
X1508638Y403868D01*
X1508648Y403770D01*
G01X1508572Y400817D02*
X1508610Y400790D01*
X1508638Y400718D01*
X1508648Y400620D01*
G01X1508572Y397667D02*
X1508610Y397641D01*
X1508638Y397569D01*
X1508648Y397470D01*
G01X1508572Y394518D02*
X1508610Y394491D01*
X1508638Y394419D01*
X1508648Y394321D01*
G01X1508572Y391368D02*
X1508610Y391342D01*
X1508638Y391270D01*
X1508648Y391171D01*
G01X1508572Y388218D02*
X1508610Y388192D01*
X1508638Y388120D01*
X1508648Y388022D01*
G01X1508572Y385069D02*
X1508610Y385042D01*
X1508638Y384970D01*
X1508648Y384872D01*
G01X1508572Y381919D02*
X1508610Y381893D01*
X1508638Y381821D01*
X1508648Y381722D01*
G01X1508572Y378770D02*
X1508610Y378743D01*
X1508638Y378671D01*
X1508648Y378573D01*
G01X1507908Y405834D02*
X1507914Y405831D01*
X1507920Y405820D01*
X1507926Y405801D01*
X1507931Y405777D01*
X1507935Y405747D01*
X1507938Y405713D01*
X1507940Y405676D01*
X1507941Y405638D01*
G01X1507908Y402685D02*
X1507914Y402681D01*
X1507920Y402670D01*
X1507926Y402652D01*
X1507931Y402627D01*
X1507935Y402597D01*
X1507938Y402564D01*
X1507940Y402527D01*
X1507941Y402488D01*
G01X1507908Y399535D02*
X1507914Y399531D01*
X1507920Y399520D01*
X1507926Y399502D01*
X1507931Y399477D01*
X1507935Y399448D01*
X1507938Y399414D01*
X1507940Y399377D01*
X1507941Y399338D01*
G01X1507908Y396386D02*
X1507914Y396382D01*
X1507920Y396371D01*
X1507926Y396353D01*
X1507931Y396328D01*
X1507935Y396298D01*
X1507938Y396264D01*
X1507940Y396228D01*
X1507941Y396189D01*
G01X1507908Y393236D02*
X1507914Y393232D01*
X1507920Y393221D01*
X1507926Y393203D01*
X1507931Y393178D01*
X1507935Y393149D01*
X1507938Y393115D01*
X1507940Y393078D01*
X1507941Y393039D01*
G01X1507908Y390086D02*
X1507914Y390083D01*
X1507920Y390071D01*
X1507926Y390053D01*
X1507931Y390029D01*
X1507935Y389999D01*
X1507938Y389965D01*
X1507940Y389928D01*
X1507941Y389889D01*
G01X1503974Y355935D02*
X1503847Y355962D01*
X1503758Y356035D01*
X1503727Y356132D01*
G01X1508945Y402685D02*
X1508974Y402681D01*
X1509001Y402670D01*
X1509027Y402652D01*
X1509049Y402627D01*
X1509068Y402597D01*
X1509081Y402564D01*
X1509090Y402527D01*
X1509093Y402488D01*
G01X1508945Y399535D02*
X1508974Y399531D01*
X1509001Y399520D01*
X1509027Y399502D01*
X1509049Y399477D01*
X1509068Y399448D01*
X1509081Y399414D01*
X1509090Y399377D01*
X1509093Y399338D01*
G01X1508945Y396386D02*
X1508974Y396382D01*
X1509001Y396371D01*
X1509027Y396353D01*
X1509049Y396328D01*
X1509068Y396298D01*
X1509081Y396264D01*
X1509090Y396228D01*
X1509093Y396189D01*
G01X1508945Y393236D02*
X1508974Y393232D01*
X1509001Y393221D01*
X1509027Y393203D01*
X1509049Y393178D01*
X1509068Y393149D01*
X1509081Y393115D01*
X1509090Y393078D01*
X1509093Y393039D01*
G01X1508945Y390086D02*
X1508974Y390083D01*
X1509001Y390071D01*
X1509027Y390053D01*
X1509049Y390029D01*
X1509068Y389999D01*
X1509081Y389965D01*
X1509090Y389928D01*
X1509093Y389889D01*
G01X1509749Y350561D02*
X1504004D01*
G01X1503974Y350423D02*
X1510058D01*
G01X1503727Y350226D02*
X1510338D01*
G01X1510176Y349970D02*
X1503590D01*
G01X1501709Y349931D02*
X1528401D01*
G01X1510338Y349833D02*
X1503727D01*
G01X1503974Y349636D02*
X1510058D01*
G01X1503590Y349577D02*
X1510176D01*
G01X1504004Y348986D02*
X1509749D01*
G01X1528401Y347569D02*
X1501709D01*
G01X1503974Y347274D02*
X1510058D01*
G01X1503727Y347077D02*
X1510338D01*
G01Y346683D02*
X1503727D01*
G01X1503974Y346486D02*
X1510058D01*
G01X1509749Y345561D02*
X1504004D01*
G01X1510176Y344970D02*
X1503590D01*
G01Y344577D02*
X1510176D01*
G01X1503974Y344124D02*
X1510058D01*
G01X1504004Y343986D02*
X1509749D01*
G01X1503727Y343927D02*
X1510338D01*
G01Y343533D02*
X1503727D01*
G01X1503974Y343337D02*
X1510058D01*
G01X1503974Y340974D02*
X1510058D01*
G01X1503727Y340777D02*
X1510338D01*
G01X1509749Y340561D02*
X1504004D01*
G01X1510338Y340384D02*
X1503727D01*
G01X1503974Y340187D02*
X1510058D01*
G01X1510176Y339970D02*
X1503590D01*
G01Y339577D02*
X1510176D01*
G01X1508572Y375620D02*
X1508610Y375594D01*
X1508638Y375521D01*
X1508648Y375423D01*
G01X1508572Y372470D02*
X1508610Y372444D01*
X1508638Y372372D01*
X1508648Y372274D01*
G01X1508572Y369321D02*
X1508610Y369294D01*
X1508638Y369222D01*
X1508648Y369124D01*
G01X1508572Y366171D02*
X1508610Y366145D01*
X1508638Y366073D01*
X1508648Y365974D01*
G01X1508572Y363022D02*
X1508610Y362995D01*
X1508638Y362923D01*
X1508648Y362825D01*
G01X1508572Y359872D02*
X1508610Y359846D01*
X1508638Y359773D01*
X1508648Y359675D01*
G01X1508572Y356722D02*
X1508610Y356696D01*
X1508638Y356624D01*
X1508648Y356525D01*
G01X1508572Y353573D02*
X1508610Y353546D01*
X1508638Y353474D01*
X1508648Y353376D01*
G01X1508572Y350423D02*
X1508610Y350397D01*
X1508638Y350325D01*
X1508648Y350226D01*
G01X1508572Y347274D02*
X1508610Y347247D01*
X1508638Y347175D01*
X1508648Y347077D01*
G01X1508572Y344124D02*
X1508610Y344097D01*
X1508638Y344025D01*
X1508648Y343927D01*
G01X1508572Y340974D02*
X1508610Y340948D01*
X1508638Y340876D01*
X1508648Y340777D01*
G01X1539110Y338986D02*
Y340561D01*
G01X1535961D02*
Y338986D01*
G01X1533008Y340561D02*
Y338986D01*
G01X1531945D02*
X1539110D01*
G01X1534976Y338789D02*
X1533992D01*
G01X1531551Y380955D02*
G03X1531945Y380561I394J0D01*
G01Y408986D02*
G03X1531551Y408592I0J-394D01*
G01Y410955D02*
G03X1531945Y410561I394J0D01*
G01Y383986D02*
G03X1531551Y383592I0J-394D01*
G01Y385955D02*
G03X1531945Y385561I394J0D01*
G01Y363986D02*
G03X1531551Y363592I0J-394D01*
G01Y365955D02*
G03X1531945Y365561I394J0D01*
G01Y378986D02*
G03X1531551Y378592I0J-394D01*
G01X1531945Y373986D02*
G03X1531551Y373592I0J-394D01*
G01Y375955D02*
G03X1531945Y375561I394J0D01*
G01Y353986D02*
G03X1531551Y353592I0J-394D01*
G01Y355955D02*
G03X1531945Y355561I394J0D01*
G01Y348986D02*
G03X1531551Y348592I0J-394D01*
G01Y350955D02*
G03X1531945Y350561I394J0D01*
G01X1531551Y340955D02*
G03X1531945Y340561I394J0D01*
G01Y343986D02*
G03X1531551Y343592I0J-394D01*
G01Y345955D02*
G03X1531945Y345561I394J0D01*
G01Y358986D02*
G03X1531551Y358592I0J-394D01*
G01Y360955D02*
G03X1531945Y360561I394J0D01*
G01X1549937Y344124D02*
Y343337D01*
G01Y340974D02*
Y340187D01*
G01Y347274D02*
Y346486D01*
G01Y353573D02*
Y352785D01*
G01Y350423D02*
Y349636D01*
G01Y356722D02*
Y355935D01*
G01Y363022D02*
Y362234D01*
G01Y359872D02*
Y359085D01*
G01Y366171D02*
Y365384D01*
G01Y372470D02*
Y371683D01*
G01Y369321D02*
Y368533D01*
G01Y375620D02*
Y374833D01*
G01Y381919D02*
Y381132D01*
G01Y378770D02*
Y377982D01*
G01Y385069D02*
Y384281D01*
G01Y391368D02*
Y390581D01*
G01Y388218D02*
Y387431D01*
G01Y394518D02*
Y393730D01*
G01Y400817D02*
Y400029D01*
G01Y397667D02*
Y396880D01*
G01Y403966D02*
Y403179D01*
G01Y410266D02*
Y409478D01*
G01Y407116D02*
Y406329D01*
G01X1548163Y344124D02*
Y343337D01*
G01Y340974D02*
Y340187D01*
G01Y347274D02*
Y346486D01*
G01Y353573D02*
Y352785D01*
G01Y350423D02*
Y349636D01*
G01Y356722D02*
Y355935D01*
G01Y363022D02*
Y362234D01*
G01Y359872D02*
Y359085D01*
G01Y366171D02*
Y365384D01*
G01Y372470D02*
Y371683D01*
G01Y369321D02*
Y368533D01*
G01Y375620D02*
Y374833D01*
G01Y381919D02*
Y381132D01*
G01Y378770D02*
Y377982D01*
G01Y385069D02*
Y384281D01*
G01Y391368D02*
Y390581D01*
G01Y388218D02*
Y387431D01*
G01Y394518D02*
Y393730D01*
G01Y400817D02*
Y400029D01*
G01Y397667D02*
Y396880D01*
G01Y403966D02*
Y403179D01*
G01Y410266D02*
Y409478D01*
G01Y407116D02*
Y406329D01*
G01X1547975Y409478D02*
Y410266D01*
G01Y406329D02*
Y407116D01*
G01Y403179D02*
Y403966D01*
G01Y400029D02*
Y400817D01*
G01Y396880D02*
Y397667D01*
G01Y393730D02*
Y394518D01*
G01Y390581D02*
Y391368D01*
G01Y387431D02*
Y388218D01*
G01Y384281D02*
Y385069D01*
G01Y381132D02*
Y381919D01*
G01Y377982D02*
Y378770D01*
G01Y374833D02*
Y375620D01*
G01Y371683D02*
Y372470D01*
G01Y368533D02*
Y369321D01*
G01Y365384D02*
Y366171D01*
G01Y362234D02*
Y363022D01*
G01Y359085D02*
Y359872D01*
G01Y355935D02*
Y356722D01*
G01Y352785D02*
Y353573D01*
G01Y349636D02*
Y350423D01*
G01Y346486D02*
Y347274D01*
G01Y343337D02*
Y344124D01*
G01Y340187D02*
Y340974D01*
G01X1545138Y409478D02*
Y410266D01*
G01Y406329D02*
Y407116D01*
G01Y403179D02*
Y403966D01*
G01Y400029D02*
Y400817D01*
G01Y396880D02*
Y397667D01*
G01Y393730D02*
Y394518D01*
G01Y390581D02*
Y391368D01*
G01Y387431D02*
Y388218D01*
G01Y384281D02*
Y385069D01*
G01Y381132D02*
Y381919D01*
G01Y377982D02*
Y378770D01*
G01Y374833D02*
Y375620D01*
G01Y371683D02*
Y372470D01*
G01Y368533D02*
Y369321D01*
G01Y365384D02*
Y366171D01*
G01Y362234D02*
Y363022D01*
G01Y359085D02*
Y359872D01*
G01Y355935D02*
Y356722D01*
G01Y352785D02*
Y353573D01*
G01Y349636D02*
Y350423D01*
G01Y346486D02*
Y347274D01*
G01Y343337D02*
Y344124D01*
G01Y340187D02*
Y340974D01*
G01X1544197Y344124D02*
Y343337D01*
G01Y340974D02*
Y340187D01*
G01Y347274D02*
Y346486D01*
G01Y353573D02*
Y352785D01*
G01Y350423D02*
Y349636D01*
G01Y356722D02*
Y355935D01*
G01Y363022D02*
Y362234D01*
G01Y359872D02*
Y359085D01*
G01Y366171D02*
Y365384D01*
G01Y372470D02*
Y371683D01*
G01Y369321D02*
Y368533D01*
G01Y375620D02*
Y374833D01*
G01Y381919D02*
Y381132D01*
G01Y378770D02*
Y377982D01*
G01Y385069D02*
Y384281D01*
G01Y391368D02*
Y390581D01*
G01Y388218D02*
Y387431D01*
G01Y394518D02*
Y393730D01*
G01Y400817D02*
Y400029D01*
G01Y397667D02*
Y396880D01*
G01Y403966D02*
Y403179D01*
G01Y410266D02*
Y409478D01*
G01Y407116D02*
Y406329D01*
G01X1542605Y344124D02*
Y343337D01*
G01Y340974D02*
Y340187D01*
G01Y347274D02*
Y346486D01*
G01Y353573D02*
Y352785D01*
G01Y350423D02*
Y349636D01*
G01Y356722D02*
Y355935D01*
G01Y363022D02*
Y362234D01*
G01Y359872D02*
Y359085D01*
G01Y366171D02*
Y365384D01*
G01Y372470D02*
Y371683D01*
G01Y369321D02*
Y368533D01*
G01Y375620D02*
Y374833D01*
G01Y381919D02*
Y381132D01*
G01Y378770D02*
Y377982D01*
G01Y385069D02*
Y384281D01*
G01Y391368D02*
Y390581D01*
G01Y388218D02*
Y387431D01*
G01Y394518D02*
Y393730D01*
G01Y400817D02*
Y400029D01*
G01Y397667D02*
Y396880D01*
G01Y403966D02*
Y403179D01*
G01Y410266D02*
Y409478D01*
G01Y407116D02*
Y406329D01*
G01X1542457Y344124D02*
Y343337D01*
G01Y340974D02*
Y340187D01*
G01Y347274D02*
Y346486D01*
G01Y353573D02*
Y352785D01*
G01Y350423D02*
Y349636D01*
G01Y356722D02*
Y355935D01*
G01Y363022D02*
Y362234D01*
G01Y359872D02*
Y359085D01*
G01Y366171D02*
Y365384D01*
G01Y372470D02*
Y371683D01*
G01Y369321D02*
Y368533D01*
G01Y375620D02*
Y374833D01*
G01Y381919D02*
Y381132D01*
G01Y378770D02*
Y377982D01*
G01Y385069D02*
Y384281D01*
G01Y391368D02*
Y390581D01*
G01Y388218D02*
Y387431D01*
G01Y394518D02*
Y393730D01*
G01Y400817D02*
Y400029D01*
G01Y397667D02*
Y396880D01*
G01Y403966D02*
Y403179D01*
G01Y410266D02*
Y409478D01*
G01Y407116D02*
Y406329D01*
G01X1541519Y410266D02*
Y412628D01*
G01Y407116D02*
Y409478D01*
G01Y403966D02*
Y406329D01*
G01Y400817D02*
Y403179D01*
G01Y397667D02*
Y400029D01*
G01Y394518D02*
Y396880D01*
G01Y391368D02*
Y393730D01*
G01Y388218D02*
Y390581D01*
G01Y385069D02*
Y387431D01*
G01Y381919D02*
Y384281D01*
G01Y378770D02*
Y381132D01*
G01Y375620D02*
Y377982D01*
G01Y372470D02*
Y374833D01*
G01Y369321D02*
Y371683D01*
G01Y366171D02*
Y368533D01*
G01Y363022D02*
Y365384D01*
G01Y359872D02*
Y362234D01*
G01Y356722D02*
Y359085D01*
G01Y353573D02*
Y355935D01*
G01Y350423D02*
Y352785D01*
G01Y347274D02*
Y349636D01*
G01Y344124D02*
Y346486D01*
G01Y340974D02*
Y343337D01*
G01X1539791Y344124D02*
Y343337D01*
G01Y340974D02*
Y340187D01*
G01Y347274D02*
Y346486D01*
G01Y353573D02*
Y352785D01*
G01Y350423D02*
Y349636D01*
G01Y356722D02*
Y355935D01*
G01Y363022D02*
Y362234D01*
G01Y359872D02*
Y359085D01*
G01Y366171D02*
Y365384D01*
G01Y372470D02*
Y371683D01*
G01Y369321D02*
Y368533D01*
G01Y375620D02*
Y374833D01*
G01Y381919D02*
Y381132D01*
G01Y378770D02*
Y377982D01*
G01Y385069D02*
Y384281D01*
G01Y391368D02*
Y390581D01*
G01Y388218D02*
Y387431D01*
G01Y394518D02*
Y393730D01*
G01Y400817D02*
Y400029D01*
G01Y397667D02*
Y396880D01*
G01Y403966D02*
Y403179D01*
G01Y410266D02*
Y409478D01*
G01Y407116D02*
Y406329D01*
G01X1539440Y393651D02*
Y391447D01*
G01Y403100D02*
Y400896D01*
G01X1539110Y408986D02*
Y410561D01*
G01Y383986D02*
Y385561D01*
G01Y378986D02*
Y380561D01*
G01Y373986D02*
Y375561D01*
G01Y363986D02*
Y365561D01*
G01Y358986D02*
Y360561D01*
G01Y353986D02*
Y355561D01*
G01Y348986D02*
Y350561D01*
G01Y343986D02*
Y345561D01*
G01X1538139Y409478D02*
Y410266D01*
G01Y406329D02*
Y407116D01*
G01Y403179D02*
Y403966D01*
G01Y400029D02*
Y400817D01*
G01Y396880D02*
Y397667D01*
G01Y393730D02*
Y394518D01*
G01Y390581D02*
Y391368D01*
G01Y387431D02*
Y388218D01*
G01Y384281D02*
Y385069D01*
G01Y381132D02*
Y381919D01*
G01Y377982D02*
Y378770D01*
G01Y374833D02*
Y375620D01*
G01Y371683D02*
Y372470D01*
G01Y368533D02*
Y369321D01*
G01Y365384D02*
Y366171D01*
G01Y362234D02*
Y363022D01*
G01Y359085D02*
Y359872D01*
G01Y355935D02*
Y356722D01*
G01Y352785D02*
Y353573D01*
G01Y349636D02*
Y350423D01*
G01Y346486D02*
Y347274D01*
G01Y343337D02*
Y344124D01*
G01Y340187D02*
Y340974D01*
G01X1537984Y391447D02*
Y387628D01*
G01Y400896D02*
Y393651D01*
G01Y406919D02*
Y403100D01*
G01X1537576Y404557D02*
Y405738D01*
G01Y401407D02*
Y402588D01*
G01Y398258D02*
Y399439D01*
G01Y395108D02*
Y396289D01*
G01Y391959D02*
Y393140D01*
G01Y388809D02*
Y389990D01*
G01X1537558Y400896D02*
Y403100D01*
G01Y391447D02*
Y393651D01*
G01X1537506Y406919D02*
Y387628D01*
G01X1537142Y368986D02*
Y370561D01*
G01X1536156Y409478D02*
Y410266D01*
G01Y406329D02*
Y407116D01*
G01Y403179D02*
Y403966D01*
G01Y400029D02*
Y400817D01*
G01Y396880D02*
Y397667D01*
G01Y393730D02*
Y394518D01*
G01Y390581D02*
Y391368D01*
G01Y387431D02*
Y388218D01*
G01Y384281D02*
Y385069D01*
G01Y381132D02*
Y381919D01*
G01Y377982D02*
Y378770D01*
G01Y374833D02*
Y375620D01*
G01Y371683D02*
Y372470D01*
G01Y368533D02*
Y369321D01*
G01Y365384D02*
Y366171D01*
G01Y362234D02*
Y363022D01*
G01Y359085D02*
Y359872D01*
G01Y355935D02*
Y356722D01*
G01Y352785D02*
Y353573D01*
G01Y349636D02*
Y350423D01*
G01Y346486D02*
Y347274D01*
G01Y343337D02*
Y344124D01*
G01Y340187D02*
Y340974D01*
G01X1535961Y345561D02*
Y343986D01*
G01Y350561D02*
Y348986D01*
G01Y355561D02*
Y353986D01*
G01Y360561D02*
Y358986D01*
G01Y365561D02*
Y363986D01*
G01Y375561D02*
Y373986D01*
G01Y380561D02*
Y378986D01*
G01Y385561D02*
Y383986D01*
G01Y410561D02*
Y408986D01*
G01X1534976Y346348D02*
Y343199D01*
G01Y351348D02*
Y348199D01*
G01Y356348D02*
Y353199D01*
G01Y361348D02*
Y358199D01*
G01Y366348D02*
Y363199D01*
G01Y376348D02*
Y373199D01*
G01Y381348D02*
Y378199D01*
G01Y386348D02*
Y383199D01*
G01Y411348D02*
Y408199D01*
G01X1534427Y389990D02*
Y388809D01*
G01Y396289D02*
Y395108D01*
G01Y393140D02*
Y391959D01*
G01Y399439D02*
Y398258D01*
G01Y405738D02*
Y404557D01*
G01Y402588D02*
Y401407D01*
G01X1534149Y406919D02*
Y387628D01*
G01X1533992Y346348D02*
Y343199D01*
G01Y351348D02*
Y348199D01*
G01Y356348D02*
Y353199D01*
G01Y361348D02*
Y358199D01*
G01Y366348D02*
Y363199D01*
G01Y370561D02*
Y368986D01*
G01Y376348D02*
Y373199D01*
G01Y381348D02*
Y378199D01*
G01Y386348D02*
Y383199D01*
G01Y411348D02*
Y408199D01*
G01X1533442Y406427D02*
Y388120D01*
G01X1533232Y387628D02*
Y406919D01*
G01X1533008Y345561D02*
Y343986D01*
G01Y350561D02*
Y348986D01*
G01Y355561D02*
Y353986D01*
G01Y360561D02*
Y358986D01*
G01Y365561D02*
Y363986D01*
G01Y371348D02*
Y368199D01*
G01Y375561D02*
Y373986D01*
G01Y380561D02*
Y378986D01*
G01Y385561D02*
Y383986D01*
G01Y410561D02*
Y408986D01*
G01X1532793Y344124D02*
Y343337D01*
G01Y340974D02*
Y340187D01*
G01Y347274D02*
Y346486D01*
G01Y353573D02*
Y352785D01*
G01Y350423D02*
Y349636D01*
G01Y356722D02*
Y355935D01*
G01Y363022D02*
Y362234D01*
G01Y359872D02*
Y359085D01*
G01Y366171D02*
Y365384D01*
G01Y372470D02*
Y371683D01*
G01Y369321D02*
Y368533D01*
G01Y375620D02*
Y374833D01*
G01Y381919D02*
Y381132D01*
G01Y378770D02*
Y377982D01*
G01Y385069D02*
Y384281D01*
G01Y391368D02*
Y390581D01*
G01Y388218D02*
Y387431D01*
G01Y394518D02*
Y393730D01*
G01Y400817D02*
Y400029D01*
G01Y397667D02*
Y396880D01*
G01Y403966D02*
Y403179D01*
G01Y410266D02*
Y409478D01*
G01Y407116D02*
Y406329D01*
G01X1532732Y406919D02*
Y387628D01*
G01X1532458Y390581D02*
Y388218D01*
G01Y393730D02*
Y391368D01*
G01Y400029D02*
Y397667D01*
G01Y396880D02*
Y394518D01*
G01Y403179D02*
Y400817D01*
G01Y406329D02*
Y403966D01*
G01X1532417Y344124D02*
Y343337D01*
G01Y340974D02*
Y340187D01*
G01Y347274D02*
Y346486D01*
G01Y353573D02*
Y352785D01*
G01Y350423D02*
Y349636D01*
G01Y356722D02*
Y355935D01*
G01Y363022D02*
Y362234D01*
G01Y359872D02*
Y359085D01*
G01Y366171D02*
Y365384D01*
G01Y372470D02*
Y371683D01*
G01Y369321D02*
Y368533D01*
G01Y375620D02*
Y374833D01*
G01Y381919D02*
Y381132D01*
G01Y378770D02*
Y377982D01*
G01Y385069D02*
Y384281D01*
G01Y391368D02*
Y390581D01*
G01Y388218D02*
Y387431D01*
G01Y394518D02*
Y393730D01*
G01Y400817D02*
Y400029D01*
G01Y397667D02*
Y396880D01*
G01Y403966D02*
Y403179D01*
G01Y410266D02*
Y409478D01*
G01Y407116D02*
Y406329D01*
G01X1532391Y344124D02*
Y343337D01*
G01Y340974D02*
Y340187D01*
G01Y347274D02*
Y346486D01*
G01Y353573D02*
Y352785D01*
G01Y350423D02*
Y349636D01*
G01Y356722D02*
Y355935D01*
G01Y363022D02*
Y362234D01*
G01Y359872D02*
Y359085D01*
G01Y366171D02*
Y365384D01*
G01Y372470D02*
Y371683D01*
G01Y369321D02*
Y368533D01*
G01Y375620D02*
Y374833D01*
G01Y381919D02*
Y381132D01*
G01Y378770D02*
Y377982D01*
G01Y385069D02*
Y384281D01*
G01Y391368D02*
Y390581D01*
G01Y388218D02*
Y387431D01*
G01Y394518D02*
Y393730D01*
G01Y400817D02*
Y400029D01*
G01Y397667D02*
Y396880D01*
G01Y403966D02*
Y403179D01*
G01Y410266D02*
Y409478D01*
G01Y407116D02*
Y406329D01*
G01X1532024Y371348D02*
Y368199D01*
G01X1531945Y406919D02*
Y387628D01*
G01X1531630D02*
Y406919D01*
G01X1526433Y409380D02*
Y424616D01*
G01Y387529D02*
Y407018D01*
G01Y366466D02*
Y349931D01*
G01Y385167D02*
Y368829D01*
G01X1534976Y411348D02*
X1533992D01*
G01X1534976Y411151D02*
X1533992D01*
G01X1534976Y410758D02*
X1533992D01*
G01X1531945Y410561D02*
X1539110D01*
G01X1542605Y410266D02*
X1549937D01*
G01X1542457D02*
X1530449D01*
G01X1542457Y409478D02*
X1530449D01*
G01X1549937D02*
X1542605D01*
G01X1531945Y408986D02*
X1539110D01*
G01X1534976Y408789D02*
X1533992D01*
G01X1534976Y408396D02*
X1533992D01*
G01X1534976Y408199D02*
X1533992D01*
G01X1542605Y407116D02*
X1549937D01*
G01X1542457D02*
X1530449D01*
G01X1531551Y407037D02*
X1530449D01*
G01Y406919D02*
X1537984D01*
G01X1535567Y406427D02*
X1533442D01*
G01X1542457Y406329D02*
X1530449D01*
G01X1549937D02*
X1542605D01*
G01X1533442Y406132D02*
X1532458D01*
G01X1533442Y405935D02*
X1532458D01*
G01X1531551Y405738D02*
X1537576D01*
G01X1531551Y404557D02*
X1537576D01*
G01X1533442Y404360D02*
X1532458D01*
G01X1533442Y404163D02*
X1532458D01*
G01X1542605Y403966D02*
X1549937D01*
G01X1542457D02*
X1530449D01*
G01X1542457Y403179D02*
X1530449D01*
G01X1549937D02*
X1542605D01*
G01X1539440Y403100D02*
X1537558D01*
G01X1533442Y402982D02*
X1532458D01*
G01X1533442Y402785D02*
X1532458D01*
G01X1531551Y402588D02*
X1537576D01*
G01X1531551Y401407D02*
X1537576D01*
G01X1533442Y401211D02*
X1532458D01*
G01X1533442Y401014D02*
X1532458D01*
G01X1539440Y400896D02*
X1537558D01*
G01X1542605Y400817D02*
X1549937D01*
G01X1542457D02*
X1530449D01*
G01X1542457Y400029D02*
X1530449D01*
G01X1549937D02*
X1542605D01*
G01X1533442Y399833D02*
X1532458D01*
G01X1533442Y399636D02*
X1532458D01*
G01X1531551Y399439D02*
X1537576D01*
G01X1531551Y398258D02*
X1537576D01*
G01X1533442Y398061D02*
X1532458D01*
G01X1533442Y397864D02*
X1532458D01*
G01X1542605Y397667D02*
X1549937D01*
G01X1542457D02*
X1530449D01*
G01X1542457Y396880D02*
X1530449D01*
G01X1549937D02*
X1542605D01*
G01X1533442Y396683D02*
X1532458D01*
G01X1533442Y396486D02*
X1532458D01*
G01X1531551Y396289D02*
X1537576D01*
G01X1531551Y395108D02*
X1537576D01*
G01X1533442Y394911D02*
X1532458D01*
G01X1533442Y394714D02*
X1532458D01*
G01X1542605Y394518D02*
X1549937D01*
G01X1542457D02*
X1530449D01*
G01X1542457Y393730D02*
X1530449D01*
G01X1549937D02*
X1542605D01*
G01X1539440Y393651D02*
X1537558D01*
G01X1533442Y393533D02*
X1532458D01*
G01X1533442Y393337D02*
X1532458D01*
G01X1531551Y393140D02*
X1537576D01*
G01X1531551Y391959D02*
X1537576D01*
G01X1533442Y391762D02*
X1532458D01*
G01X1533442Y391565D02*
X1532458D01*
G01X1539440Y391447D02*
X1537558D01*
G01X1542605Y391368D02*
X1549937D01*
G01X1542457D02*
X1530449D01*
G01X1542457Y390581D02*
X1530449D01*
G01X1549937D02*
X1542605D01*
G01X1533442Y390384D02*
X1532458D01*
G01X1533442Y390187D02*
X1532458D01*
G01X1531551Y389990D02*
X1537576D01*
G01X1531551Y388809D02*
X1537576D01*
G01X1533442Y388612D02*
X1532458D01*
G01X1533442Y388415D02*
X1532458D01*
G01X1542605Y388218D02*
X1549937D01*
G01X1542457D02*
X1530449D01*
G01X1533442Y388120D02*
X1535567D01*
G01X1530449Y387628D02*
X1537984D01*
G01X1531551Y387510D02*
X1530449D01*
G01X1542457Y387431D02*
X1530449D01*
G01X1549937D02*
X1542605D01*
G01X1534976Y386348D02*
X1533992D01*
G01X1534976Y386151D02*
X1533992D01*
G01X1534976Y385758D02*
X1533992D01*
G01X1531945Y385561D02*
X1539110D01*
G01X1542605Y385069D02*
X1549937D01*
G01X1542457D02*
X1530449D01*
G01X1542457Y384281D02*
X1530449D01*
G01X1549937D02*
X1542605D01*
G01X1531945Y383986D02*
X1539110D01*
G01X1534976Y383789D02*
X1533992D01*
G01X1534976Y383396D02*
X1533992D01*
G01X1534976Y383199D02*
X1533992D01*
G01X1542605Y381919D02*
X1549937D01*
G01X1542457D02*
X1530449D01*
G01X1534976Y381348D02*
X1533992D01*
G01X1534976Y381151D02*
X1533992D01*
G01X1542457Y381132D02*
X1530449D01*
G01X1549937D02*
X1542605D01*
G01X1534976Y380758D02*
X1533992D01*
G01X1531945Y380561D02*
X1539110D01*
G01X1531945Y378986D02*
X1539110D01*
G01X1534976Y378789D02*
X1533992D01*
G01X1542605Y378770D02*
X1549937D01*
G01X1542457D02*
X1530449D01*
G01X1534976Y378396D02*
X1533992D01*
G01X1534976Y378199D02*
X1533992D01*
G01X1542457Y377982D02*
X1530449D01*
G01X1549937D02*
X1542605D01*
G01X1534976Y376348D02*
X1533992D01*
G01X1534976Y376151D02*
X1533992D01*
G01X1534976Y375758D02*
X1533992D01*
G01X1542605Y375620D02*
X1549937D01*
G01X1542457D02*
X1530449D01*
G01X1531945Y375561D02*
X1539110D01*
G01X1542457Y374833D02*
X1530449D01*
G01X1549937D02*
X1542605D01*
G01X1531945Y373986D02*
X1539110D01*
G01X1534976Y373789D02*
X1533992D01*
G01X1534976Y373396D02*
X1533992D01*
G01X1534976Y373199D02*
X1533992D01*
G01X1542605Y372470D02*
X1549937D01*
G01X1542457D02*
X1530449D01*
G01Y371978D02*
X1531551D01*
G01X1542457Y371683D02*
X1530449D01*
G01X1549937D02*
X1542605D01*
G01X1533008Y371348D02*
X1532024D01*
G01X1533008Y371151D02*
X1532024D01*
G01X1533008Y370758D02*
X1532024D01*
G01X1531551Y370561D02*
X1537142D01*
G01X1542605Y369321D02*
X1549937D01*
G01X1542457D02*
X1530449D01*
G01X1531551Y368986D02*
X1537142D01*
G01X1533008Y368789D02*
X1532024D01*
G01X1542457Y368533D02*
X1530449D01*
G01X1549937D02*
X1542605D01*
G01X1533008Y368396D02*
X1532024D01*
G01X1533008Y368199D02*
X1532024D01*
G01X1531551Y367569D02*
X1530449D01*
G01X1534976Y366348D02*
X1533992D01*
G01X1542605Y366171D02*
X1549937D01*
G01X1542457D02*
X1530449D01*
G01X1534976Y366151D02*
X1533992D01*
G01X1534976Y365758D02*
X1533992D01*
G01X1531945Y365561D02*
X1539110D01*
G01X1542457Y365384D02*
X1530449D01*
G01X1549937D02*
X1542605D01*
G01X1531945Y363986D02*
X1539110D01*
G01X1534976Y363789D02*
X1533992D01*
G01X1534976Y363396D02*
X1533992D01*
G01X1534976Y363199D02*
X1533992D01*
G01X1542605Y363022D02*
X1549937D01*
G01X1542457D02*
X1530449D01*
G01X1542457Y362234D02*
X1530449D01*
G01X1549937D02*
X1542605D01*
G01X1534976Y361348D02*
X1533992D01*
G01X1534976Y361151D02*
X1533992D01*
G01X1534976Y360758D02*
X1533992D01*
G01X1531945Y360561D02*
X1539110D01*
G01X1542605Y359872D02*
X1549937D01*
G01X1542457D02*
X1530449D01*
G01X1542457Y359085D02*
X1530449D01*
G01X1549937D02*
X1542605D01*
G01X1531945Y358986D02*
X1539110D01*
G01X1534976Y358789D02*
X1533992D01*
G01X1534976Y358396D02*
X1533992D01*
G01X1534976Y358199D02*
X1533992D01*
G01X1542605Y356722D02*
X1549937D01*
G01X1542457D02*
X1530449D01*
G01X1534976Y356348D02*
X1533992D01*
G01X1534976Y356151D02*
X1533992D01*
G01X1542457Y355935D02*
X1530449D01*
G01X1549937D02*
X1542605D01*
G01X1534976Y355758D02*
X1533992D01*
G01X1531945Y355561D02*
X1539110D01*
G01X1531945Y353986D02*
X1539110D01*
G01X1534976Y353789D02*
X1533992D01*
G01X1542605Y353573D02*
X1549937D01*
G01X1542457D02*
X1530449D01*
G01X1534976Y353396D02*
X1533992D01*
G01X1534976Y353199D02*
X1533992D01*
G01X1542457Y352785D02*
X1530449D01*
G01X1549937D02*
X1542605D01*
G01X1534976Y351348D02*
X1533992D01*
G01X1534976Y351151D02*
X1533992D01*
G01X1534976Y350758D02*
X1533992D01*
G01X1531945Y350561D02*
X1539110D01*
G01X1542605Y350423D02*
X1549937D01*
G01X1542457D02*
X1530449D01*
G01X1542457Y349636D02*
X1530449D01*
G01X1549937D02*
X1542605D01*
G01X1531945Y348986D02*
X1539110D01*
G01X1534976Y348789D02*
X1533992D01*
G01X1534976Y348396D02*
X1533992D01*
G01X1534976Y348199D02*
X1533992D01*
G01X1542605Y347274D02*
X1549937D01*
G01X1542457D02*
X1530449D01*
G01X1542457Y346486D02*
X1530449D01*
G01X1549937D02*
X1542605D01*
G01X1534976Y346348D02*
X1533992D01*
G01X1534976Y346151D02*
X1533992D01*
G01X1534976Y345758D02*
X1533992D01*
G01X1531945Y345561D02*
X1539110D01*
G01X1542605Y344124D02*
X1549937D01*
G01X1542457D02*
X1530449D01*
G01X1531945Y343986D02*
X1539110D01*
G01X1534976Y343789D02*
X1533992D01*
G01X1534976Y343396D02*
X1533992D01*
G01X1542457Y343337D02*
X1530449D01*
G01X1549937D02*
X1542605D01*
G01X1534976Y343199D02*
X1533992D01*
G01X1534976Y341348D02*
X1533992D01*
G01X1534976Y341151D02*
X1533992D01*
G01X1542605Y340974D02*
X1549937D01*
G01X1542457D02*
X1530449D01*
G01X1534976Y340758D02*
X1533992D01*
G01X1531945Y340561D02*
X1539110D01*
G01X1542457Y340187D02*
X1530449D01*
G01X1549937D02*
X1542605D01*
G01X1533205Y483848D02*
G03Y482667I0J-590D01*
G01X1526905D02*
G03Y483848I0J591D01*
G01X1534779Y479616D02*
Y481585D01*
G01Y484144D02*
Y482175D01*
G01X1533205Y481092D02*
Y482667D01*
G01Y483848D02*
Y484439D01*
G01X1532220Y479321D02*
Y484439D01*
G01X1532024D02*
Y479321D01*
G01X1531630Y482175D02*
Y484144D01*
G01Y481585D02*
Y479616D01*
G01X1528480Y482175D02*
Y484144D01*
G01Y481585D02*
Y479616D01*
G01X1528087Y484439D02*
Y479321D01*
G01X1527890D02*
Y484439D01*
G01X1526905Y482667D02*
Y481092D01*
G01Y484439D02*
Y483848D01*
G01X1525331Y479616D02*
Y481585D01*
G01Y484144D02*
Y482175D01*
G01X1524149Y475692D02*
Y538054D01*
G01X1525331Y482175D02*
X1528480D01*
G01X1534779D02*
X1531630D01*
G01X1525331Y481585D02*
X1528480D01*
G01X1534779D02*
X1531630D01*
G01X1508572Y412628D02*
X1508610Y412654D01*
X1508638Y412726D01*
X1508648Y412825D01*
G01X1508572Y422077D02*
X1508610Y422103D01*
X1508638Y422175D01*
X1508648Y422274D01*
G01X1508572Y425226D02*
X1508610Y425253D01*
X1508638Y425325D01*
X1508648Y425423D01*
G01X1508572Y428376D02*
X1508610Y428402D01*
X1508638Y428474D01*
X1508648Y428573D01*
G01X1508572Y437825D02*
X1508610Y437851D01*
X1508638Y437923D01*
X1508648Y438022D01*
G01X1501709Y448514D02*
X1499740Y446545D01*
G01X1509749Y413986D02*
X1510176Y414577D01*
G01X1509749Y418986D02*
X1510176Y419577D01*
G01X1509749Y423986D02*
X1510176Y424577D01*
G01X1509749Y428986D02*
X1510176Y429577D01*
G01X1509749Y433986D02*
X1510176Y434577D01*
G01X1509749Y438986D02*
X1510176Y439577D01*
G01X1504004Y415561D02*
X1503865Y415365D01*
X1503727Y415168D01*
X1503590Y414970D01*
G01X1504004Y420561D02*
X1503865Y420365D01*
X1503727Y420168D01*
X1503590Y419970D01*
G01X1504004Y425561D02*
X1503865Y425365D01*
X1503727Y425168D01*
X1503590Y424970D01*
G01X1504004Y430561D02*
X1503865Y430365D01*
X1503727Y430168D01*
X1503590Y429970D01*
G01X1504004Y435561D02*
X1503865Y435365D01*
X1503727Y435168D01*
X1503590Y434970D01*
G01X1504004Y440561D02*
X1503865Y440365D01*
X1503727Y440168D01*
X1503590Y439970D01*
G01X1509332Y414577D02*
X1509060Y413986D01*
G01X1509332Y419577D02*
X1509060Y418986D01*
G01X1509332Y424577D02*
X1509060Y423986D01*
G01X1509332Y429577D02*
X1509060Y428986D01*
G01X1509332Y434577D02*
X1509060Y433986D01*
G01X1509332Y439577D02*
X1509060Y438986D01*
G01X1497740Y456829D02*
X1497683Y456694D01*
X1497677Y456459D01*
X1497714Y456130D01*
G01X1497740Y456829D02*
X1497682Y456689D01*
X1497677Y456449D01*
G01X1508208Y414577D02*
X1508130Y413986D01*
G01X1508208Y419577D02*
X1508130Y418986D01*
G01X1508208Y424577D02*
X1508130Y423986D01*
G01X1508208Y429577D02*
X1508130Y428986D01*
G01X1508208Y434577D02*
X1508130Y433986D01*
G01X1508208Y439577D02*
X1508130Y438986D01*
G01X1508648Y415974D02*
X1508638Y415876D01*
X1508610Y415804D01*
X1508572Y415777D01*
G01X1508648Y419124D02*
X1508638Y419026D01*
X1508610Y418953D01*
X1508572Y418927D01*
G01X1508648Y431722D02*
X1508638Y431624D01*
X1508610Y431552D01*
X1508572Y431525D01*
G01X1508648Y434872D02*
X1508638Y434774D01*
X1508610Y434702D01*
X1508572Y434675D01*
G01X1510338Y438022D02*
Y438415D01*
G01Y434872D02*
Y435266D01*
G01Y431722D02*
Y432116D01*
G01Y425423D02*
Y425817D01*
G01Y428573D02*
Y428966D01*
G01Y422274D02*
Y422667D01*
G01Y415974D02*
Y416368D01*
G01Y419124D02*
Y419518D01*
G01Y412825D02*
Y413218D01*
G01X1510176Y414970D02*
Y414577D01*
G01Y419970D02*
Y419577D01*
G01Y424970D02*
Y424577D01*
G01Y429970D02*
Y429577D01*
G01Y434970D02*
Y434577D01*
G01Y439970D02*
Y439577D01*
G01X1509332Y414970D02*
Y414577D01*
G01Y419970D02*
Y419577D01*
G01Y424970D02*
Y424577D01*
G01Y429970D02*
Y429577D01*
G01Y434970D02*
Y434577D01*
G01Y439970D02*
Y439577D01*
G01X1509161Y438022D02*
Y438415D01*
G01Y434872D02*
Y435266D01*
G01Y431722D02*
Y432116D01*
G01Y425423D02*
Y425817D01*
G01Y428573D02*
Y428966D01*
G01Y422274D02*
Y422667D01*
G01Y415974D02*
Y416368D01*
G01Y419124D02*
Y419518D01*
G01Y412825D02*
Y413218D01*
G01X1508648D02*
Y412825D01*
G01Y416368D02*
Y415974D01*
G01Y419518D02*
Y419124D01*
G01Y422667D02*
Y422274D01*
G01Y425817D02*
Y425423D01*
G01Y428966D02*
Y428573D01*
G01Y432116D02*
Y431722D01*
G01Y438415D02*
Y438022D01*
G01Y435266D02*
Y434872D01*
G01X1508208Y439577D02*
Y439970D01*
G01Y434577D02*
Y434970D01*
G01Y429577D02*
Y429970D01*
G01Y424577D02*
Y424970D01*
G01Y419577D02*
Y419970D01*
G01Y414577D02*
Y414970D01*
G01X1503727Y413218D02*
Y412825D01*
G01Y416368D02*
Y415974D01*
G01Y419518D02*
Y419124D01*
G01Y422667D02*
Y422274D01*
G01Y425817D02*
Y425423D01*
G01Y428966D02*
Y428573D01*
G01Y432116D02*
Y431722D01*
G01Y438415D02*
Y438022D01*
G01Y435266D02*
Y434872D01*
G01X1503590Y439577D02*
Y439970D01*
G01Y434577D02*
Y434970D01*
G01Y429577D02*
Y429970D01*
G01Y424577D02*
Y424970D01*
G01Y419577D02*
Y419970D01*
G01Y414577D02*
Y414970D01*
G01X1500921Y413376D02*
Y444380D01*
G01X1497772Y455679D02*
Y448514D01*
G01X1509161Y438415D02*
X1509158Y438453D01*
X1509151Y438490D01*
X1509138Y438524D01*
X1509121Y438554D01*
X1509100Y438579D01*
X1509076Y438597D01*
X1509050Y438608D01*
X1509023Y438612D01*
G01X1509161Y435266D02*
X1509158Y435304D01*
X1509151Y435341D01*
X1509138Y435375D01*
X1509121Y435405D01*
X1509100Y435429D01*
X1509076Y435447D01*
X1509050Y435459D01*
X1509023Y435463D01*
G01X1509161Y432116D02*
X1509158Y432154D01*
X1509151Y432191D01*
X1509138Y432225D01*
X1509121Y432255D01*
X1509100Y432280D01*
X1509076Y432298D01*
X1509050Y432309D01*
X1509023Y432313D01*
G01X1509161Y428966D02*
X1509158Y429005D01*
X1509151Y429041D01*
X1509138Y429075D01*
X1509121Y429106D01*
X1509100Y429130D01*
X1509076Y429148D01*
X1509050Y429159D01*
X1509023Y429163D01*
G01X1509161Y425817D02*
X1509158Y425855D01*
X1509151Y425892D01*
X1509138Y425926D01*
X1509121Y425956D01*
X1509100Y425980D01*
X1509076Y425999D01*
X1509050Y426010D01*
X1509023Y426014D01*
G01X1509161Y422667D02*
X1509158Y422705D01*
X1509151Y422742D01*
X1509138Y422776D01*
X1509121Y422806D01*
X1509100Y422831D01*
X1509076Y422849D01*
X1509050Y422860D01*
X1509023Y422864D01*
G01X1509161Y419518D02*
X1509158Y419556D01*
X1509151Y419593D01*
X1509138Y419627D01*
X1509121Y419657D01*
X1509100Y419681D01*
X1509076Y419699D01*
X1509050Y419711D01*
X1509023Y419714D01*
G01X1509161Y416368D02*
X1509158Y416406D01*
X1509151Y416443D01*
X1509138Y416477D01*
X1509121Y416507D01*
X1509100Y416532D01*
X1509076Y416550D01*
X1509050Y416561D01*
X1509023Y416565D01*
G01X1509161Y413218D02*
X1509158Y413257D01*
X1509151Y413293D01*
X1509138Y413327D01*
X1509121Y413358D01*
X1509100Y413382D01*
X1509076Y413400D01*
X1509050Y413411D01*
X1509023Y413415D01*
G01X1508208Y439970D02*
X1508130Y440561D01*
G01X1508208Y434970D02*
X1508130Y435561D01*
G01X1508208Y429970D02*
X1508130Y430561D01*
G01X1508208Y424970D02*
X1508130Y425561D01*
G01X1508208Y419970D02*
X1508130Y420561D01*
G01X1508208Y414970D02*
X1508130Y415561D01*
G01X1497712Y456138D02*
X1497767Y455753D01*
G01X1503727Y438022D02*
X1503758Y437925D01*
X1503847Y437852D01*
X1503974Y437825D01*
G01X1503727Y434872D02*
X1503758Y434775D01*
X1503847Y434703D01*
X1503974Y434675D01*
G01X1503727Y431722D02*
X1503758Y431625D01*
X1503847Y431553D01*
X1503974Y431525D01*
G01X1503727Y428573D02*
X1503758Y428476D01*
X1503847Y428404D01*
X1503974Y428376D01*
G01X1503727Y425423D02*
X1503758Y425326D01*
X1503847Y425254D01*
X1503974Y425226D01*
G01X1503727Y422274D02*
X1503758Y422177D01*
X1503847Y422104D01*
X1503974Y422077D01*
G01X1503727Y419124D02*
X1503758Y419027D01*
X1503847Y418955D01*
X1503974Y418927D01*
G01X1503727Y415974D02*
X1503758Y415877D01*
X1503847Y415805D01*
X1503974Y415777D01*
G01X1503727Y412825D02*
X1503758Y412728D01*
X1503847Y412656D01*
X1503974Y412628D01*
G01X1509023Y437825D02*
X1509050Y437828D01*
X1509075Y437840D01*
X1509099Y437858D01*
X1509121Y437882D01*
X1509138Y437912D01*
X1509150Y437946D01*
X1509158Y437983D01*
X1509161Y438022D01*
G01X1509023Y434675D02*
X1509050Y434679D01*
X1509075Y434690D01*
X1509099Y434708D01*
X1509121Y434733D01*
X1509138Y434762D01*
X1509150Y434796D01*
X1509158Y434833D01*
X1509161Y434872D01*
G01X1503974Y438612D02*
X1503846Y438584D01*
X1503758Y438511D01*
X1503727Y438415D01*
G01X1503974Y435463D02*
X1503846Y435435D01*
X1503758Y435362D01*
X1503727Y435266D01*
G01X1503974Y432313D02*
X1503846Y432285D01*
X1503758Y432212D01*
X1503727Y432116D01*
G01X1503974Y429163D02*
X1503846Y429136D01*
X1503758Y429063D01*
X1503727Y428966D01*
G01X1503974Y426014D02*
X1503846Y425986D01*
X1503758Y425913D01*
X1503727Y425817D01*
G01X1503974Y422864D02*
X1503846Y422836D01*
X1503758Y422763D01*
X1503727Y422667D01*
G01X1503974Y419714D02*
X1503846Y419687D01*
X1503758Y419614D01*
X1503727Y419518D01*
G01X1503974Y416565D02*
X1503846Y416537D01*
X1503758Y416464D01*
X1503727Y416368D01*
G01X1503974Y413415D02*
X1503846Y413388D01*
X1503758Y413315D01*
X1503727Y413218D01*
G01X1509060Y440561D02*
X1509332Y439970D01*
G01X1509060Y435561D02*
X1509332Y434970D01*
G01X1509060Y430561D02*
X1509332Y429970D01*
G01X1509060Y425561D02*
X1509332Y424970D01*
G01X1509060Y420561D02*
X1509332Y419970D01*
G01X1509060Y415561D02*
X1509332Y414970D01*
G01X1497772Y456860D02*
X1551709D01*
G01X1524149Y455679D02*
X1497772D01*
G01X1501709Y448514D02*
X1551709D01*
G01X1499740D02*
X1496457D01*
G01X1530449Y443986D02*
X1499740D01*
G01X1520212Y443592D02*
X1501709D01*
G01X1509749Y440561D02*
X1504004D01*
G01X1510176Y439970D02*
X1503590D01*
G01Y439577D02*
X1510176D01*
G01X1504004Y438986D02*
X1509749D01*
G01X1503974Y438612D02*
X1510058D01*
G01X1503727Y438415D02*
X1510338D01*
G01Y438022D02*
X1503727D01*
G01X1503974Y437825D02*
X1510058D01*
G01X1509749Y435561D02*
X1504004D01*
G01X1503974Y435463D02*
X1510058D01*
G01X1503727Y435266D02*
X1510338D01*
G01X1510176Y434970D02*
X1503590D01*
G01X1510338Y434872D02*
X1503727D01*
G01X1503974Y434675D02*
X1510058D01*
G01X1503590Y434577D02*
X1510176D01*
G01X1504004Y433986D02*
X1509749D01*
G01X1503974Y432313D02*
X1510058D01*
G01X1503727Y432116D02*
X1510338D01*
G01Y431722D02*
X1503727D01*
G01X1503974Y431525D02*
X1510058D01*
G01X1509749Y430561D02*
X1504004D01*
G01X1510176Y429970D02*
X1503590D01*
G01Y429577D02*
X1510176D01*
G01X1503974Y429163D02*
X1510058D01*
G01X1504004Y428986D02*
X1509749D01*
G01X1503727Y428966D02*
X1510338D01*
G01Y428573D02*
X1503727D01*
G01X1503974Y428376D02*
X1510058D01*
G01X1509023Y431525D02*
X1509050Y431529D01*
X1509075Y431540D01*
X1509099Y431558D01*
X1509121Y431583D01*
X1509138Y431613D01*
X1509150Y431647D01*
X1509158Y431683D01*
X1509161Y431722D01*
G01X1509023Y428376D02*
X1509050Y428380D01*
X1509075Y428391D01*
X1509099Y428409D01*
X1509121Y428434D01*
X1509138Y428463D01*
X1509150Y428497D01*
X1509158Y428534D01*
X1509161Y428573D01*
G01X1509023Y425226D02*
X1509050Y425230D01*
X1509075Y425241D01*
X1509099Y425259D01*
X1509121Y425284D01*
X1509138Y425314D01*
X1509150Y425347D01*
X1509158Y425384D01*
X1509161Y425423D01*
G01X1509023Y422077D02*
X1509050Y422080D01*
X1509075Y422092D01*
X1509099Y422110D01*
X1509121Y422134D01*
X1509138Y422164D01*
X1509150Y422198D01*
X1509158Y422235D01*
X1509161Y422274D01*
G01X1509023Y418927D02*
X1509050Y418931D01*
X1509075Y418942D01*
X1509099Y418960D01*
X1509121Y418985D01*
X1509138Y419014D01*
X1509150Y419048D01*
X1509158Y419085D01*
X1509161Y419124D01*
G01X1509023Y415777D02*
X1509050Y415781D01*
X1509075Y415792D01*
X1509099Y415810D01*
X1509121Y415835D01*
X1509138Y415865D01*
X1509150Y415899D01*
X1509158Y415935D01*
X1509161Y415974D01*
G01X1509023Y412628D02*
X1509050Y412632D01*
X1509075Y412643D01*
X1509099Y412661D01*
X1509121Y412686D01*
X1509138Y412715D01*
X1509150Y412749D01*
X1509158Y412786D01*
X1509161Y412825D01*
G01X1503590Y439577D02*
X1503727Y439379D01*
X1503865Y439182D01*
X1504004Y438986D01*
G01X1503590Y434577D02*
X1503727Y434379D01*
X1503865Y434182D01*
X1504004Y433986D01*
G01X1503590Y429577D02*
X1503727Y429379D01*
X1503865Y429182D01*
X1504004Y428986D01*
G01X1503590Y424577D02*
X1503727Y424379D01*
X1503865Y424182D01*
X1504004Y423986D01*
G01X1503590Y419577D02*
X1503727Y419379D01*
X1503865Y419182D01*
X1504004Y418986D01*
G01X1503590Y414577D02*
X1503727Y414379D01*
X1503865Y414182D01*
X1504004Y413986D01*
G01X1509749Y440561D02*
X1510176Y439970D01*
G01X1509749Y435561D02*
X1510176Y434970D01*
G01X1509749Y430561D02*
X1510176Y429970D01*
G01X1509749Y425561D02*
X1510176Y424970D01*
G01X1509749Y420561D02*
X1510176Y419970D01*
G01X1509749Y415561D02*
X1510176Y414970D01*
G01X1499740Y445561D02*
X1501709Y443592D01*
G01Y426978D02*
X1528401D01*
G01X1503974Y426014D02*
X1510058D01*
G01X1503727Y425817D02*
X1510338D01*
G01X1509749Y425561D02*
X1504004D01*
G01X1510338Y425423D02*
X1503727D01*
G01X1503974Y425226D02*
X1510058D01*
G01X1510176Y424970D02*
X1503590D01*
G01X1528401Y424616D02*
X1501709D01*
G01X1503590Y424577D02*
X1510176D01*
G01X1504004Y423986D02*
X1509749D01*
G01X1503974Y422864D02*
X1510058D01*
G01X1503727Y422667D02*
X1510338D01*
G01Y422274D02*
X1503727D01*
G01X1503974Y422077D02*
X1510058D01*
G01X1509749Y420561D02*
X1504004D01*
G01X1510176Y419970D02*
X1503590D01*
G01X1503974Y419714D02*
X1510058D01*
G01X1503590Y419577D02*
X1510176D01*
G01X1503727Y419518D02*
X1510338D01*
G01Y419124D02*
X1503727D01*
G01X1504004Y418986D02*
X1509749D01*
G01X1503974Y418927D02*
X1510058D01*
G01X1503974Y416565D02*
X1510058D01*
G01X1503727Y416368D02*
X1510338D01*
G01Y415974D02*
X1503727D01*
G01X1503974Y415777D02*
X1510058D01*
G01X1509749Y415561D02*
X1504004D01*
G01X1510176Y414970D02*
X1503590D01*
G01Y414577D02*
X1510176D01*
G01X1504004Y413986D02*
X1509749D01*
G01X1503974Y413415D02*
X1510058D01*
G01X1520212Y413376D02*
X1500751D01*
G01X1503727Y413218D02*
X1510338D01*
G01Y412825D02*
X1503727D01*
G01X1503974Y412628D02*
X1510058D01*
G01X1508572Y438612D02*
X1508610Y438586D01*
X1508638Y438514D01*
X1508648Y438415D01*
G01X1508572Y435463D02*
X1508610Y435436D01*
X1508638Y435364D01*
X1508648Y435266D01*
G01X1508572Y432313D02*
X1508610Y432286D01*
X1508638Y432214D01*
X1508648Y432116D01*
G01X1508572Y429163D02*
X1508610Y429137D01*
X1508638Y429065D01*
X1508648Y428966D01*
G01X1508572Y426014D02*
X1508610Y425987D01*
X1508638Y425915D01*
X1508648Y425817D01*
G01X1508572Y422864D02*
X1508610Y422838D01*
X1508638Y422766D01*
X1508648Y422667D01*
G01X1508572Y419714D02*
X1508610Y419688D01*
X1508638Y419616D01*
X1508648Y419518D01*
G01X1508572Y416565D02*
X1508610Y416538D01*
X1508638Y416466D01*
X1508648Y416368D01*
G01X1508572Y413415D02*
X1508610Y413389D01*
X1508638Y413317D01*
X1508648Y413218D01*
G01X1541472Y452077D02*
G03I-2165J0D01*
G01X1542653D02*
G03I-3346J0D01*
G01X1542811D02*
G03I-3504J0D01*
G01X1543835D02*
G03I-4528J0D01*
G01X1547119Y450472D02*
G03X1549334Y455640I-6937J6032D01*
G01X1546234Y450398D02*
G03X1548448Y455640I-7143J6105D01*
G01X1531945Y438986D02*
G03X1531551Y438592I0J-394D01*
G01Y440955D02*
G03X1531945Y440561I394J0D01*
G01Y433986D02*
G03X1531551Y433592I0J-394D01*
G01Y435955D02*
G03X1531945Y435561I394J0D01*
G01X1533205Y481092D02*
G03Y479911I0J-591D01*
G01X1532220Y462313D02*
G03Y465463I0J1575D01*
G01X1533143Y453918D02*
G03X1533685Y454901I-1276J1344D01*
G01X1531945Y413986D02*
G03X1531551Y413592I0J-394D01*
G01Y415955D02*
G03X1531945Y415561I394J0D01*
G01Y418986D02*
G03X1531551Y418592I0J-394D01*
G01Y420955D02*
G03X1531945Y420561I394J0D01*
G01Y428986D02*
G03X1531551Y428592I0J-394D01*
G01Y430955D02*
G03X1531945Y430561I394J0D01*
G01Y423986D02*
G03X1531551Y423592I0J-394D01*
G01Y425955D02*
G03X1531945Y425561I394J0D01*
G01X1526905Y479911D02*
G03Y481092I0J591D01*
G01X1527890Y465463D02*
G03Y462313I0J-1575D01*
G01X1533648Y453373D02*
G03X1534718Y455197I-2810J2874D01*
G01X1526672Y450472D02*
G03X1528886Y455640I-6938J6031D01*
G01X1525786Y450398D02*
G03X1528001Y455640I-7142J6107D01*
G01X1528526Y439373D02*
X1528787Y439459D01*
G01X1528003Y441421D02*
X1528265Y441506D01*
G01X1526261Y441676D02*
X1526522Y441762D01*
G01X1528700Y439970D02*
X1528526Y439885D01*
G01X1526784Y439117D02*
X1527132Y439288D01*
G01X1526174Y442188D02*
X1525738Y441932D01*
G01X1533354Y450713D02*
X1533067Y450535D01*
X1532713Y450472D01*
G01X1543408Y450537D02*
X1543691Y450715D01*
X1543878Y450980D01*
X1543945Y451282D01*
X1543881Y451582D01*
X1543695Y451849D01*
X1543410Y452031D01*
X1543059Y452096D01*
G01X1542711Y452031D02*
X1542428Y451854D01*
X1542241Y451588D01*
X1542174Y451287D01*
X1542238Y450986D01*
X1542424Y450719D01*
X1542709Y450538D01*
X1543059Y450472D01*
G01X1538241Y450537D02*
X1538524Y450715D01*
X1538711Y450980D01*
X1538778Y451282D01*
X1538713Y451582D01*
X1538528Y451849D01*
X1538243Y452031D01*
X1537892Y452096D01*
G01X1537543Y452031D02*
X1537261Y451854D01*
X1537073Y451588D01*
X1537006Y451287D01*
X1537071Y450986D01*
X1537256Y450719D01*
X1537542Y450538D01*
X1537892Y450472D01*
G01X1526958Y439800D02*
X1526696Y439629D01*
G01X1543482Y452839D02*
X1543843Y453075D01*
X1544081Y453425D01*
X1544167Y453828D01*
X1544084Y454231D01*
X1543848Y454583D01*
X1543484Y454823D01*
X1543059Y454908D01*
G01X1542636Y454824D02*
X1542276Y454588D01*
X1542038Y454237D01*
X1541952Y453834D01*
X1542035Y453432D01*
X1542271Y453079D01*
X1542635Y452839D01*
X1543059Y452755D01*
G01X1538315Y452839D02*
X1538675Y453075D01*
X1538914Y453425D01*
X1538999Y453828D01*
X1538917Y454231D01*
X1538680Y454583D01*
X1538317Y454823D01*
X1537892Y454908D01*
G01X1537469Y454824D02*
X1537109Y454588D01*
X1536870Y454237D01*
X1536785Y453834D01*
X1536867Y453432D01*
X1537104Y453079D01*
X1537467Y452839D01*
X1537892Y452755D01*
G01X1528787Y439459D02*
X1529136Y439714D01*
G01X1533143Y453918D02*
X1531514Y452371D01*
G01X1544257Y452383D02*
X1544709Y452823D01*
X1544979Y453359D01*
X1545049Y453929D01*
X1544908Y454494D01*
X1544561Y455018D01*
X1544034Y455412D01*
X1543391Y455615D01*
X1542712Y455612D01*
X1542072Y455405D01*
X1541549Y455008D01*
X1541207Y454485D01*
X1541069Y453923D01*
X1541141Y453356D01*
X1541411Y452822D01*
G01X1539090Y452383D02*
X1539542Y452823D01*
X1539812Y453359D01*
X1539882Y453929D01*
X1539740Y454494D01*
X1539394Y455018D01*
X1538866Y455412D01*
X1538224Y455615D01*
X1537544Y455612D01*
X1536904Y455405D01*
X1536381Y455008D01*
X1536040Y454485D01*
X1535902Y453923D01*
X1535974Y453356D01*
X1536244Y452822D01*
G01X1533648Y453374D02*
X1532086Y451846D01*
G01X1528874Y440141D02*
X1528700Y439970D01*
G01X1527132Y439288D02*
X1527480Y439629D01*
G01X1527829Y441932D02*
X1527480Y441591D01*
G01X1525999Y441421D02*
X1526261Y441676D01*
G01X1526916Y480713D02*
X1526823Y480602D01*
G01Y480729D02*
X1526916Y480840D01*
G01X1541862Y452383D02*
X1541539Y451964D01*
X1541376Y451480D01*
X1541398Y450976D01*
X1541601Y450499D01*
X1541968Y450095D01*
X1542474Y449828D01*
X1543065Y449734D01*
X1543654Y449831D01*
X1544157Y450100D01*
X1544521Y450504D01*
X1544722Y450982D01*
X1544741Y451487D01*
X1544578Y451968D01*
X1544257Y452383D01*
G01X1536694D02*
X1536372Y451964D01*
X1536209Y451480D01*
X1536231Y450976D01*
X1536434Y450499D01*
X1536801Y450095D01*
X1537307Y449828D01*
X1537898Y449734D01*
X1538487Y449831D01*
X1538989Y450100D01*
X1539354Y450504D01*
X1539555Y450982D01*
X1539574Y451487D01*
X1539410Y451968D01*
X1539090Y452383D01*
G01X1529136Y439714D02*
X1529397Y440056D01*
G01X1531514Y452371D02*
X1531177Y451910D01*
X1531031Y451391D01*
X1531092Y450873D01*
X1531343Y450389D01*
X1531779Y449995D01*
X1532352Y449771D01*
X1532987Y449753D01*
X1533571Y449939D01*
X1534026Y450292D01*
X1534319Y450763D01*
X1534423Y451284D01*
G01X1533354Y450713D02*
X1533544Y450980D01*
G01X1532086Y451846D02*
X1531903Y451581D01*
X1531839Y451283D01*
X1531904Y450986D01*
G01X1527132Y440056D02*
X1526958Y439800D01*
G01X1527829Y441165D02*
X1528003Y441421D01*
G01X1525738Y441932D02*
X1525477Y441506D01*
G01X1527480Y439629D02*
X1527655Y439970D01*
G01X1527480Y441591D02*
X1527306Y441250D01*
G01X1528961Y440397D02*
X1528874Y440141D01*
G01X1527742Y440909D02*
X1527829Y441165D01*
G01X1527219Y440397D02*
X1527132Y440056D01*
G01X1527306Y441250D02*
X1527219Y440909D01*
G01X1525912Y441079D02*
X1525999Y441421D01*
G01X1533543Y450980D02*
X1533611Y451284D01*
G01X1529397Y440056D02*
X1529484Y440482D01*
G01X1527655Y439970D02*
X1527742Y440397D01*
G01X1525477Y441506D02*
X1525390Y441079D01*
G01X1534423Y451284D02*
X1534336Y450807D01*
X1534088Y450365D01*
X1533700Y450013D01*
X1533193Y449794D01*
X1532616Y449737D01*
X1532052Y449859D01*
X1531576Y450142D01*
X1531237Y450546D01*
X1531057Y451003D01*
X1531042Y451484D01*
X1531199Y451954D01*
X1531514Y452371D01*
G01X1551709Y443179D02*
Y456860D01*
G01X1551391Y443179D02*
Y448514D01*
G01X1550916Y443179D02*
Y445758D01*
G01X1550072Y449734D02*
Y450472D01*
G01X1549937Y413415D02*
Y412628D01*
G01Y419714D02*
Y418927D01*
G01Y416565D02*
Y415777D01*
G01Y422864D02*
Y422077D01*
G01Y429163D02*
Y428376D01*
G01Y426014D02*
Y425226D01*
G01Y432313D02*
Y431525D01*
G01Y438612D02*
Y437825D01*
G01Y435463D02*
Y434675D01*
G01X1548163Y413415D02*
Y412628D01*
G01Y419714D02*
Y418927D01*
G01Y416565D02*
Y415777D01*
G01Y422864D02*
Y422077D01*
G01Y429163D02*
Y428376D01*
G01Y426014D02*
Y425226D01*
G01Y432313D02*
Y431525D01*
G01Y438612D02*
Y437825D01*
G01Y435463D02*
Y434675D01*
G01X1547975Y437825D02*
Y438612D01*
G01Y434675D02*
Y435463D01*
G01Y431525D02*
Y432313D01*
G01Y428376D02*
Y429163D01*
G01Y425226D02*
Y426014D01*
G01Y422077D02*
Y422864D01*
G01Y418927D02*
Y419714D01*
G01Y415777D02*
Y416565D01*
G01Y412628D02*
Y413415D01*
G01X1546234Y450399D02*
Y449734D01*
G01X1545138Y437825D02*
Y438612D01*
G01Y434675D02*
Y435463D01*
G01Y431525D02*
Y432313D01*
G01Y428376D02*
Y429163D01*
G01Y425226D02*
Y426014D01*
G01Y422077D02*
Y422864D01*
G01Y418927D02*
Y419714D01*
G01Y415777D02*
Y416565D01*
G01Y412628D02*
Y413415D01*
G01X1545062Y448514D02*
Y445758D01*
G01X1544197Y413415D02*
Y412628D01*
G01Y419714D02*
Y418927D01*
G01Y416565D02*
Y415777D01*
G01Y422864D02*
Y422077D01*
G01Y429163D02*
Y428376D01*
G01Y426014D02*
Y425226D01*
G01Y432313D02*
Y431525D01*
G01Y438612D02*
Y437825D01*
G01Y435463D02*
Y434675D01*
G01X1542605Y413415D02*
Y412628D01*
G01Y419714D02*
Y418927D01*
G01Y416565D02*
Y415777D01*
G01Y422864D02*
Y422077D01*
G01Y429163D02*
Y428376D01*
G01Y426014D02*
Y425226D01*
G01Y432313D02*
Y431525D01*
G01Y438612D02*
Y437825D01*
G01Y435463D02*
Y434675D01*
G01X1542457Y413415D02*
Y412628D01*
G01Y419714D02*
Y418927D01*
G01Y416565D02*
Y415777D01*
G01Y422864D02*
Y422077D01*
G01Y429163D02*
Y428376D01*
G01Y426014D02*
Y425226D01*
G01Y432313D02*
Y431525D01*
G01Y438612D02*
Y437825D01*
G01Y435463D02*
Y434675D01*
G01X1541519Y438612D02*
Y441191D01*
G01Y435463D02*
Y437825D01*
G01Y432313D02*
Y434675D01*
G01Y429163D02*
Y431525D01*
G01Y426014D02*
Y428376D01*
G01Y422864D02*
Y425226D01*
G01Y419714D02*
Y422077D01*
G01Y416565D02*
Y418927D01*
G01Y413415D02*
Y415777D01*
G01X1540075Y438770D02*
Y440738D01*
G01X1539791Y413415D02*
Y412628D01*
G01Y419714D02*
Y418927D01*
G01Y416565D02*
Y415777D01*
G01Y422864D02*
Y422077D01*
G01Y429163D02*
Y428376D01*
G01Y426014D02*
Y425226D01*
G01Y432313D02*
Y431525D01*
G01Y438612D02*
Y437825D01*
G01Y435463D02*
Y434675D01*
G01X1539110Y438986D02*
Y440561D01*
G01Y433986D02*
Y435561D01*
G01Y428986D02*
Y430561D01*
G01Y423986D02*
Y425561D01*
G01Y418986D02*
Y420561D01*
G01Y413986D02*
Y415561D01*
G01X1538244Y469793D02*
Y456860D01*
G01X1538139Y437825D02*
Y438612D01*
G01Y434675D02*
Y435463D01*
G01Y431525D02*
Y432313D01*
G01Y428376D02*
Y429163D01*
G01Y425226D02*
Y426014D01*
G01Y422077D02*
Y422864D01*
G01Y418927D02*
Y419714D01*
G01Y415777D02*
Y416565D01*
G01Y412628D02*
Y413415D01*
G01X1537188Y448514D02*
Y445758D01*
G01X1536549Y446151D02*
Y446211D01*
G01X1536156Y437825D02*
Y438612D01*
G01Y434675D02*
Y435463D01*
G01Y431525D02*
Y432313D01*
G01Y428376D02*
Y429163D01*
G01Y425226D02*
Y426014D01*
G01Y422077D02*
Y422864D01*
G01Y418927D02*
Y419714D01*
G01Y415777D02*
Y416565D01*
G01Y412628D02*
Y413415D01*
G01X1535961Y415561D02*
Y413986D01*
G01Y420561D02*
Y418986D01*
G01Y425561D02*
Y423986D01*
G01Y430561D02*
Y428986D01*
G01Y435561D02*
Y433986D01*
G01Y440561D02*
Y438986D01*
G01X1534976Y416348D02*
Y413199D01*
G01Y421348D02*
Y418199D01*
G01Y426348D02*
Y423199D01*
G01Y431348D02*
Y428199D01*
G01Y436348D02*
Y433199D01*
G01Y441348D02*
Y438199D01*
G01X1534718Y455197D02*
Y455640D01*
G01X1534423Y451284D02*
Y451432D01*
G01X1533992Y446211D02*
Y448514D01*
G01Y416348D02*
Y413199D01*
G01Y421348D02*
Y418199D01*
G01Y426348D02*
Y423199D01*
G01Y431348D02*
Y428199D01*
G01Y436348D02*
Y433199D01*
G01Y441348D02*
Y438199D01*
G01X1533611Y451432D02*
Y451284D01*
G01X1533205Y479321D02*
Y479911D01*
G01X1533008Y415561D02*
Y413986D01*
G01Y420561D02*
Y418986D01*
G01Y425561D02*
Y423986D01*
G01Y430561D02*
Y428986D01*
G01Y435561D02*
Y433986D01*
G01Y440561D02*
Y438986D01*
G01X1532846Y463100D02*
Y464675D01*
G01X1532811D02*
Y463100D01*
G01X1532793Y413415D02*
Y412628D01*
G01Y419714D02*
Y418927D01*
G01Y416565D02*
Y415777D01*
G01Y422864D02*
Y422077D01*
G01Y429163D02*
Y428376D01*
G01Y426014D02*
Y425226D01*
G01Y432313D02*
Y431525D01*
G01Y438612D02*
Y437825D01*
G01Y435463D02*
Y434675D01*
G01X1532787Y464675D02*
Y463100D01*
G01X1532417Y413415D02*
Y412628D01*
G01Y419714D02*
Y418927D01*
G01Y416565D02*
Y415777D01*
G01Y422864D02*
Y422077D01*
G01Y429163D02*
Y428376D01*
G01Y426014D02*
Y425226D01*
G01Y432313D02*
Y431525D01*
G01Y438612D02*
Y437825D01*
G01Y435463D02*
Y434675D01*
G01X1532391Y413415D02*
Y412628D01*
G01Y419714D02*
Y418927D01*
G01Y416565D02*
Y415777D01*
G01Y422864D02*
Y422077D01*
G01Y429163D02*
Y428376D01*
G01Y426014D02*
Y425226D01*
G01Y432313D02*
Y431525D01*
G01Y438612D02*
Y437825D01*
G01Y435463D02*
Y434675D01*
G01X1532004Y440738D02*
Y438770D01*
G01X1531464Y463100D02*
Y464675D01*
G01X1531094D02*
Y463100D01*
G01X1530806Y455640D02*
Y454901D01*
G01X1529624Y449734D02*
Y450472D01*
G01X1529484Y440482D02*
Y440909D01*
G01Y437923D02*
Y437411D01*
G01X1529016Y463100D02*
Y464675D01*
G01X1528961Y440909D02*
Y440397D01*
G01X1528646Y464675D02*
Y463100D01*
G01X1528526Y439885D02*
Y439373D01*
G01X1528087Y446703D02*
Y449144D01*
G01Y454892D02*
Y451112D01*
G01X1527742Y440397D02*
Y440909D01*
G01X1527324Y463100D02*
Y464675D01*
G01X1527299Y463100D02*
Y464675D01*
G01X1527264D02*
Y463100D01*
G01X1527219Y440909D02*
Y440397D01*
G01X1527010Y480840D02*
Y480092D01*
G01X1526916D02*
Y480713D01*
G01X1526905Y479911D02*
Y479321D01*
G01X1526823Y480602D02*
Y480729D01*
G01X1526522Y441762D02*
Y442274D01*
G01X1526433Y426978D02*
Y443396D01*
G01X1525912Y440397D02*
Y441079D01*
G01X1525786Y450399D02*
Y449734D01*
G01X1525390Y437411D02*
Y437923D01*
G01Y441079D02*
Y440397D01*
G01X1524149Y456860D02*
Y448514D01*
G01X1522181Y444577D02*
Y442805D01*
G01X1521866Y443396D02*
Y469793D01*
G01X1525390Y440397D02*
X1525477Y439970D01*
G01X1529484Y440909D02*
X1529397Y441250D01*
G01X1525999Y440056D02*
X1525912Y440397D01*
G01X1528874Y441165D02*
X1528961Y440909D01*
G01X1526522Y442274D02*
X1526174Y442188D01*
G01X1528177Y442018D02*
X1527829Y441932D01*
G01X1529397Y441250D02*
X1529223Y441591D01*
G01X1525477Y439970D02*
X1525651Y439629D01*
G01X1536804Y445758D02*
X1536549Y446151D01*
G01X1528700Y441421D02*
X1528874Y441165D01*
G01X1526174Y439800D02*
X1525999Y440056D01*
G01X1532086Y450722D02*
X1531903Y450987D01*
X1531839Y451286D01*
X1531904Y451582D01*
G01X1544257Y452383D02*
X1544580Y451964D01*
X1544742Y451480D01*
X1544721Y450976D01*
X1544518Y450499D01*
X1544151Y450095D01*
X1543645Y449828D01*
X1543054Y449734D01*
X1542464Y449831D01*
X1541962Y450100D01*
X1541598Y450504D01*
X1541397Y450982D01*
X1541377Y451487D01*
X1541541Y451968D01*
X1541862Y452383D01*
G01X1539090D02*
X1539413Y451964D01*
X1539575Y451480D01*
X1539553Y450976D01*
X1539350Y450499D01*
X1538984Y450095D01*
X1538477Y449828D01*
X1537886Y449734D01*
X1537297Y449831D01*
X1536795Y450100D01*
X1536431Y450504D01*
X1536229Y450982D01*
X1536210Y451487D01*
X1536374Y451968D01*
X1536694Y452383D01*
G01X1526916Y480840D02*
X1527010D01*
G01Y480092D02*
X1526916D01*
G01X1531630Y479616D02*
X1534779D01*
G01X1528480D02*
X1525331D01*
G01X1526905Y479321D02*
X1533205D01*
G01X1559583Y475692D02*
X1524149D01*
G01X1538244Y469793D02*
X1521866D01*
G01X1527890Y465463D02*
X1532220D01*
G01X1527264Y464675D02*
X1532846D01*
G01Y463100D02*
X1527264D01*
G01X1532220Y462313D02*
X1527890D01*
G01X1538244Y459616D02*
X1521866D01*
G01X1528886Y455640D02*
X1528000D01*
G01X1534718D02*
X1530806D01*
G01X1549334D02*
X1548448D01*
G01X1530806Y454901D02*
X1533684D01*
G01X1551709Y454892D02*
X1528087D01*
G01X1534423Y451432D02*
X1533611D01*
G01X1528087Y451112D02*
X1551709D01*
G01X1529624Y450472D02*
X1526672D01*
G01X1550072D02*
X1547119D01*
G01X1546234Y449734D02*
X1550072D01*
G01X1525786D02*
X1529624D01*
G01X1551709Y449144D02*
X1528087D01*
G01Y446703D02*
X1551709D01*
G01X1536549Y446211D02*
X1530449D01*
G01X1536549Y446151D02*
X1530449D01*
G01X1550916Y445758D02*
X1530449D01*
G01X1531551Y444577D02*
X1522181D01*
G01X1521866Y443396D02*
X1528401D01*
G01X1531551Y443179D02*
X1551709D01*
G01X1531551Y442805D02*
X1522181D01*
G01X1528526Y442018D02*
X1528177D01*
G01X1528265Y441506D02*
X1528439D01*
G01X1534976Y441348D02*
X1533992D01*
G01X1535567Y441191D02*
X1544551D01*
G01X1534976Y441151D02*
X1533992D01*
G01X1534976Y440758D02*
X1533992D01*
G01X1540075Y440738D02*
X1532004D01*
G01X1531945Y440561D02*
X1539110D01*
G01X1526696Y439629D02*
X1526435D01*
G01X1526348Y439117D02*
X1526784D01*
G01X1531945Y438986D02*
X1539110D01*
G01X1534976Y438789D02*
X1533992D01*
G01X1532004Y438770D02*
X1540075D01*
G01X1542605Y438612D02*
X1549937D01*
G01X1542457D02*
X1530449D01*
G01X1528177Y438435D02*
X1528874D01*
G01X1534976Y438396D02*
X1533992D01*
G01X1534976Y438199D02*
X1533992D01*
G01X1525390Y437923D02*
X1528787D01*
G01X1542457Y437825D02*
X1530449D01*
G01X1549937D02*
X1542605D01*
G01X1529484Y437411D02*
X1525390D01*
G01X1534976Y436348D02*
X1533992D01*
G01X1534976Y436151D02*
X1533992D01*
G01X1534976Y435758D02*
X1533992D01*
G01X1531945Y435561D02*
X1539110D01*
G01X1542605Y435463D02*
X1549937D01*
G01X1542457D02*
X1530449D01*
G01X1542457Y434675D02*
X1530449D01*
G01X1549937D02*
X1542605D01*
G01X1531945Y433986D02*
X1539110D01*
G01X1534976Y433789D02*
X1533992D01*
G01X1534976Y433396D02*
X1533992D01*
G01X1534976Y433199D02*
X1533992D01*
G01X1542605Y432313D02*
X1549937D01*
G01X1542457D02*
X1530449D01*
G01X1542457Y431525D02*
X1530449D01*
G01X1549937D02*
X1542605D01*
G01X1534976Y431348D02*
X1533992D01*
G01X1534976Y431151D02*
X1533992D01*
G01X1534976Y430758D02*
X1533992D01*
G01X1531945Y430561D02*
X1539110D01*
G01X1542605Y429163D02*
X1549937D01*
G01X1542457D02*
X1530449D01*
G01X1531945Y428986D02*
X1539110D01*
G01X1534976Y428789D02*
X1533992D01*
G01X1534976Y428396D02*
X1533992D01*
G01X1542457Y428376D02*
X1530449D01*
G01X1549937D02*
X1542605D01*
G01X1534976Y428199D02*
X1533992D01*
G01X1529223Y441591D02*
X1528874Y441932D01*
G01X1525651Y439629D02*
X1525999Y439288D01*
G01X1541862Y452383D02*
X1541410Y452823D01*
X1541140Y453359D01*
X1541070Y453929D01*
X1541211Y454494D01*
X1541558Y455018D01*
X1542085Y455412D01*
X1542728Y455615D01*
X1543407Y455612D01*
X1544047Y455405D01*
X1544570Y455008D01*
X1544912Y454485D01*
X1545050Y453923D01*
X1544978Y453356D01*
X1544708Y452822D01*
G01X1536694Y452383D02*
X1536243Y452823D01*
X1535973Y453359D01*
X1535902Y453929D01*
X1536044Y454494D01*
X1536391Y455018D01*
X1536918Y455412D01*
X1537561Y455615D01*
X1538240Y455612D01*
X1538880Y455405D01*
X1539403Y455008D01*
X1539744Y454485D01*
X1539882Y453923D01*
X1539811Y453356D01*
X1539540Y452822D01*
G01X1543482Y454824D02*
X1543843Y454588D01*
X1544081Y454237D01*
X1544167Y453834D01*
X1544084Y453432D01*
X1543848Y453079D01*
X1543484Y452839D01*
X1543059Y452755D01*
G01X1542636Y452839D02*
X1542276Y453075D01*
X1542038Y453425D01*
X1541952Y453828D01*
X1542035Y454231D01*
X1542271Y454583D01*
X1542635Y454823D01*
X1543059Y454908D01*
G01X1538315Y454824D02*
X1538675Y454588D01*
X1538914Y454237D01*
X1538999Y453834D01*
X1538917Y453432D01*
X1538680Y453079D01*
X1538317Y452839D01*
X1537892Y452755D01*
G01X1528874Y441932D02*
X1528526Y442018D01*
G01X1532712Y450472D02*
X1532365Y450542D01*
G01X1534976Y426348D02*
X1533992D01*
G01X1534976Y426151D02*
X1533992D01*
G01X1542605Y426014D02*
X1549937D01*
G01X1542457D02*
X1530449D01*
G01X1534976Y425758D02*
X1533992D01*
G01X1531945Y425561D02*
X1539110D01*
G01X1542457Y425226D02*
X1530449D01*
G01X1549937D02*
X1542605D01*
G01X1531945Y423986D02*
X1539110D01*
G01X1534976Y423789D02*
X1533992D01*
G01X1534976Y423396D02*
X1533992D01*
G01X1534976Y423199D02*
X1533992D01*
G01X1542605Y422864D02*
X1549937D01*
G01X1542457D02*
X1530449D01*
G01X1542457Y422077D02*
X1530449D01*
G01X1549937D02*
X1542605D01*
G01X1534976Y421348D02*
X1533992D01*
G01X1534976Y421151D02*
X1533992D01*
G01X1534976Y420758D02*
X1533992D01*
G01X1531945Y420561D02*
X1539110D01*
G01X1542605Y419714D02*
X1549937D01*
G01X1542457D02*
X1530449D01*
G01X1531945Y418986D02*
X1539110D01*
G01X1542457Y418927D02*
X1530449D01*
G01X1549937D02*
X1542605D01*
G01X1534976Y418789D02*
X1533992D01*
G01X1534976Y418396D02*
X1533992D01*
G01X1534976Y418199D02*
X1533992D01*
G01X1542605Y416565D02*
X1549937D01*
G01X1542457D02*
X1530449D01*
G01X1534976Y416348D02*
X1533992D01*
G01X1534976Y416151D02*
X1533992D01*
G01X1542457Y415777D02*
X1530449D01*
G01X1549937D02*
X1542605D01*
G01X1534976Y415758D02*
X1533992D01*
G01X1531945Y415561D02*
X1539110D01*
G01X1531945Y413986D02*
X1539110D01*
G01X1534976Y413789D02*
X1533992D01*
G01X1542605Y413415D02*
X1549937D01*
G01X1542457D02*
X1530449D01*
G01X1534976Y413396D02*
X1533992D01*
G01X1534976Y413199D02*
X1533992D01*
G01X1542457Y412628D02*
X1530449D01*
G01X1549937D02*
X1542605D01*
G01X1528874Y438435D02*
X1529484Y437923D01*
G01X1528787D02*
X1528177Y438435D01*
G01X1537469Y452839D02*
X1537109Y453075D01*
X1536870Y453425D01*
X1536785Y453828D01*
X1536867Y454231D01*
X1537104Y454583D01*
X1537467Y454823D01*
X1537892Y454908D01*
G01X1526435Y439629D02*
X1526174Y439800D01*
G01X1532366Y450541D02*
X1532086Y450722D01*
G01X1543408Y452031D02*
X1543691Y451854D01*
X1543878Y451588D01*
X1543945Y451287D01*
X1543881Y450986D01*
X1543695Y450719D01*
X1543410Y450538D01*
X1543059Y450472D01*
G01X1542711Y450537D02*
X1542428Y450715D01*
X1542241Y450980D01*
X1542174Y451282D01*
X1542238Y451582D01*
X1542424Y451849D01*
X1542709Y452031D01*
X1543059Y452096D01*
G01X1538241Y452031D02*
X1538524Y451854D01*
X1538711Y451588D01*
X1538778Y451287D01*
X1538713Y450986D01*
X1538528Y450719D01*
X1538243Y450538D01*
X1537892Y450472D01*
G01X1537543Y450537D02*
X1537261Y450715D01*
X1537073Y450980D01*
X1537006Y451282D01*
X1537071Y451582D01*
X1537256Y451849D01*
X1537542Y452031D01*
X1537892Y452096D01*
G01X1525999Y439288D02*
X1526348Y439117D01*
G01X1528439Y441506D02*
X1528700Y441421D01*
G01X1501709Y555108D02*
G03I-985J0D01*
G01X1496588Y550975D02*
G03X1497714Y548219I3937J0D01*
G01X1506433Y541329D02*
Y555108D01*
G01Y541329D02*
Y555108D01*
G01Y541329D02*
Y555108D01*
G01X1504464Y552746D02*
Y555108D01*
G01X1498559Y552746D02*
Y555108D01*
G01X1496590D02*
Y552746D01*
G01X1496588Y550975D02*
Y555108D01*
G01X1496590Y552746D02*
X1504464D01*
G01X1533205Y484439D02*
X1526905D01*
G01X1531630Y484144D02*
X1534779D01*
G01X1528480D02*
X1525331D01*
G01X1524149Y538054D02*
X1599147D01*
G01X1500364Y560128D02*
G03I-985J0D01*
G01X1496689Y563803D02*
G03I-984J0D01*
G01X1532220Y694596D02*
G03Y697746I0J1575D01*
G01X1527890D02*
G03Y694596I0J-1575D01*
G01X1538244Y703199D02*
Y690266D01*
G01X1532846Y695384D02*
Y696959D01*
G01X1532811D02*
Y695384D01*
G01X1532787Y696959D02*
Y695384D01*
G01X1531464D02*
Y696959D01*
G01X1531094D02*
Y695384D01*
G01X1529016D02*
Y696959D01*
G01X1528646D02*
Y695384D01*
G01X1527324D02*
Y696959D01*
G01X1527299Y695384D02*
Y696959D01*
G01X1527264D02*
Y695384D01*
G01X1521866Y716663D02*
Y690266D01*
G01X1538244Y700443D02*
X1521866D01*
G01X1527890Y697746D02*
X1532220D01*
G01X1527264Y696959D02*
X1532846D01*
G01Y695384D02*
X1527264D01*
G01X1532220Y694596D02*
X1527890D01*
G01X1521866Y690266D02*
X1538244D01*
G01X1509749Y759498D02*
X1510176Y760088D01*
G01X1509749Y764498D02*
X1510176Y765088D01*
G01X1509749Y769498D02*
X1510176Y770088D01*
G01X1507781Y774498D02*
X1508207Y775088D01*
G01X1504004Y761073D02*
X1503865Y760877D01*
X1503727Y760680D01*
X1503590Y760482D01*
G01X1504004Y766073D02*
X1503865Y765877D01*
X1503727Y765680D01*
X1503590Y765482D01*
G01X1504004Y771073D02*
X1503865Y770877D01*
X1503727Y770680D01*
X1503590Y770482D01*
G01X1509332Y760088D02*
X1509060Y759498D01*
G01X1509332Y765088D02*
X1509060Y764498D01*
G01X1509332Y770088D02*
X1509060Y769498D01*
G01X1507364Y775088D02*
X1507091Y774498D01*
G01X1503727Y762037D02*
X1503760Y762136D01*
X1503848Y762207D01*
X1503974Y762234D01*
G01X1509023Y774045D02*
X1509050Y774049D01*
X1509075Y774060D01*
X1509099Y774078D01*
X1509121Y774103D01*
X1509138Y774133D01*
X1509150Y774166D01*
X1509158Y774203D01*
X1509161Y774242D01*
G01X1509023Y770896D02*
X1509050Y770899D01*
X1509075Y770910D01*
X1509099Y770928D01*
X1509121Y770953D01*
X1509138Y770983D01*
X1509150Y771017D01*
X1509158Y771054D01*
X1509161Y771092D01*
G01X1509023Y767746D02*
X1509050Y767750D01*
X1509075Y767761D01*
X1509099Y767779D01*
X1509121Y767804D01*
X1509138Y767833D01*
X1509150Y767867D01*
X1509158Y767904D01*
X1509161Y767943D01*
G01X1509023Y764596D02*
X1509050Y764600D01*
X1509075Y764611D01*
X1509099Y764629D01*
X1509121Y764654D01*
X1509138Y764684D01*
X1509150Y764718D01*
X1509158Y764754D01*
X1509161Y764793D01*
G01X1509023Y761447D02*
X1509050Y761451D01*
X1509075Y761462D01*
X1509099Y761480D01*
X1509121Y761504D01*
X1509138Y761534D01*
X1509150Y761568D01*
X1509158Y761605D01*
X1509161Y761644D01*
G01X1509023Y758297D02*
X1509050Y758301D01*
X1509075Y758312D01*
X1509099Y758330D01*
X1509121Y758355D01*
X1509138Y758384D01*
X1509150Y758418D01*
X1509158Y758455D01*
X1509161Y758494D01*
G01X1503974Y774833D02*
X1503846Y774805D01*
X1503758Y774732D01*
X1503727Y774636D01*
G01X1503974Y771683D02*
X1503846Y771655D01*
X1503758Y771582D01*
X1503727Y771486D01*
G01X1503974Y768533D02*
X1503846Y768506D01*
X1503758Y768433D01*
X1503727Y768337D01*
G01X1503974Y765384D02*
X1503846Y765356D01*
X1503758Y765283D01*
X1503727Y765187D01*
G01X1503974Y759085D02*
X1503846Y759057D01*
X1503758Y758984D01*
X1503727Y758888D01*
G01X1508208Y760088D02*
X1508130Y759498D01*
G01X1508208Y765088D02*
X1508130Y764498D01*
G01X1508208Y770088D02*
X1508130Y769498D01*
G01X1506239Y775088D02*
X1506161Y774498D01*
G01X1508648Y758494D02*
X1508638Y758396D01*
X1508610Y758324D01*
X1508572Y758297D01*
G01X1508648Y761644D02*
X1508638Y761545D01*
X1508610Y761473D01*
X1508572Y761447D01*
G01X1508648Y764793D02*
X1508638Y764695D01*
X1508610Y764623D01*
X1508572Y764596D01*
G01X1508648Y767943D02*
X1508638Y767844D01*
X1508610Y767772D01*
X1508572Y767746D01*
G01X1508648Y771092D02*
X1508638Y770994D01*
X1508610Y770922D01*
X1508572Y770896D01*
G01X1508648Y774242D02*
X1508638Y774144D01*
X1508610Y774072D01*
X1508572Y774045D01*
G01X1508208Y770482D02*
X1508130Y771073D01*
G01X1508208Y765482D02*
X1508130Y766073D01*
G01X1508208Y760482D02*
X1508130Y761073D01*
G01X1501621Y775088D02*
X1508207D01*
G01X1503974Y774833D02*
X1510058D01*
G01X1503727Y774636D02*
X1510338D01*
G01X1502036Y774498D02*
X1507781D01*
G01X1501709Y774340D02*
X1528401D01*
G01X1510338Y774242D02*
X1503727D01*
G01X1503974Y774045D02*
X1510058D01*
G01X1528401Y771978D02*
X1501709D01*
G01X1503974Y771683D02*
X1510058D01*
G01X1503727Y771486D02*
X1510338D01*
G01Y771092D02*
X1503727D01*
G01X1509749Y771073D02*
X1504004D01*
G01X1503974Y770896D02*
X1510058D01*
G01X1510176Y770482D02*
X1503590D01*
G01Y770088D02*
X1510176D01*
G01X1504004Y769498D02*
X1509749D01*
G01X1503974Y768533D02*
X1510058D01*
G01X1503727Y768337D02*
X1510338D01*
G01Y767943D02*
X1503727D01*
G01X1503974Y767746D02*
X1510058D01*
G01X1509749Y766073D02*
X1504004D01*
G01X1510176Y765482D02*
X1503590D01*
G01X1503974Y765384D02*
X1510058D01*
G01X1503727Y765187D02*
X1510338D01*
G01X1503590Y765088D02*
X1510176D01*
G01X1510338Y764793D02*
X1503727D01*
G01X1503974Y764596D02*
X1510058D01*
G01X1504004Y764498D02*
X1509749D01*
G01X1503974Y762234D02*
X1510058D01*
G01X1503727Y762037D02*
X1510338D01*
G01Y761644D02*
X1503727D01*
G01X1503974Y761447D02*
X1510058D01*
G01X1509749Y761073D02*
X1504004D01*
G01X1510176Y760482D02*
X1503590D01*
G01Y760088D02*
X1510176D01*
G01X1504004Y759498D02*
X1509749D01*
G01X1503974Y759085D02*
X1510058D01*
G01X1503727Y758888D02*
X1510338D01*
G01Y758494D02*
X1503727D01*
G01X1503974Y758297D02*
X1510058D01*
G01X1510338Y771092D02*
Y771486D01*
G01Y774242D02*
Y774636D01*
G01Y767943D02*
Y768337D01*
G01Y761644D02*
Y762037D01*
G01Y764793D02*
Y765187D01*
G01Y758494D02*
Y758888D01*
G01X1510176Y760482D02*
Y760088D01*
G01Y765482D02*
Y765088D01*
G01Y770482D02*
Y770088D01*
G01X1509332Y760482D02*
Y760088D01*
G01Y765482D02*
Y765088D01*
G01Y770482D02*
Y770088D01*
G01X1509161Y771092D02*
Y771486D01*
G01Y774242D02*
Y774636D01*
G01Y767943D02*
Y768337D01*
G01Y761644D02*
Y762037D01*
G01Y764793D02*
Y765187D01*
G01Y758494D02*
Y758888D01*
G01X1508648D02*
Y758494D01*
G01Y762037D02*
Y761644D01*
G01Y765187D02*
Y764793D01*
G01Y768337D02*
Y767943D01*
G01Y771486D02*
Y771092D01*
G01Y774636D02*
Y774242D01*
G01X1508208Y770088D02*
Y770482D01*
G01Y765088D02*
Y765482D01*
G01Y760088D02*
Y760482D01*
G01X1508207Y775482D02*
Y775088D01*
G01X1507364Y775482D02*
Y775088D01*
G01X1506239D02*
Y775482D01*
G01X1503727Y758888D02*
Y758494D01*
G01Y762037D02*
Y761644D01*
G01Y765187D02*
Y764793D01*
G01Y768337D02*
Y767943D01*
G01Y771486D02*
Y771092D01*
G01Y774636D02*
Y774242D01*
G01X1503590Y770088D02*
Y770482D01*
G01Y765088D02*
Y765482D01*
G01Y760088D02*
Y760482D01*
G01X1501709Y849104D02*
Y716466D01*
G01X1501621Y775088D02*
Y775482D01*
G01X1500921Y715679D02*
Y786585D01*
G01X1500862Y716073D02*
Y849498D01*
G01X1499740Y854025D02*
Y711545D01*
G01X1509161Y774636D02*
X1509158Y774674D01*
X1509151Y774711D01*
X1509138Y774745D01*
X1509121Y774775D01*
X1509100Y774799D01*
X1509076Y774817D01*
X1509050Y774829D01*
X1509023Y774833D01*
G01X1509161Y771486D02*
X1509158Y771524D01*
X1509151Y771561D01*
X1509138Y771595D01*
X1509121Y771625D01*
X1509100Y771650D01*
X1509076Y771668D01*
X1509050Y771679D01*
X1509023Y771683D01*
G01X1509161Y768337D02*
X1509158Y768375D01*
X1509151Y768412D01*
X1509138Y768445D01*
X1509121Y768476D01*
X1509100Y768500D01*
X1509076Y768518D01*
X1509050Y768529D01*
X1509023Y768533D01*
G01X1509161Y765187D02*
X1509158Y765225D01*
X1509151Y765262D01*
X1509138Y765296D01*
X1509121Y765326D01*
X1509100Y765350D01*
X1509076Y765369D01*
X1509050Y765380D01*
X1509023Y765384D01*
G01X1509161Y762037D02*
X1509158Y762076D01*
X1509151Y762112D01*
X1509138Y762146D01*
X1509121Y762177D01*
X1509100Y762201D01*
X1509076Y762219D01*
X1509050Y762230D01*
X1509023Y762234D01*
G01X1509161Y758888D02*
X1509158Y758926D01*
X1509151Y758963D01*
X1509138Y758997D01*
X1509121Y759027D01*
X1509100Y759051D01*
X1509076Y759069D01*
X1509050Y759081D01*
X1509023Y759085D01*
G01X1503727Y774242D02*
X1503758Y774145D01*
X1503847Y774073D01*
X1503974Y774045D01*
G01X1503727Y771092D02*
X1503758Y770995D01*
X1503847Y770923D01*
X1503974Y770896D01*
G01X1503727Y767943D02*
X1503758Y767846D01*
X1503847Y767774D01*
X1503974Y767746D01*
G01X1503727Y764793D02*
X1503758Y764696D01*
X1503847Y764624D01*
X1503974Y764596D01*
G01X1503727Y758494D02*
X1503758Y758397D01*
X1503847Y758325D01*
X1503974Y758297D01*
G01Y761447D02*
X1503847Y761474D01*
X1503758Y761547D01*
X1503727Y761644D01*
G01X1509060Y771073D02*
X1509332Y770482D01*
G01X1509060Y766073D02*
X1509332Y765482D01*
G01X1509060Y761073D02*
X1509332Y760482D01*
G01X1501621Y775088D02*
X1501758Y774891D01*
X1501896Y774694D01*
X1502036Y774498D01*
G01X1503590Y770088D02*
X1503727Y769891D01*
X1503865Y769694D01*
X1504004Y769498D01*
G01X1503590Y765088D02*
X1503727Y764891D01*
X1503865Y764694D01*
X1504004Y764498D01*
G01X1503590Y760088D02*
X1503727Y759891D01*
X1503865Y759694D01*
X1504004Y759498D01*
G01X1509749Y771073D02*
X1510176Y770482D01*
G01X1509749Y766073D02*
X1510176Y765482D01*
G01X1509749Y761073D02*
X1510176Y760482D01*
G01X1508572Y774833D02*
X1508610Y774806D01*
X1508638Y774734D01*
X1508648Y774636D01*
G01X1508572Y771683D02*
X1508610Y771657D01*
X1508638Y771584D01*
X1508648Y771486D01*
G01X1508572Y768533D02*
X1508610Y768507D01*
X1508638Y768435D01*
X1508648Y768337D01*
G01X1508572Y765384D02*
X1508610Y765357D01*
X1508638Y765285D01*
X1508648Y765187D01*
G01X1508572Y762234D02*
X1508610Y762208D01*
X1508638Y762136D01*
X1508648Y762037D01*
G01X1508572Y759085D02*
X1508610Y759058D01*
X1508638Y758986D01*
X1508648Y758888D01*
G01X1531945Y769498D02*
G03X1531551Y769104I0J-394D01*
G01Y771466D02*
G03X1531945Y771073I394J1D01*
G01Y759498D02*
G03X1531551Y759104I0J-394D01*
G01Y761466D02*
G03X1531945Y761073I394J1D01*
G01X1531551Y756466D02*
G03X1531945Y756073I394J1D01*
G01Y764498D02*
G03X1531551Y764104I0J-394D01*
G01Y766466D02*
G03X1531945Y766073I394J1D01*
G01X1549937Y759085D02*
Y758297D01*
G01Y765384D02*
Y764596D01*
G01Y762234D02*
Y761447D01*
G01Y768533D02*
Y767746D01*
G01Y774833D02*
Y774045D01*
G01Y771683D02*
Y770896D01*
G01X1548163Y759085D02*
Y758297D01*
G01Y765384D02*
Y764596D01*
G01Y762234D02*
Y761447D01*
G01Y768533D02*
Y767746D01*
G01Y774833D02*
Y774045D01*
G01Y771683D02*
Y770896D01*
G01X1547975Y774045D02*
Y774833D01*
G01Y770896D02*
Y771683D01*
G01Y767746D02*
Y768533D01*
G01Y764596D02*
Y765384D01*
G01Y761447D02*
Y762234D01*
G01Y758297D02*
Y759085D01*
G01X1545138Y774045D02*
Y774833D01*
G01Y770896D02*
Y771683D01*
G01Y767746D02*
Y768533D01*
G01Y764596D02*
Y765384D01*
G01Y761447D02*
Y762234D01*
G01Y758297D02*
Y759085D01*
G01X1544551Y714301D02*
Y851270D01*
G01X1544197Y759085D02*
Y758297D01*
G01Y765384D02*
Y764596D01*
G01Y762234D02*
Y761447D01*
G01Y768533D02*
Y767746D01*
G01Y774833D02*
Y774045D01*
G01Y771683D02*
Y770896D01*
G01X1542605Y759085D02*
Y758297D01*
G01Y765384D02*
Y764596D01*
G01Y762234D02*
Y761447D01*
G01Y768533D02*
Y767746D01*
G01Y774833D02*
Y774045D01*
G01Y771683D02*
Y770896D01*
G01X1542457Y759085D02*
Y758297D01*
G01Y765384D02*
Y764596D01*
G01Y762234D02*
Y761447D01*
G01Y768533D02*
Y767746D01*
G01Y774833D02*
Y774045D01*
G01Y771683D02*
Y770896D01*
G01X1541519Y774833D02*
Y777195D01*
G01Y771683D02*
Y774045D01*
G01Y768533D02*
Y770896D01*
G01Y765384D02*
Y767746D01*
G01Y762234D02*
Y764596D01*
G01Y759085D02*
Y761447D01*
G01Y755935D02*
Y758297D01*
G01X1539791Y759085D02*
Y758297D01*
G01Y765384D02*
Y764596D01*
G01Y762234D02*
Y761447D01*
G01Y768533D02*
Y767746D01*
G01Y774833D02*
Y774045D01*
G01Y771683D02*
Y770896D01*
G01X1539110Y769498D02*
Y771073D01*
G01Y764498D02*
Y766073D01*
G01Y759498D02*
Y761073D01*
G01X1538139Y774045D02*
Y774833D01*
G01Y770896D02*
Y771683D01*
G01Y767746D02*
Y768533D01*
G01Y764596D02*
Y765384D01*
G01Y761447D02*
Y762234D01*
G01Y758297D02*
Y759085D01*
G01X1537142Y774498D02*
Y776073D01*
G01X1536156Y774045D02*
Y774833D01*
G01Y770896D02*
Y771683D01*
G01Y767746D02*
Y768533D01*
G01Y764596D02*
Y765384D01*
G01Y761447D02*
Y762234D01*
G01Y758297D02*
Y759085D01*
G01X1536021Y848691D02*
Y717077D01*
G01X1535961Y761073D02*
Y759498D01*
G01Y766073D02*
Y764498D01*
G01Y771073D02*
Y769498D01*
G01X1535567Y851270D02*
Y714301D01*
G01X1534976Y756860D02*
Y753711D01*
G01Y761860D02*
Y758711D01*
G01Y766860D02*
Y763711D01*
G01Y771860D02*
Y768711D01*
G01X1533992Y756860D02*
Y753711D01*
G01Y761860D02*
Y758711D01*
G01Y766860D02*
Y763711D01*
G01Y771860D02*
Y768711D01*
G01Y776073D02*
Y774498D01*
G01X1533008Y761073D02*
Y759498D01*
G01Y766073D02*
Y764498D01*
G01Y771073D02*
Y769498D01*
G01Y776860D02*
Y773711D01*
G01X1532793Y759085D02*
Y758297D01*
G01Y765384D02*
Y764596D01*
G01Y762234D02*
Y761447D01*
G01Y768533D02*
Y767746D01*
G01Y774833D02*
Y774045D01*
G01Y771683D02*
Y770896D01*
G01X1532417Y759085D02*
Y758297D01*
G01Y765384D02*
Y764596D01*
G01Y762234D02*
Y761447D01*
G01Y768533D02*
Y767746D01*
G01Y774833D02*
Y774045D01*
G01Y771683D02*
Y770896D01*
G01X1532391Y759085D02*
Y758297D01*
G01Y765384D02*
Y764596D01*
G01Y762234D02*
Y761447D01*
G01Y768533D02*
Y767746D01*
G01Y774833D02*
Y774045D01*
G01Y771683D02*
Y770896D01*
G01X1532024Y776860D02*
Y773711D01*
G01X1531551Y851270D02*
Y714301D01*
G01X1530449Y713848D02*
Y851722D01*
G01X1528401Y848907D02*
Y716663D01*
G01X1526433Y771978D02*
Y755443D01*
G01Y790679D02*
Y774340D01*
G01X1520212Y716466D02*
Y849104D01*
G01X1542605Y774833D02*
X1549937D01*
G01X1542457D02*
X1530449D01*
G01X1531551Y774498D02*
X1537142D01*
G01X1533008Y774301D02*
X1532024D01*
G01X1542457Y774045D02*
X1530449D01*
G01X1549937D02*
X1542605D01*
G01X1533008Y773907D02*
X1532024D01*
G01X1533008Y773711D02*
X1532024D01*
G01X1531551Y773081D02*
X1530449D01*
G01X1534976Y771860D02*
X1533992D01*
G01X1542605Y771683D02*
X1549937D01*
G01X1542457D02*
X1530449D01*
G01X1534976Y771663D02*
X1533992D01*
G01X1534976Y771270D02*
X1533992D01*
G01X1531945Y771073D02*
X1539110D01*
G01X1542457Y770896D02*
X1530449D01*
G01X1549937D02*
X1542605D01*
G01X1531945Y769498D02*
X1539110D01*
G01X1534976Y769301D02*
X1533992D01*
G01X1534976Y768907D02*
X1533992D01*
G01X1534976Y768711D02*
X1533992D01*
G01X1542605Y768533D02*
X1549937D01*
G01X1542457D02*
X1530449D01*
G01X1542457Y767746D02*
X1530449D01*
G01X1549937D02*
X1542605D01*
G01X1534976Y766860D02*
X1533992D01*
G01X1534976Y766663D02*
X1533992D01*
G01X1534976Y766270D02*
X1533992D01*
G01X1531945Y766073D02*
X1539110D01*
G01X1542605Y765384D02*
X1549937D01*
G01X1542457D02*
X1530449D01*
G01X1542457Y764596D02*
X1530449D01*
G01X1549937D02*
X1542605D01*
G01X1531945Y764498D02*
X1539110D01*
G01X1534976Y764301D02*
X1533992D01*
G01X1534976Y763907D02*
X1533992D01*
G01X1534976Y763711D02*
X1533992D01*
G01X1542605Y762234D02*
X1549937D01*
G01X1542457D02*
X1530449D01*
G01X1534976Y761860D02*
X1533992D01*
G01X1534976Y761663D02*
X1533992D01*
G01X1542457Y761447D02*
X1530449D01*
G01X1549937D02*
X1542605D01*
G01X1534976Y761270D02*
X1533992D01*
G01X1531945Y761073D02*
X1539110D01*
G01X1531945Y759498D02*
X1539110D01*
G01X1534976Y759301D02*
X1533992D01*
G01X1542605Y759085D02*
X1549937D01*
G01X1542457D02*
X1530449D01*
G01X1534976Y758907D02*
X1533992D01*
G01X1534976Y758711D02*
X1533992D01*
G01X1542457Y758297D02*
X1530449D01*
G01X1549937D02*
X1542605D01*
G01X1534976Y756860D02*
X1533992D01*
G01X1534976Y756663D02*
X1533992D01*
G01X1497714Y703931D02*
X1497677Y703607D01*
X1497683Y703366D01*
X1497740Y703230D01*
G01X1551709Y703199D02*
X1497772D01*
G01X1497740Y703230D02*
X1497682Y703370D01*
X1497677Y703610D01*
G01X1501709Y716466D02*
X1499740Y714498D01*
G01X1509749Y719498D02*
X1510176Y720088D01*
G01X1509749Y724498D02*
X1510176Y725088D01*
G01X1509749Y729498D02*
X1510176Y730088D01*
G01X1507781Y734498D02*
X1508207Y735088D01*
G01X1509749Y739498D02*
X1510176Y740088D01*
G01X1504004Y721073D02*
X1503865Y720877D01*
X1503727Y720680D01*
X1503590Y720482D01*
G01X1504004Y726073D02*
X1503865Y725877D01*
X1503727Y725680D01*
X1503590Y725482D01*
G01X1509749Y744498D02*
X1510176Y745088D01*
G01X1509749Y749498D02*
X1510176Y750088D01*
G01X1509749Y754498D02*
X1510176Y755088D01*
G01X1504004Y731073D02*
X1503865Y730877D01*
X1503727Y730680D01*
X1503590Y730482D01*
G01X1502036Y736073D02*
X1501896Y735877D01*
X1501758Y735680D01*
X1501621Y735482D01*
G01X1504004Y741073D02*
X1503865Y740877D01*
X1503727Y740680D01*
X1503590Y740482D01*
G01X1504004Y746073D02*
X1503865Y745877D01*
X1503727Y745680D01*
X1503590Y745482D01*
G01X1504004Y751073D02*
X1503865Y750877D01*
X1503727Y750680D01*
X1503590Y750482D01*
G01X1504004Y756073D02*
X1503865Y755877D01*
X1503727Y755680D01*
X1503590Y755482D01*
G01X1509332Y720088D02*
X1509060Y719498D01*
G01X1509332Y725088D02*
X1509060Y724498D01*
G01X1509332Y730088D02*
X1509060Y729498D01*
G01X1507364Y735088D02*
X1507091Y734498D01*
G01X1509332Y740088D02*
X1509060Y739498D01*
G01X1509332Y745088D02*
X1509060Y744498D01*
G01X1509332Y750088D02*
X1509060Y749498D01*
G01X1509332Y755088D02*
X1509060Y754498D01*
G01X1503727Y733691D02*
X1503760Y733790D01*
X1503848Y733861D01*
X1503974Y733888D01*
G01X1509023Y755148D02*
X1509050Y755151D01*
X1509075Y755162D01*
X1509099Y755180D01*
X1509121Y755205D01*
X1509138Y755235D01*
X1509150Y755269D01*
X1509158Y755305D01*
X1509161Y755344D01*
G01X1509023Y751998D02*
X1509050Y752002D01*
X1509075Y752013D01*
X1509099Y752031D01*
X1509121Y752056D01*
X1509138Y752085D01*
X1509150Y752119D01*
X1509158Y752156D01*
X1509161Y752195D01*
G01X1509023Y748848D02*
X1509050Y748852D01*
X1509075Y748863D01*
X1509099Y748881D01*
X1509121Y748906D01*
X1509138Y748936D01*
X1509150Y748970D01*
X1509158Y749006D01*
X1509161Y749045D01*
G01X1509023Y745699D02*
X1509050Y745702D01*
X1509075Y745714D01*
X1509099Y745732D01*
X1509121Y745756D01*
X1509138Y745786D01*
X1509150Y745820D01*
X1509158Y745857D01*
X1509161Y745896D01*
G01X1503974Y755935D02*
X1503846Y755907D01*
X1503758Y755834D01*
X1503727Y755738D01*
G01X1503974Y752785D02*
X1503846Y752758D01*
X1503758Y752685D01*
X1503727Y752588D01*
G01X1503974Y749636D02*
X1503846Y749608D01*
X1503758Y749535D01*
X1503727Y749439D01*
G01X1503974Y746486D02*
X1503846Y746458D01*
X1503758Y746385D01*
X1503727Y746289D01*
G01X1503974Y743337D02*
X1503846Y743309D01*
X1503758Y743236D01*
X1503727Y743140D01*
G01X1503974Y740187D02*
X1503846Y740159D01*
X1503758Y740086D01*
X1503727Y739990D01*
G01X1503974Y737037D02*
X1503846Y737010D01*
X1503758Y736937D01*
X1503727Y736840D01*
G01X1503974Y730738D02*
X1503846Y730710D01*
X1503758Y730637D01*
X1503727Y730541D01*
G01X1503974Y727588D02*
X1503846Y727561D01*
X1503758Y727488D01*
X1503727Y727392D01*
G01X1503974Y724439D02*
X1503846Y724411D01*
X1503758Y724338D01*
X1503727Y724242D01*
G01X1503974Y721289D02*
X1503846Y721262D01*
X1503758Y721189D01*
X1503727Y721092D01*
G01X1497714Y703929D02*
X1497767Y704306D01*
G01X1508208Y720088D02*
X1508130Y719498D01*
G01Y724498D02*
X1508208Y725088D01*
G01Y730088D02*
X1508130Y729498D01*
G01X1508208Y740088D02*
X1508130Y739498D01*
G01X1508208Y745088D02*
X1508130Y744498D01*
G01X1506239Y735088D02*
X1506161Y734498D01*
G01X1508208Y750088D02*
X1508130Y749498D01*
G01X1508208Y755088D02*
X1508130Y754498D01*
G01X1508648Y720699D02*
X1508638Y720600D01*
X1508610Y720528D01*
X1508572Y720502D01*
G01X1508648Y723848D02*
X1508638Y723750D01*
X1508610Y723678D01*
X1508572Y723651D01*
G01X1508648Y726998D02*
X1508638Y726900D01*
X1508610Y726827D01*
X1508572Y726801D01*
G01X1508648Y730148D02*
X1508638Y730049D01*
X1508610Y729977D01*
X1508572Y729951D01*
G01X1508648Y733297D02*
X1508638Y733199D01*
X1508610Y733127D01*
X1508572Y733100D01*
G01X1508648Y736447D02*
X1508638Y736348D01*
X1508610Y736276D01*
X1508572Y736250D01*
G01X1508648Y739596D02*
X1508638Y739498D01*
X1508610Y739426D01*
X1508572Y739400D01*
G01X1508648Y742746D02*
X1508638Y742648D01*
X1508610Y742576D01*
X1508572Y742549D01*
G01X1508648Y745896D02*
X1508638Y745797D01*
X1508610Y745725D01*
X1508572Y745699D01*
G01X1508648Y749045D02*
X1508638Y748947D01*
X1508610Y748875D01*
X1508572Y748848D01*
G01X1508648Y752195D02*
X1508638Y752096D01*
X1508610Y752024D01*
X1508572Y751998D01*
G01X1508648Y755344D02*
X1508638Y755246D01*
X1508610Y755174D01*
X1508572Y755148D01*
G01X1508208Y755482D02*
X1508130Y756073D01*
G01X1508208Y750482D02*
X1508130Y751073D01*
G01X1508208Y745482D02*
X1508130Y746073D01*
G01X1508208Y740482D02*
X1508130Y741073D01*
G01X1508208Y730482D02*
X1508130Y731073D01*
G01Y726073D02*
X1508208Y725482D01*
G01X1506239Y735482D02*
X1506161Y736073D01*
G01X1508208Y720482D02*
X1508130Y721073D01*
G01X1509749Y756073D02*
X1504004D01*
G01X1503974Y755935D02*
X1510058D01*
G01X1503727Y755738D02*
X1510338D01*
G01X1510176Y755482D02*
X1503590D01*
G01X1501709Y755443D02*
X1528401D01*
G01X1510338Y755344D02*
X1503727D01*
G01X1503974Y755148D02*
X1510058D01*
G01X1503590Y755088D02*
X1510176D01*
G01X1504004Y754498D02*
X1509749D01*
G01X1528401Y753081D02*
X1501709D01*
G01X1503974Y752785D02*
X1510058D01*
G01X1503727Y752588D02*
X1510338D01*
G01Y752195D02*
X1503727D01*
G01X1503974Y751998D02*
X1510058D01*
G01X1509749Y751073D02*
X1504004D01*
G01X1510176Y750482D02*
X1503590D01*
G01Y750088D02*
X1510176D01*
G01X1503974Y749636D02*
X1510058D01*
G01X1504004Y749498D02*
X1509749D01*
G01X1503727Y749439D02*
X1510338D01*
G01Y749045D02*
X1503727D01*
G01X1503974Y748848D02*
X1510058D01*
G01X1503974Y746486D02*
X1510058D01*
G01X1503727Y746289D02*
X1510338D01*
G01X1509749Y746073D02*
X1504004D01*
G01X1510338Y745896D02*
X1503727D01*
G01X1503974Y745699D02*
X1510058D01*
G01X1510176Y745482D02*
X1503590D01*
G01Y745088D02*
X1510176D01*
G01X1504004Y744498D02*
X1509749D01*
G01X1503974Y743337D02*
X1510058D01*
G01X1503727Y743140D02*
X1510338D01*
G01Y742746D02*
X1503727D01*
G01X1503974Y742549D02*
X1510058D01*
G01X1509749Y741073D02*
X1504004D01*
G01X1510176Y740482D02*
X1503590D01*
G01X1503974Y740187D02*
X1510058D01*
G01X1503590Y740088D02*
X1510176D01*
G01X1503727Y739990D02*
X1510338D01*
G01Y739596D02*
X1503727D01*
G01X1504004Y739498D02*
X1509749D01*
G01X1503974Y739400D02*
X1510058D01*
G01X1503974Y737037D02*
X1510058D01*
G01X1503727Y736840D02*
X1510338D01*
G01X1501709Y736545D02*
X1528401D01*
G01X1510338Y736447D02*
X1503727D01*
G01X1503974Y736250D02*
X1510058D01*
G01X1507781Y736073D02*
X1502036D01*
G01X1509023Y742549D02*
X1509050Y742553D01*
X1509075Y742564D01*
X1509099Y742582D01*
X1509121Y742607D01*
X1509138Y742636D01*
X1509150Y742670D01*
X1509158Y742707D01*
X1509161Y742746D01*
G01X1509023Y739400D02*
X1509050Y739403D01*
X1509075Y739414D01*
X1509099Y739432D01*
X1509121Y739457D01*
X1509138Y739487D01*
X1509150Y739521D01*
X1509158Y739557D01*
X1509161Y739596D01*
G01X1509023Y736250D02*
X1509050Y736254D01*
X1509075Y736265D01*
X1509099Y736283D01*
X1509121Y736308D01*
X1509138Y736337D01*
X1509150Y736371D01*
X1509158Y736408D01*
X1509161Y736447D01*
G01X1509023Y733100D02*
X1509050Y733104D01*
X1509075Y733115D01*
X1509099Y733133D01*
X1509121Y733158D01*
X1509138Y733188D01*
X1509150Y733221D01*
X1509158Y733258D01*
X1509161Y733297D01*
G01X1509023Y729951D02*
X1509050Y729954D01*
X1509075Y729966D01*
X1509099Y729984D01*
X1509121Y730008D01*
X1509138Y730038D01*
X1509150Y730072D01*
X1509158Y730109D01*
X1509161Y730148D01*
G01X1509023Y726801D02*
X1509050Y726805D01*
X1509075Y726816D01*
X1509099Y726834D01*
X1509121Y726859D01*
X1509138Y726888D01*
X1509150Y726922D01*
X1509158Y726959D01*
X1509161Y726998D01*
G01X1509023Y723651D02*
X1509050Y723655D01*
X1509075Y723666D01*
X1509099Y723684D01*
X1509121Y723709D01*
X1509138Y723739D01*
X1509150Y723773D01*
X1509158Y723809D01*
X1509161Y723848D01*
G01X1509023Y720502D02*
X1509050Y720506D01*
X1509075Y720517D01*
X1509099Y720535D01*
X1509121Y720560D01*
X1509138Y720589D01*
X1509150Y720623D01*
X1509158Y720660D01*
X1509161Y720699D01*
G01X1510338Y752195D02*
Y752588D01*
G01Y755344D02*
Y755738D01*
G01Y749045D02*
Y749439D01*
G01Y742746D02*
Y743140D01*
G01Y745896D02*
Y746289D01*
G01Y739596D02*
Y739990D01*
G01Y736447D02*
Y736840D01*
G01Y730148D02*
Y730541D01*
G01Y733297D02*
Y733691D01*
G01Y726998D02*
Y727392D01*
G01Y723848D02*
Y724242D01*
G01Y720699D02*
Y721092D01*
G01X1510176Y720482D02*
Y720088D01*
G01Y725482D02*
Y725088D01*
G01Y730482D02*
Y730088D01*
G01Y740482D02*
Y740088D01*
G01Y745482D02*
Y745088D01*
G01Y750482D02*
Y750088D01*
G01Y755482D02*
Y755088D01*
G01X1509332Y720482D02*
Y720088D01*
G01Y725482D02*
Y725088D01*
G01Y730482D02*
Y730088D01*
G01Y740482D02*
Y740088D01*
G01Y745482D02*
Y745088D01*
G01Y750482D02*
Y750088D01*
G01Y755482D02*
Y755088D01*
G01X1509161Y752195D02*
Y752588D01*
G01Y755344D02*
Y755738D01*
G01Y749045D02*
Y749439D01*
G01Y742746D02*
Y743140D01*
G01Y745896D02*
Y746289D01*
G01Y739596D02*
Y739990D01*
G01Y736447D02*
Y736840D01*
G01Y730148D02*
Y730541D01*
G01Y733297D02*
Y733691D01*
G01Y726998D02*
Y727392D01*
G01Y723848D02*
Y724242D01*
G01Y720699D02*
Y721092D01*
G01X1508648Y724242D02*
Y723848D01*
G01Y721092D02*
Y720699D01*
G01Y727392D02*
Y726998D01*
G01Y730541D02*
Y730148D01*
G01Y733691D02*
Y733297D01*
G01Y736840D02*
Y736447D01*
G01Y739990D02*
Y739596D01*
G01Y743140D02*
Y742746D01*
G01Y746289D02*
Y745896D01*
G01Y749439D02*
Y749045D01*
G01Y752588D02*
Y752195D01*
G01Y755738D02*
Y755344D01*
G01X1508208Y755088D02*
Y755482D01*
G01Y750088D02*
Y750482D01*
G01Y745088D02*
Y745482D01*
G01Y740088D02*
Y740482D01*
G01Y730088D02*
Y730482D01*
G01Y720088D02*
Y720482D01*
G01Y725482D02*
Y725088D01*
G01X1508207Y735482D02*
Y735088D01*
G01X1507364Y735482D02*
Y735088D01*
G01X1506239D02*
Y735482D01*
G01X1503727Y724242D02*
Y723848D01*
G01Y721092D02*
Y720699D01*
G01Y727392D02*
Y726998D01*
G01Y730541D02*
Y730148D01*
G01Y733691D02*
Y733297D01*
G01Y736840D02*
Y736447D01*
G01Y739990D02*
Y739596D01*
G01Y743140D02*
Y742746D01*
G01Y746289D02*
Y745896D01*
G01Y749439D02*
Y749045D01*
G01Y752588D02*
Y752195D01*
G01Y755738D02*
Y755344D01*
G01X1503590Y755088D02*
Y755482D01*
G01Y750088D02*
Y750482D01*
G01Y745088D02*
Y745482D01*
G01Y740088D02*
Y740482D01*
G01Y730088D02*
Y730482D01*
G01Y725088D02*
Y725482D01*
G01Y720088D02*
Y720482D01*
G01X1501621Y735088D02*
Y735482D01*
G01X1497772Y711545D02*
Y704380D01*
G01X1509161Y755738D02*
X1509158Y755776D01*
X1509151Y755813D01*
X1509138Y755847D01*
X1509121Y755877D01*
X1509100Y755902D01*
X1509076Y755920D01*
X1509050Y755931D01*
X1509023Y755935D01*
G01X1509161Y752588D02*
X1509158Y752627D01*
X1509151Y752663D01*
X1509138Y752697D01*
X1509121Y752728D01*
X1509100Y752752D01*
X1509076Y752770D01*
X1509050Y752781D01*
X1509023Y752785D01*
G01X1509161Y749439D02*
X1509158Y749477D01*
X1509151Y749514D01*
X1509138Y749548D01*
X1509121Y749578D01*
X1509100Y749602D01*
X1509076Y749621D01*
X1509050Y749632D01*
X1509023Y749636D01*
G01X1509161Y746289D02*
X1509158Y746328D01*
X1509151Y746364D01*
X1509138Y746398D01*
X1509121Y746428D01*
X1509100Y746453D01*
X1509076Y746471D01*
X1509050Y746482D01*
X1509023Y746486D01*
G01X1509161Y743140D02*
X1509158Y743178D01*
X1509151Y743215D01*
X1509138Y743249D01*
X1509121Y743279D01*
X1509100Y743303D01*
X1509076Y743321D01*
X1509050Y743333D01*
X1509023Y743337D01*
G01X1509161Y739990D02*
X1509158Y740028D01*
X1509151Y740065D01*
X1509138Y740099D01*
X1509121Y740129D01*
X1509100Y740154D01*
X1509076Y740172D01*
X1509050Y740183D01*
X1509023Y740187D01*
G01X1509161Y736840D02*
X1509158Y736879D01*
X1509151Y736915D01*
X1509138Y736949D01*
X1509121Y736980D01*
X1509100Y737004D01*
X1509076Y737022D01*
X1509050Y737033D01*
X1509023Y737037D01*
G01X1509161Y733691D02*
X1509158Y733729D01*
X1509151Y733766D01*
X1509138Y733800D01*
X1509121Y733830D01*
X1509100Y733854D01*
X1509076Y733873D01*
X1509050Y733884D01*
X1509023Y733888D01*
G01X1509161Y730541D02*
X1509158Y730579D01*
X1509151Y730616D01*
X1509138Y730650D01*
X1509121Y730680D01*
X1509100Y730705D01*
X1509076Y730723D01*
X1509050Y730734D01*
X1509023Y730738D01*
G01X1509161Y727392D02*
X1509158Y727430D01*
X1509151Y727467D01*
X1509138Y727501D01*
X1509121Y727531D01*
X1509100Y727555D01*
X1509076Y727573D01*
X1509050Y727585D01*
X1509023Y727588D01*
G01X1509161Y724242D02*
X1509158Y724280D01*
X1509151Y724317D01*
X1509138Y724351D01*
X1509121Y724381D01*
X1509100Y724406D01*
X1509076Y724424D01*
X1509050Y724435D01*
X1509023Y724439D01*
G01X1509161Y721092D02*
X1509158Y721131D01*
X1509151Y721167D01*
X1509138Y721201D01*
X1509121Y721232D01*
X1509100Y721256D01*
X1509076Y721274D01*
X1509050Y721285D01*
X1509023Y721289D01*
G01X1503727Y755344D02*
X1503758Y755247D01*
X1503847Y755175D01*
X1503974Y755148D01*
G01X1503727Y752195D02*
X1503758Y752098D01*
X1503847Y752026D01*
X1503974Y751998D01*
G01X1503727Y749045D02*
X1503758Y748948D01*
X1503847Y748876D01*
X1503974Y748848D01*
G01X1503727Y745896D02*
X1503758Y745799D01*
X1503847Y745726D01*
X1503974Y745699D01*
G01X1503727Y742746D02*
X1503758Y742649D01*
X1503847Y742577D01*
X1503974Y742549D01*
G01X1503727Y739596D02*
X1503758Y739499D01*
X1503847Y739427D01*
X1503974Y739400D01*
G01X1503727Y736447D02*
X1503758Y736350D01*
X1503847Y736278D01*
X1503974Y736250D01*
G01X1508207Y735482D02*
X1501621D01*
G01Y735088D02*
X1508207D01*
G01X1502036Y734498D02*
X1507781D01*
G01X1528401Y734183D02*
X1501709D01*
G01X1503974Y733888D02*
X1510058D01*
G01X1503727Y733691D02*
X1510338D01*
G01Y733297D02*
X1503727D01*
G01X1503974Y733100D02*
X1510058D01*
G01X1509749Y731073D02*
X1504004D01*
G01X1503974Y730738D02*
X1510058D01*
G01X1503727Y730541D02*
X1510338D01*
G01X1510176Y730482D02*
X1503590D01*
G01X1510338Y730148D02*
X1503727D01*
G01X1503590Y730088D02*
X1510176D01*
G01X1503974Y729951D02*
X1510058D01*
G01X1504004Y729498D02*
X1509749D01*
G01X1503974Y727588D02*
X1510058D01*
G01X1503727Y727392D02*
X1510338D01*
G01Y726998D02*
X1503727D01*
G01X1503974Y726801D02*
X1510058D01*
G01X1509749Y726073D02*
X1504004D01*
G01X1510176Y725482D02*
X1503590D01*
G01Y725088D02*
X1510176D01*
G01X1504004Y724498D02*
X1509749D01*
G01X1503974Y724439D02*
X1510058D01*
G01X1503727Y724242D02*
X1510338D01*
G01Y723848D02*
X1503727D01*
G01X1503974Y723651D02*
X1510058D01*
G01X1503974Y721289D02*
X1510058D01*
G01X1503727Y721092D02*
X1510338D01*
G01X1509749Y721073D02*
X1504004D01*
G01X1510338Y720699D02*
X1503727D01*
G01X1503974Y720502D02*
X1510058D01*
G01X1510176Y720482D02*
X1503590D01*
G01Y720088D02*
X1510176D01*
G01X1504004Y719498D02*
X1509749D01*
G01X1501709Y716466D02*
X1520212D01*
G01X1499740Y716073D02*
X1530449D01*
G01X1501709Y711545D02*
X1551709D01*
G01X1499740D02*
X1496457D01*
G01X1497772Y704380D02*
X1524149D01*
G01X1503727Y730148D02*
X1503758Y730051D01*
X1503847Y729978D01*
X1503974Y729951D01*
G01X1503727Y726998D02*
X1503758Y726901D01*
X1503847Y726829D01*
X1503974Y726801D01*
G01X1503727Y723848D02*
X1503758Y723751D01*
X1503847Y723679D01*
X1503974Y723651D01*
G01X1503727Y720699D02*
X1503758Y720602D01*
X1503847Y720530D01*
X1503974Y720502D01*
G01X1509060Y756073D02*
X1509332Y755482D01*
G01X1509060Y751073D02*
X1509332Y750482D01*
G01X1509060Y746073D02*
X1509332Y745482D01*
G01X1509060Y741073D02*
X1509332Y740482D01*
G01X1507091Y736073D02*
X1507364Y735482D01*
G01X1509060Y731073D02*
X1509332Y730482D01*
G01X1509060Y726073D02*
X1509332Y725482D01*
G01X1509060Y721073D02*
X1509332Y720482D01*
G01X1503590Y755088D02*
X1503727Y754891D01*
X1503865Y754694D01*
X1504004Y754498D01*
G01X1503590Y750088D02*
X1503727Y749891D01*
X1503865Y749694D01*
X1504004Y749498D01*
G01X1503590Y745088D02*
X1503727Y744891D01*
X1503865Y744694D01*
X1504004Y744498D01*
G01X1503590Y740088D02*
X1503727Y739891D01*
X1503865Y739694D01*
X1504004Y739498D01*
G01X1509749Y756073D02*
X1510176Y755482D01*
G01X1509749Y751073D02*
X1510176Y750482D01*
G01X1509749Y746073D02*
X1510176Y745482D01*
G01X1509749Y741073D02*
X1510176Y740482D01*
G01X1507781Y736073D02*
X1508207Y735482D01*
G01X1508572Y755935D02*
X1508610Y755909D01*
X1508638Y755836D01*
X1508648Y755738D01*
G01X1508572Y752785D02*
X1508610Y752759D01*
X1508638Y752687D01*
X1508648Y752588D01*
G01X1503974Y733100D02*
X1503847Y733128D01*
X1503758Y733200D01*
X1503727Y733297D01*
G01X1501621Y735088D02*
X1501758Y734891D01*
X1501896Y734694D01*
X1502036Y734498D01*
G01X1503590Y730088D02*
X1503727Y729891D01*
X1503865Y729694D01*
X1504004Y729498D01*
G01X1503590Y725088D02*
X1503727Y724891D01*
X1503865Y724694D01*
X1504004Y724498D01*
G01X1503590Y720088D02*
X1503727Y719891D01*
X1503865Y719694D01*
X1504004Y719498D01*
G01X1509749Y731073D02*
X1510176Y730482D01*
G01X1509749Y726073D02*
X1510176Y725482D01*
G01X1509749Y721073D02*
X1510176Y720482D01*
G01X1499740Y713514D02*
X1501709Y711545D01*
G01X1508572Y749636D02*
X1508610Y749609D01*
X1508638Y749537D01*
X1508648Y749439D01*
G01X1508572Y746486D02*
X1508610Y746460D01*
X1508638Y746388D01*
X1508648Y746289D01*
G01X1508572Y743337D02*
X1508610Y743310D01*
X1508638Y743238D01*
X1508648Y743140D01*
G01X1508572Y740187D02*
X1508610Y740161D01*
X1508638Y740088D01*
X1508648Y739990D01*
G01X1508572Y737037D02*
X1508610Y737011D01*
X1508638Y736939D01*
X1508648Y736840D01*
G01X1508572Y733888D02*
X1508610Y733861D01*
X1508638Y733789D01*
X1508648Y733691D01*
G01X1508572Y730738D02*
X1508610Y730712D01*
X1508638Y730640D01*
X1508648Y730541D01*
G01X1508572Y727588D02*
X1508610Y727562D01*
X1508638Y727490D01*
X1508648Y727392D01*
G01X1508572Y724439D02*
X1508610Y724412D01*
X1508638Y724340D01*
X1508648Y724242D01*
G01X1508572Y721289D02*
X1508610Y721263D01*
X1508638Y721191D01*
X1508648Y721092D01*
G01X1551709Y703199D02*
Y717077D01*
G01X1524149Y703199D02*
Y711545D01*
G01X1543875Y707025D02*
G03X1542450I-713J83D01*
G01X1542889Y704401D02*
G03X1544475Y704687I265J3073D01*
G01X1543223Y705392D02*
G03X1543814Y705757I10J645D01*
G01X1542450Y706200D02*
G03X1543223Y705392I791J-17D01*
G01X1544475Y704687D02*
G03X1545318Y705756I-704J1422D01*
G01X1545109Y707643D02*
G03X1543875Y708616I-1735J-931D01*
G01X1542232Y708573D02*
G03X1541068Y707434I730J-1911D01*
G01X1541154Y705418D02*
G03X1542893Y704401I1806J1094D01*
G01X1543875Y708616D02*
G03X1542232Y708572I-756J-2475D01*
G01X1540894Y706278D02*
G03X1541156Y705415I2971J431D01*
G01X1545448Y706200D02*
G03X1545109Y707643I-3015J53D01*
G01X1540894Y706773D02*
G03Y706276I3524J-249D01*
G01X1541068Y707434D02*
G03X1540894Y706773I4018J-1411D01*
G01X1541472Y707982D02*
G03I-2165J0D01*
G01X1541261Y705266D02*
G03Y710699I-1954J2716D01*
G01X1537353D02*
G03Y705266I1954J-2717D01*
G01X1542811Y707982D02*
G03I-3504J0D01*
G01X1537003Y711880D02*
G03Y704085I2304J-3898D01*
G01X1541611D02*
G03Y711880I-2304J3897D01*
G01X1531945Y754498D02*
G03X1531551Y754104I0J-394D01*
G01X1531945Y739498D02*
G03X1531551Y739104I0J-394D01*
G01Y741466D02*
G03X1531945Y741073I394J1D01*
G01Y744498D02*
G03X1531551Y744104I0J-394D01*
G01Y746466D02*
G03X1531945Y746073I394J1D01*
G01Y749498D02*
G03X1531551Y749104I0J-394D01*
G01Y751466D02*
G03X1531945Y751073I394J1D01*
G01X1535250Y705709D02*
G03X1536723I736J278D01*
G01Y707394D02*
G03X1535250I-737J-277D01*
G01X1533978Y705375D02*
G03X1534499Y704809I1352J722D01*
G01X1537545Y704811D02*
G03X1538065Y705376I-832J1287D01*
G01Y707689D02*
G03X1537544Y708254I-1351J-723D01*
G01X1534498Y708253D02*
G03X1533977Y707688I830J-1288D01*
G01X1535250Y707394D02*
G03Y705710I2236J-842D01*
G01X1533977Y707688D02*
G03X1533978Y705375I2163J-1156D01*
G01X1538065Y705376D02*
G03Y707689I-2163J1156D01*
G01X1534499Y704809D02*
G03X1537545Y704811I1521J2363D01*
G01X1537544Y708254D02*
G03X1534498I-1523J-2362D01*
G01X1531945Y719498D02*
G03X1531551Y719104I0J-394D01*
G01Y721466D02*
G03X1531945Y721073I394J1D01*
G01Y729498D02*
G03X1531551Y729104I0J-394D01*
G01Y731466D02*
G03X1531945Y731073I394J1D01*
G01Y724498D02*
G03X1531551Y724104I0J-394D01*
G01Y726466D02*
G03X1531945Y726073I394J1D01*
G01X1533043Y707530D02*
G03X1532749Y708201I-913J0D01*
G01D02*
G03X1530114Y708056I-1247J-1352D01*
G01X1536723Y705710D02*
G03Y707394I-2237J842D01*
G01X1528761Y707125D02*
G03X1527330I-716J0D01*
G01X1531651D02*
G03X1530220I-716J0D01*
G01X1530114Y708056D02*
G03X1527333Y708051I-1388J-1207D01*
G01X1549942Y708607D02*
X1548647Y706756D01*
G01X1548560Y708607D02*
X1547870Y707621D01*
G01X1546917Y706747D02*
X1545474Y704601D01*
G01X1536549Y713907D02*
X1536804Y714301D01*
G01X1547673Y705878D02*
X1546882Y704601D01*
G01X1541261Y710699D02*
X1541279Y710755D01*
X1541331Y710920D01*
X1541410Y711178D01*
X1541506Y711505D01*
X1541611Y711880D01*
G01X1537003Y704085D02*
X1537106Y704454D01*
X1537203Y704783D01*
X1537283Y705045D01*
X1537335Y705211D01*
X1537353Y705266D01*
G01X1551391Y711545D02*
Y717077D01*
G01X1550916Y714301D02*
Y717077D01*
G01X1549937Y721289D02*
Y720502D01*
G01Y727588D02*
Y726801D01*
G01Y724439D02*
Y723651D01*
G01Y730738D02*
Y729951D01*
G01Y737037D02*
Y736250D01*
G01Y733888D02*
Y733100D01*
G01Y740187D02*
Y739400D01*
G01Y746486D02*
Y745699D01*
G01Y743337D02*
Y742549D01*
G01Y749636D02*
Y748848D01*
G01Y755935D02*
Y755148D01*
G01Y752785D02*
Y751998D01*
G01X1548163Y721289D02*
Y720502D01*
G01Y727588D02*
Y726801D01*
G01Y724439D02*
Y723651D01*
G01Y730738D02*
Y729951D01*
G01Y737037D02*
Y736250D01*
G01Y733888D02*
Y733100D01*
G01Y740187D02*
Y739400D01*
G01Y746486D02*
Y745699D01*
G01Y743337D02*
Y742549D01*
G01Y749636D02*
Y748848D01*
G01Y755935D02*
Y755148D01*
G01Y752785D02*
Y751998D01*
G01X1547975Y755148D02*
Y755935D01*
G01Y751998D02*
Y752785D01*
G01Y748848D02*
Y749636D01*
G01Y745699D02*
Y746486D01*
G01Y742549D02*
Y743337D01*
G01Y739400D02*
Y740187D01*
G01Y736250D02*
Y737037D01*
G01Y733100D02*
Y733888D01*
G01Y729951D02*
Y730738D01*
G01Y726801D02*
Y727588D01*
G01Y723651D02*
Y724439D01*
G01Y720502D02*
Y721289D01*
G01X1545138Y755148D02*
Y755935D01*
G01Y751998D02*
Y752785D01*
G01Y748848D02*
Y749636D01*
G01Y745699D02*
Y746486D01*
G01Y742549D02*
Y743337D01*
G01Y739400D02*
Y740187D01*
G01Y736250D02*
Y737037D01*
G01Y733100D02*
Y733888D01*
G01Y729951D02*
Y730738D01*
G01Y726801D02*
Y727588D01*
G01Y723651D02*
Y724439D01*
G01Y720502D02*
Y721289D01*
G01X1545062Y714301D02*
Y711545D01*
G01X1544197Y721289D02*
Y720502D01*
G01Y727588D02*
Y726801D01*
G01Y724439D02*
Y723651D01*
G01Y730738D02*
Y729951D01*
G01Y737037D02*
Y736250D01*
G01Y733888D02*
Y733100D01*
G01Y740187D02*
Y739400D01*
G01Y746486D02*
Y745699D01*
G01Y743337D02*
Y742549D01*
G01Y749636D02*
Y748848D01*
G01Y755935D02*
Y755148D01*
G01Y752785D02*
Y751998D01*
G01X1542605Y721289D02*
Y720502D01*
G01Y727588D02*
Y726801D01*
G01Y724439D02*
Y723651D01*
G01Y730738D02*
Y729951D01*
G01Y737037D02*
Y736250D01*
G01Y733888D02*
Y733100D01*
G01Y740187D02*
Y739400D01*
G01Y746486D02*
Y745699D01*
G01Y743337D02*
Y742549D01*
G01Y749636D02*
Y748848D01*
G01Y755935D02*
Y755148D01*
G01Y752785D02*
Y751998D01*
G01X1542457Y721289D02*
Y720502D01*
G01Y727588D02*
Y726801D01*
G01Y724439D02*
Y723651D01*
G01Y730738D02*
Y729951D01*
G01Y737037D02*
Y736250D01*
G01Y733888D02*
Y733100D01*
G01Y740187D02*
Y739400D01*
G01Y746486D02*
Y745699D01*
G01Y743337D02*
Y742549D01*
G01Y749636D02*
Y748848D01*
G01Y755935D02*
Y755148D01*
G01Y752785D02*
Y751998D01*
G01X1541519Y752785D02*
Y755148D01*
G01Y749636D02*
Y751998D01*
G01Y746486D02*
Y748848D01*
G01Y743337D02*
Y745699D01*
G01Y740187D02*
Y742549D01*
G01Y737037D02*
Y739400D01*
G01Y733888D02*
Y736250D01*
G01Y730738D02*
Y733100D01*
G01Y727588D02*
Y729951D01*
G01Y724439D02*
Y726801D01*
G01Y721289D02*
Y723651D01*
G01Y718829D02*
Y720502D01*
G01X1540303Y710354D02*
Y704601D01*
G01X1539791Y721289D02*
Y720502D01*
G01Y727588D02*
Y726801D01*
G01Y724439D02*
Y723651D01*
G01Y730738D02*
Y729951D01*
G01Y737037D02*
Y736250D01*
G01Y733888D02*
Y733100D01*
G01Y740187D02*
Y739400D01*
G01Y746486D02*
Y745699D01*
G01Y743337D02*
Y742549D01*
G01Y749636D02*
Y748848D01*
G01Y755935D02*
Y755148D01*
G01Y752785D02*
Y751998D01*
G01X1539110Y754498D02*
Y756073D01*
G01Y749498D02*
Y751073D01*
G01Y744498D02*
Y746073D01*
G01Y739498D02*
Y741073D01*
G01Y729498D02*
Y731073D01*
G01Y724498D02*
Y726073D01*
G01Y719498D02*
Y721073D01*
G01X1538843Y704601D02*
Y710354D01*
G01X1538139Y755148D02*
Y755935D01*
G01Y751998D02*
Y752785D01*
G01Y748848D02*
Y749636D01*
G01Y745699D02*
Y746486D01*
G01Y742549D02*
Y743337D01*
G01Y739400D02*
Y740187D01*
G01Y736250D02*
Y737037D01*
G01Y733100D02*
Y733888D01*
G01Y729951D02*
Y730738D01*
G01Y726801D02*
Y727588D01*
G01Y723651D02*
Y724439D01*
G01Y720502D02*
Y721289D01*
G01X1537188Y714301D02*
Y711545D01*
G01X1537142Y734498D02*
Y736073D01*
G01X1536549Y713848D02*
Y713907D01*
G01X1536156Y755148D02*
Y755935D01*
G01Y751998D02*
Y752785D01*
G01Y748848D02*
Y749636D01*
G01Y745699D02*
Y746486D01*
G01Y742549D02*
Y743337D01*
G01Y739400D02*
Y740187D01*
G01Y736250D02*
Y737037D01*
G01Y733100D02*
Y733888D01*
G01Y729951D02*
Y730738D01*
G01Y726801D02*
Y727588D01*
G01Y723651D02*
Y724439D01*
G01Y720502D02*
Y721289D01*
G01X1535961Y721073D02*
Y719498D01*
G01Y726073D02*
Y724498D01*
G01Y731073D02*
Y729498D01*
G01Y741073D02*
Y739498D01*
G01Y746073D02*
Y744498D01*
G01Y751073D02*
Y749498D01*
G01Y756073D02*
Y754498D01*
G01X1534976Y721860D02*
Y718711D01*
G01Y726860D02*
Y723711D01*
G01Y731860D02*
Y728711D01*
G01Y741860D02*
Y738711D01*
G01Y746860D02*
Y743711D01*
G01Y751860D02*
Y748711D01*
G01X1533992Y711545D02*
Y713848D01*
G01Y721860D02*
Y718711D01*
G01Y726860D02*
Y723711D01*
G01Y731860D02*
Y728711D01*
G01Y736073D02*
Y734498D01*
G01Y741860D02*
Y738711D01*
G01Y746860D02*
Y743711D01*
G01Y751860D02*
Y748711D01*
G01X1533043Y707530D02*
Y704601D01*
G01X1533008Y721073D02*
Y719498D01*
G01Y726073D02*
Y724498D01*
G01Y731073D02*
Y729498D01*
G01Y736860D02*
Y733711D01*
G01Y741073D02*
Y739498D01*
G01Y746073D02*
Y744498D01*
G01Y751073D02*
Y749498D01*
G01Y756073D02*
Y754498D01*
G01X1532793Y721289D02*
Y720502D01*
G01Y727588D02*
Y726801D01*
G01Y724439D02*
Y723651D01*
G01Y730738D02*
Y729951D01*
G01Y737037D02*
Y736250D01*
G01Y733888D02*
Y733100D01*
G01Y740187D02*
Y739400D01*
G01Y746486D02*
Y745699D01*
G01Y743337D02*
Y742549D01*
G01Y749636D02*
Y748848D01*
G01Y755935D02*
Y755148D01*
G01Y752785D02*
Y751998D01*
G01X1532417Y721289D02*
Y720502D01*
G01Y727588D02*
Y726801D01*
G01Y724439D02*
Y723651D01*
G01Y730738D02*
Y729951D01*
G01Y737037D02*
Y736250D01*
G01Y733888D02*
Y733100D01*
G01Y740187D02*
Y739400D01*
G01Y746486D02*
Y745699D01*
G01Y743337D02*
Y742549D01*
G01Y749636D02*
Y748848D01*
G01Y755935D02*
Y755148D01*
G01Y752785D02*
Y751998D01*
G01X1532391Y721289D02*
Y720502D01*
G01Y727588D02*
Y726801D01*
G01Y724439D02*
Y723651D01*
G01Y730738D02*
Y729951D01*
G01Y737037D02*
Y736250D01*
G01Y733888D02*
Y733100D01*
G01Y740187D02*
Y739400D01*
G01Y746486D02*
Y745699D01*
G01Y743337D02*
Y742549D01*
G01Y749636D02*
Y748848D01*
G01Y755935D02*
Y755148D01*
G01Y752785D02*
Y751998D01*
G01X1532024Y736860D02*
Y733711D01*
G01X1531651Y704601D02*
Y707125D01*
G01X1530220D02*
Y704601D01*
G01X1528761D02*
Y707125D01*
G01X1528087Y708947D02*
Y705167D01*
G01Y713317D02*
Y710915D01*
G01X1527333Y708607D02*
Y708051D01*
G01X1527330Y707125D02*
Y704601D01*
G01X1526433Y734183D02*
Y716663D01*
G01Y753081D02*
Y736545D01*
G01X1525890Y708607D02*
Y704601D01*
G01X1522181Y717254D02*
Y715482D01*
G01X1534976Y756270D02*
X1533992D01*
G01X1531945Y756073D02*
X1539110D01*
G01X1542605Y755935D02*
X1549937D01*
G01X1542457D02*
X1530449D01*
G01X1542457Y755148D02*
X1530449D01*
G01X1549937D02*
X1542605D01*
G01X1531945Y754498D02*
X1539110D01*
G01X1534976Y754301D02*
X1533992D01*
G01X1534976Y753907D02*
X1533992D01*
G01X1534976Y753711D02*
X1533992D01*
G01X1542605Y752785D02*
X1549937D01*
G01X1542457D02*
X1530449D01*
G01X1542457Y751998D02*
X1530449D01*
G01X1549937D02*
X1542605D01*
G01X1534976Y751860D02*
X1533992D01*
G01X1534976Y751663D02*
X1533992D01*
G01X1534976Y751270D02*
X1533992D01*
G01X1531945Y751073D02*
X1539110D01*
G01X1542605Y749636D02*
X1549937D01*
G01X1542457D02*
X1530449D01*
G01X1531945Y749498D02*
X1539110D01*
G01X1534976Y749301D02*
X1533992D01*
G01X1534976Y748907D02*
X1533992D01*
G01X1542457Y748848D02*
X1530449D01*
G01X1549937D02*
X1542605D01*
G01X1534976Y748711D02*
X1533992D01*
G01X1534976Y746860D02*
X1533992D01*
G01X1534976Y746663D02*
X1533992D01*
G01X1542605Y746486D02*
X1549937D01*
G01X1542457D02*
X1530449D01*
G01X1534976Y746270D02*
X1533992D01*
G01X1531945Y746073D02*
X1539110D01*
G01X1542457Y745699D02*
X1530449D01*
G01X1549937D02*
X1542605D01*
G01X1531945Y744498D02*
X1539110D01*
G01X1534976Y744301D02*
X1533992D01*
G01X1534976Y743907D02*
X1533992D01*
G01X1534976Y743711D02*
X1533992D01*
G01X1542605Y743337D02*
X1549937D01*
G01X1542457D02*
X1530449D01*
G01X1542457Y742549D02*
X1530449D01*
G01X1549937D02*
X1542605D01*
G01X1534976Y741860D02*
X1533992D01*
G01X1534976Y741663D02*
X1533992D01*
G01X1534976Y741270D02*
X1533992D01*
G01X1531945Y741073D02*
X1539110D01*
G01X1542605Y740187D02*
X1549937D01*
G01X1542457D02*
X1530449D01*
G01X1531945Y739498D02*
X1539110D01*
G01X1542457Y739400D02*
X1530449D01*
G01X1549937D02*
X1542605D01*
G01X1534976Y739301D02*
X1533992D01*
G01X1534976Y738907D02*
X1533992D01*
G01X1534976Y738711D02*
X1533992D01*
G01X1530449Y737490D02*
X1531551D01*
G01X1542605Y737037D02*
X1549937D01*
G01X1542457D02*
X1530449D01*
G01X1533008Y736860D02*
X1532024D01*
G01X1533008Y736663D02*
X1532024D01*
G01X1533008Y736270D02*
X1532024D01*
G01X1542457Y736250D02*
X1530449D01*
G01X1549937D02*
X1542605D01*
G01X1531551Y736073D02*
X1537142D01*
G01X1541261Y705266D02*
X1541279Y705210D01*
X1541331Y705044D01*
X1541410Y704786D01*
X1541506Y704458D01*
X1541611Y704085D01*
G01X1537353Y710699D02*
X1537335Y710755D01*
X1537283Y710920D01*
X1537204Y711179D01*
X1537108Y711506D01*
X1537003Y711880D01*
G01X1531551Y734498D02*
X1537142D01*
G01X1533008Y734301D02*
X1532024D01*
G01X1533008Y733907D02*
X1532024D01*
G01X1542605Y733888D02*
X1549937D01*
G01X1542457D02*
X1530449D01*
G01X1533008Y733711D02*
X1532024D01*
G01X1542457Y733100D02*
X1530449D01*
G01X1549937D02*
X1542605D01*
G01X1530449Y733081D02*
X1531551D01*
G01X1534976Y731860D02*
X1533992D01*
G01X1534976Y731663D02*
X1533992D01*
G01X1534976Y731270D02*
X1533992D01*
G01X1531945Y731073D02*
X1539110D01*
G01X1542605Y730738D02*
X1549937D01*
G01X1542457D02*
X1530449D01*
G01X1542457Y729951D02*
X1530449D01*
G01X1549937D02*
X1542605D01*
G01X1531945Y729498D02*
X1539110D01*
G01X1534976Y729301D02*
X1533992D01*
G01X1534976Y728907D02*
X1533992D01*
G01X1534976Y728711D02*
X1533992D01*
G01X1542605Y727588D02*
X1549937D01*
G01X1542457D02*
X1530449D01*
G01X1534976Y726860D02*
X1533992D01*
G01X1542457Y726801D02*
X1530449D01*
G01X1549937D02*
X1542605D01*
G01X1534976Y726663D02*
X1533992D01*
G01X1534976Y726270D02*
X1533992D01*
G01X1539110Y726073D02*
X1531945D01*
G01X1539110Y724498D02*
X1531945D01*
G01X1542605Y724439D02*
X1549937D01*
G01X1542457D02*
X1530449D01*
G01X1534976Y724301D02*
X1533992D01*
G01X1534976Y723907D02*
X1533992D01*
G01X1534976Y723711D02*
X1533992D01*
G01X1542457Y723651D02*
X1530449D01*
G01X1549937D02*
X1542605D01*
G01X1534976Y721860D02*
X1533992D01*
G01X1534976Y721663D02*
X1533992D01*
G01X1542605Y721289D02*
X1549937D01*
G01X1542457D02*
X1530449D01*
G01X1534976Y721270D02*
X1533992D01*
G01X1531945Y721073D02*
X1539110D01*
G01X1542457Y720502D02*
X1530449D01*
G01X1549937D02*
X1542605D01*
G01X1531945Y719498D02*
X1539110D01*
G01X1534976Y719301D02*
X1533992D01*
G01X1534976Y718907D02*
X1533992D01*
G01X1544551Y718829D02*
X1535567D01*
G01X1534976Y718711D02*
X1533992D01*
G01X1531551Y717254D02*
X1522181D01*
G01X1551709Y717077D02*
X1531551D01*
G01X1521866Y716663D02*
X1528401D01*
G01X1531551Y715482D02*
X1522181D01*
G01X1550916Y714301D02*
X1530449D01*
G01X1536549Y713907D02*
X1530449D01*
G01X1536549Y713848D02*
X1530449D01*
G01X1551709Y713317D02*
X1528087D01*
G01X1541611Y711880D02*
X1537003D01*
G01X1551709Y710915D02*
X1528087D01*
G01X1537353Y710699D02*
X1541261D01*
G01X1540303Y710354D02*
X1538843D01*
G01X1551709Y708947D02*
X1528087D01*
G01X1527333Y708607D02*
X1525890D01*
G01X1549942D02*
X1548560D01*
G01X1547265D02*
X1545648D01*
G01X1543875Y707025D02*
X1542450D01*
G01X1545448Y706200D02*
X1542449D01*
G01X1545318Y705756D02*
X1543814D01*
G01X1541261Y705266D02*
X1537353D01*
G01X1551709Y705167D02*
X1528087D01*
G01X1527330Y704601D02*
X1525890D01*
G01X1530220D02*
X1528761D01*
G01X1533043D02*
X1531651D01*
G01X1540303D02*
X1538843D01*
G01X1549968D02*
X1548419D01*
G01X1546882D02*
X1545474D01*
G01X1537003Y704085D02*
X1541611D01*
G01X1547673Y705878D02*
X1548419Y704601D01*
G01X1548647Y706756D02*
X1549968Y704601D01*
G01X1547265Y708607D02*
X1547870Y707621D01*
G01X1545648Y708607D02*
X1546917Y706747D01*
G01X1502036Y776073D02*
X1501896Y775877D01*
X1501758Y775680D01*
X1501621Y775482D01*
G01X1506239D02*
X1506161Y776073D01*
G01X1507781D02*
X1502036D01*
G01X1508207Y775482D02*
X1501621D01*
G01X1507091Y776073D02*
X1507364Y775482D01*
G01X1507781Y776073D02*
X1508207Y775482D01*
G01X1508572Y799242D02*
X1508610Y799268D01*
X1508638Y799341D01*
X1508648Y799439D01*
G01X1508572Y814990D02*
X1508610Y815016D01*
X1508638Y815089D01*
X1508648Y815187D01*
G01X1508572Y818140D02*
X1508610Y818166D01*
X1508638Y818238D01*
X1508648Y818337D01*
G01X1508572Y827588D02*
X1508610Y827615D01*
X1508638Y827687D01*
X1508648Y827785D01*
G01X1508572Y830738D02*
X1508610Y830765D01*
X1508638Y830837D01*
X1508648Y830935D01*
G01X1508572Y833888D02*
X1508610Y833914D01*
X1508638Y833986D01*
X1508648Y834085D01*
G01X1508572Y843337D02*
X1508610Y843363D01*
X1508638Y843435D01*
X1508648Y843533D01*
G01X1499740Y791053D02*
X1501709Y793022D01*
G01X1509749Y779498D02*
X1510176Y780088D01*
G01X1509749Y784498D02*
X1510176Y785088D01*
G01X1509749Y819498D02*
X1510176Y820088D01*
G01X1509749Y824498D02*
X1510176Y825088D01*
G01X1509749Y829498D02*
X1510176Y830088D01*
G01X1509749Y834498D02*
X1510176Y835088D01*
G01X1509749Y839498D02*
X1510176Y840088D01*
G01X1509749Y844498D02*
X1510176Y845088D01*
G01X1509817Y789498D02*
X1510241Y790088D01*
G01X1509817Y814498D02*
X1510241Y815088D01*
G01X1504004Y781073D02*
X1503865Y780877D01*
X1503727Y780680D01*
X1503590Y780482D01*
G01X1504004Y786073D02*
X1503865Y785877D01*
X1503727Y785680D01*
X1503590Y785482D01*
G01X1504004Y821073D02*
X1503865Y820877D01*
X1503727Y820680D01*
X1503590Y820482D01*
G01X1504004Y826073D02*
X1503865Y825877D01*
X1503727Y825680D01*
X1503590Y825482D01*
G01X1504004Y831073D02*
X1503865Y830877D01*
X1503727Y830680D01*
X1503590Y830482D01*
G01X1504004Y836073D02*
X1503865Y835877D01*
X1503727Y835680D01*
X1503590Y835482D01*
G01X1504004Y841073D02*
X1503865Y840877D01*
X1503727Y840680D01*
X1503590Y840482D01*
G01X1504004Y846073D02*
X1503865Y845877D01*
X1503727Y845680D01*
X1503590Y845482D01*
G01X1503904Y791073D02*
X1503768Y790877D01*
X1503633Y790680D01*
X1503499Y790482D01*
G01X1503904Y816073D02*
X1503768Y815877D01*
X1503633Y815680D01*
X1503499Y815482D01*
G01X1509332Y780088D02*
X1509060Y779498D01*
G01X1509332Y785088D02*
X1509060Y784498D01*
G01X1509332Y790088D02*
X1509060Y789498D01*
G01X1509332Y815088D02*
X1509060Y814498D01*
G01X1509332Y820088D02*
X1509060Y819498D01*
G01X1509332Y825088D02*
X1509060Y824498D01*
G01X1509332Y830088D02*
X1509060Y829498D01*
G01X1509332Y835088D02*
X1509060Y834498D01*
G01X1509332Y840088D02*
X1509060Y839498D01*
G01X1509332Y845088D02*
X1509060Y844498D01*
G01X1509023Y843337D02*
X1509050Y843340D01*
X1509075Y843351D01*
X1509099Y843369D01*
X1509121Y843394D01*
X1509138Y843424D01*
X1509150Y843458D01*
X1509158Y843494D01*
X1509161Y843533D01*
G01X1509023Y840187D02*
X1509050Y840191D01*
X1509075Y840202D01*
X1509099Y840220D01*
X1509121Y840245D01*
X1509138Y840274D01*
X1509150Y840308D01*
X1509158Y840345D01*
X1509161Y840384D01*
G01X1509023Y837037D02*
X1509050Y837041D01*
X1509075Y837052D01*
X1509099Y837070D01*
X1509121Y837095D01*
X1509138Y837125D01*
X1509150Y837159D01*
X1509158Y837195D01*
X1509161Y837234D01*
G01X1509023Y833888D02*
X1509050Y833891D01*
X1509075Y833903D01*
X1509099Y833921D01*
X1509121Y833945D01*
X1509138Y833975D01*
X1509150Y834009D01*
X1509158Y834046D01*
X1509161Y834085D01*
G01X1509023Y830738D02*
X1509050Y830742D01*
X1509075Y830753D01*
X1509099Y830771D01*
X1509121Y830796D01*
X1509138Y830825D01*
X1509150Y830859D01*
X1509158Y830896D01*
X1509161Y830935D01*
G01X1509023Y827588D02*
X1509050Y827592D01*
X1509075Y827603D01*
X1509099Y827621D01*
X1509121Y827646D01*
X1509138Y827676D01*
X1509150Y827710D01*
X1509158Y827746D01*
X1509161Y827785D01*
G01X1509023Y824439D02*
X1509050Y824443D01*
X1509075Y824454D01*
X1509099Y824472D01*
X1509121Y824497D01*
X1509138Y824526D01*
X1509150Y824560D01*
X1509158Y824597D01*
X1509161Y824636D01*
G01X1503964Y811346D02*
X1503838Y811319D01*
X1503748Y811246D01*
X1503717Y811149D01*
G01X1503964Y808197D02*
X1503838Y808169D01*
X1503748Y808097D01*
X1503717Y808000D01*
G01X1503964Y805047D02*
X1503838Y805020D01*
X1503748Y804947D01*
X1503717Y804850D01*
G01X1503964Y801897D02*
X1503838Y801870D01*
X1503748Y801797D01*
X1503717Y801701D01*
G01X1503964Y798748D02*
X1503838Y798720D01*
X1503748Y798648D01*
X1503717Y798551D01*
G01X1503964Y795598D02*
X1503838Y795571D01*
X1503748Y795498D01*
X1503717Y795401D01*
G01X1503974Y844124D02*
X1503846Y844096D01*
X1503758Y844023D01*
X1503727Y843927D01*
G01X1503974Y840974D02*
X1503846Y840947D01*
X1503758Y840874D01*
X1503727Y840777D01*
G01X1503974Y837825D02*
X1503846Y837797D01*
X1503758Y837724D01*
X1503727Y837628D01*
G01X1503974Y834675D02*
X1503846Y834647D01*
X1503758Y834574D01*
X1503727Y834478D01*
G01X1503974Y831525D02*
X1503846Y831498D01*
X1503758Y831425D01*
X1503727Y831329D01*
G01X1503974Y828376D02*
X1503846Y828348D01*
X1503758Y828275D01*
X1503727Y828179D01*
G01X1503974Y825226D02*
X1503846Y825199D01*
X1503758Y825126D01*
X1503727Y825029D01*
G01X1503974Y822077D02*
X1503846Y822049D01*
X1503758Y821976D01*
X1503727Y821880D01*
G01X1503974Y818927D02*
X1503846Y818899D01*
X1503758Y818826D01*
X1503727Y818730D01*
G01X1503974Y815777D02*
X1503846Y815750D01*
X1503758Y815677D01*
X1503727Y815581D01*
G01X1503974Y812628D02*
X1503846Y812600D01*
X1503758Y812527D01*
X1503727Y812431D01*
G01X1503974Y809478D02*
X1503846Y809451D01*
X1503758Y809378D01*
X1503727Y809281D01*
G01X1503974Y806329D02*
X1503846Y806301D01*
X1503758Y806228D01*
X1503727Y806132D01*
G01X1503974Y803179D02*
X1503846Y803151D01*
X1503758Y803078D01*
X1503727Y802982D01*
G01X1503974Y800029D02*
X1503846Y800002D01*
X1503758Y799929D01*
X1503727Y799833D01*
G01X1503974Y796880D02*
X1503846Y796852D01*
X1503758Y796779D01*
X1503727Y796683D01*
G01X1503974Y793730D02*
X1503846Y793702D01*
X1503758Y793630D01*
X1503727Y793533D01*
G01X1503974Y790581D02*
X1503846Y790553D01*
X1503758Y790480D01*
X1503727Y790384D01*
G01X1503974Y787431D02*
X1503846Y787403D01*
X1503758Y787330D01*
X1503727Y787234D01*
G01X1503974Y784281D02*
X1503846Y784254D01*
X1503758Y784181D01*
X1503727Y784085D01*
G01X1503974Y781132D02*
X1503846Y781104D01*
X1503758Y781031D01*
X1503727Y780935D01*
G01X1509749Y846073D02*
X1504004D01*
G01X1510176Y845482D02*
X1503590D01*
G01Y845088D02*
X1510176D01*
G01X1504004Y844498D02*
X1509749D01*
G01X1503974Y844124D02*
X1510058D01*
G01X1503727Y843927D02*
X1510338D01*
G01Y843533D02*
X1503727D01*
G01X1503974Y843337D02*
X1510058D01*
G01X1509749Y841073D02*
X1504004D01*
G01X1503974Y840974D02*
X1510058D01*
G01X1503727Y840777D02*
X1510338D01*
G01X1510176Y840482D02*
X1503590D01*
G01X1510338Y840384D02*
X1503727D01*
G01X1503974Y840187D02*
X1510058D01*
G01X1503590Y840088D02*
X1510176D01*
G01X1504004Y839498D02*
X1509749D01*
G01X1503974Y837825D02*
X1510058D01*
G01X1503727Y837628D02*
X1510338D01*
G01Y837234D02*
X1503727D01*
G01X1503974Y837037D02*
X1510058D01*
G01X1509749Y836073D02*
X1504004D01*
G01X1510176Y835482D02*
X1503590D01*
G01Y835088D02*
X1510176D01*
G01X1503974Y834675D02*
X1510058D01*
G01X1504004Y834498D02*
X1509749D01*
G01X1503727Y834478D02*
X1510338D01*
G01Y834085D02*
X1503727D01*
G01X1503974Y833888D02*
X1510058D01*
G01X1501709Y832490D02*
X1528401D01*
G01X1503974Y831525D02*
X1510058D01*
G01X1503727Y831329D02*
X1510338D01*
G01X1509749Y831073D02*
X1504004D01*
G01X1510338Y830935D02*
X1503727D01*
G01X1503974Y830738D02*
X1510058D01*
G01X1510176Y830482D02*
X1503590D01*
G01X1528401Y830128D02*
X1501709D01*
G01X1503590Y830088D02*
X1510176D01*
G01X1504004Y829498D02*
X1509749D01*
G01X1503974Y828376D02*
X1510058D01*
G01X1503727Y828179D02*
X1510338D01*
G01Y827785D02*
X1503727D01*
G01X1503974Y827588D02*
X1510058D01*
G01X1509749Y826073D02*
X1504004D01*
G01X1510176Y825482D02*
X1503590D01*
G01X1503974Y825226D02*
X1510058D01*
G01X1503590Y825088D02*
X1510176D01*
G01X1503727Y825029D02*
X1510338D01*
G01Y824636D02*
X1503727D01*
G01X1504004Y824498D02*
X1509749D01*
G01X1503974Y824439D02*
X1510058D01*
G01X1503974Y822077D02*
X1510058D01*
G01X1503727Y821880D02*
X1510338D01*
G01Y821486D02*
X1503727D01*
G01X1503974Y821289D02*
X1510058D01*
G01X1509749Y821073D02*
X1504004D01*
G01X1510176Y820482D02*
X1503590D01*
G01Y820088D02*
X1510176D01*
G01X1504004Y819498D02*
X1509749D01*
G01X1503974Y818927D02*
X1510058D01*
G01X1520212Y818888D02*
X1500751D01*
G01X1503727Y818730D02*
X1510338D01*
G01Y818337D02*
X1503727D01*
G01X1503974Y818140D02*
X1510058D01*
G01X1509817Y816073D02*
X1503904D01*
G01X1503974Y815777D02*
X1510058D01*
G01X1503727Y815581D02*
X1510338D01*
G01X1510241Y815482D02*
X1503499D01*
G01X1510338Y815187D02*
X1503727D01*
G01X1503499Y815088D02*
X1510241D01*
G01X1503974Y814990D02*
X1510058D01*
G01X1501709Y814892D02*
X1528401D01*
G01X1509817Y814498D02*
X1503904D01*
G01X1499740Y813711D02*
X1506209D01*
G01X1503974Y812628D02*
X1510058D01*
G01X1520212Y812549D02*
X1501709D01*
G01X1528401Y812529D02*
X1506209D01*
G01X1509023Y821289D02*
X1509050Y821293D01*
X1509075Y821304D01*
X1509099Y821322D01*
X1509121Y821347D01*
X1509138Y821377D01*
X1509150Y821410D01*
X1509158Y821447D01*
X1509161Y821486D01*
G01X1509023Y818140D02*
X1509050Y818143D01*
X1509075Y818155D01*
X1509099Y818173D01*
X1509121Y818197D01*
X1509138Y818227D01*
X1509150Y818261D01*
X1509158Y818298D01*
X1509161Y818337D01*
G01X1509023Y814990D02*
X1509050Y814994D01*
X1509075Y815005D01*
X1509099Y815023D01*
X1509121Y815048D01*
X1509138Y815077D01*
X1509150Y815111D01*
X1509158Y815148D01*
X1509161Y815187D01*
G01X1509023Y811840D02*
X1509050Y811844D01*
X1509075Y811855D01*
X1509099Y811873D01*
X1509121Y811898D01*
X1509138Y811928D01*
X1509150Y811962D01*
X1509158Y811998D01*
X1509161Y812037D01*
G01X1509023Y808691D02*
X1509050Y808695D01*
X1509075Y808706D01*
X1509099Y808724D01*
X1509121Y808749D01*
X1509138Y808778D01*
X1509150Y808812D01*
X1509158Y808849D01*
X1509161Y808888D01*
G01X1509023Y805541D02*
X1509050Y805545D01*
X1509075Y805556D01*
X1509099Y805574D01*
X1509121Y805599D01*
X1509138Y805629D01*
X1509150Y805662D01*
X1509158Y805699D01*
X1509161Y805738D01*
G01X1509023Y802392D02*
X1509050Y802395D01*
X1509075Y802406D01*
X1509099Y802425D01*
X1509121Y802449D01*
X1509138Y802479D01*
X1509150Y802513D01*
X1509158Y802550D01*
X1509161Y802588D01*
G01X1509023Y799242D02*
X1509050Y799246D01*
X1509075Y799257D01*
X1509099Y799275D01*
X1509121Y799300D01*
X1509138Y799329D01*
X1509150Y799363D01*
X1509158Y799400D01*
X1509161Y799439D01*
G01X1509023Y796092D02*
X1509050Y796096D01*
X1509075Y796107D01*
X1509099Y796125D01*
X1509121Y796150D01*
X1509138Y796180D01*
X1509150Y796214D01*
X1509158Y796250D01*
X1509161Y796289D01*
G01X1509023Y792943D02*
X1509050Y792947D01*
X1509075Y792958D01*
X1509099Y792976D01*
X1509121Y793000D01*
X1509138Y793030D01*
X1509150Y793064D01*
X1509158Y793101D01*
X1509161Y793140D01*
G01X1509023Y789793D02*
X1509050Y789797D01*
X1509075Y789808D01*
X1509099Y789826D01*
X1509121Y789851D01*
X1509138Y789881D01*
X1509150Y789914D01*
X1509158Y789951D01*
X1509161Y789990D01*
G01X1509023Y786644D02*
X1509050Y786647D01*
X1509075Y786658D01*
X1509099Y786677D01*
X1509121Y786701D01*
X1509138Y786731D01*
X1509150Y786765D01*
X1509158Y786802D01*
X1509161Y786840D01*
G01X1509023Y783494D02*
X1509050Y783498D01*
X1509075Y783509D01*
X1509099Y783527D01*
X1509121Y783552D01*
X1509138Y783581D01*
X1509150Y783615D01*
X1509158Y783652D01*
X1509161Y783691D01*
G01X1509023Y780344D02*
X1509050Y780348D01*
X1509075Y780359D01*
X1509099Y780377D01*
X1509121Y780402D01*
X1509138Y780432D01*
X1509150Y780466D01*
X1509158Y780502D01*
X1509161Y780541D01*
G01X1509023Y777195D02*
X1509050Y777199D01*
X1509075Y777210D01*
X1509099Y777228D01*
X1509121Y777252D01*
X1509138Y777282D01*
X1509150Y777316D01*
X1509158Y777353D01*
X1509161Y777392D01*
G01X1503974Y777982D02*
X1503846Y777954D01*
X1503758Y777882D01*
X1503727Y777785D01*
G01X1508208Y780088D02*
X1508130Y779498D01*
G01X1508208Y785088D02*
X1508130Y784498D01*
G01X1508208Y790088D02*
X1508130Y789498D01*
G01X1508208Y815088D02*
X1508130Y814498D01*
G01X1508208Y820088D02*
X1508130Y819498D01*
G01X1508208Y825088D02*
X1508130Y824498D01*
G01X1508208Y830088D02*
X1508130Y829498D01*
G01X1508208Y835088D02*
X1508130Y834498D01*
G01X1508208Y840088D02*
X1508130Y839498D01*
G01X1508208Y845088D02*
X1508130Y844498D01*
G01X1508648Y777392D02*
X1508638Y777293D01*
X1508610Y777221D01*
X1508572Y777195D01*
G01X1508648Y780541D02*
X1508638Y780443D01*
X1508610Y780371D01*
X1508572Y780344D01*
G01X1508648Y783691D02*
X1508638Y783593D01*
X1508610Y783520D01*
X1508572Y783494D01*
G01X1508648Y786840D02*
X1508638Y786742D01*
X1508610Y786670D01*
X1508572Y786644D01*
G01X1508648Y789990D02*
X1508638Y789892D01*
X1508610Y789820D01*
X1508572Y789793D01*
G01X1508648Y793140D02*
X1508638Y793041D01*
X1508610Y792969D01*
X1508572Y792943D01*
G01X1508648Y796289D02*
X1508638Y796191D01*
X1508610Y796119D01*
X1508572Y796092D01*
G01X1508648Y802588D02*
X1508638Y802490D01*
X1508610Y802418D01*
X1508572Y802392D01*
G01X1508648Y805738D02*
X1508638Y805640D01*
X1508610Y805568D01*
X1508572Y805541D01*
G01X1508648Y808888D02*
X1508638Y808789D01*
X1508610Y808717D01*
X1508572Y808691D01*
G01X1508648Y812037D02*
X1508638Y811939D01*
X1508610Y811867D01*
X1508572Y811840D01*
G01X1508648Y821486D02*
X1508638Y821388D01*
X1508610Y821316D01*
X1508572Y821289D01*
G01X1508648Y824636D02*
X1508638Y824537D01*
X1508610Y824465D01*
X1508572Y824439D01*
G01X1508648Y837234D02*
X1508638Y837136D01*
X1508610Y837064D01*
X1508572Y837037D01*
G01X1508648Y840384D02*
X1508638Y840285D01*
X1508610Y840213D01*
X1508572Y840187D01*
G01X1509093Y794417D02*
X1509090Y794379D01*
X1509081Y794342D01*
X1509068Y794308D01*
X1509049Y794278D01*
X1509027Y794253D01*
X1509002Y794235D01*
X1508974Y794224D01*
X1508945Y794220D01*
G01X1509093Y797567D02*
X1509090Y797528D01*
X1509081Y797492D01*
X1509068Y797458D01*
X1509049Y797427D01*
X1509027Y797403D01*
X1509002Y797385D01*
X1508974Y797374D01*
X1508945Y797370D01*
G01X1509093Y800716D02*
X1509090Y800678D01*
X1509081Y800641D01*
X1509068Y800607D01*
X1509049Y800577D01*
X1509027Y800553D01*
X1509002Y800535D01*
X1508974Y800523D01*
X1508945Y800519D01*
G01X1509093Y803866D02*
X1509090Y803828D01*
X1509081Y803791D01*
X1509068Y803757D01*
X1509049Y803727D01*
X1509027Y803702D01*
X1509002Y803684D01*
X1508974Y803673D01*
X1508945Y803669D01*
G01X1509093Y807015D02*
X1509090Y806977D01*
X1509081Y806940D01*
X1509068Y806907D01*
X1509049Y806876D01*
X1509027Y806852D01*
X1509002Y806834D01*
X1508974Y806823D01*
X1508945Y806819D01*
G01X1509093Y810165D02*
X1509090Y810127D01*
X1509081Y810090D01*
X1509068Y810056D01*
X1509049Y810026D01*
X1509027Y810001D01*
X1509002Y809983D01*
X1508974Y809972D01*
X1508945Y809968D01*
G01X1508208Y845482D02*
X1508130Y846073D01*
G01X1508208Y840482D02*
X1508130Y841073D01*
G01X1508208Y835482D02*
X1508130Y836073D01*
G01X1508208Y830482D02*
X1508130Y831073D01*
G01X1508208Y825482D02*
X1508130Y826073D01*
G01X1508208Y820482D02*
X1508130Y821073D01*
G01X1508208Y815482D02*
X1508130Y816073D01*
G01X1508208Y790482D02*
X1508130Y791073D01*
G01X1508208Y785482D02*
X1508130Y786073D01*
G01X1508208Y780482D02*
X1508130Y781073D01*
G01X1508945Y811346D02*
X1508974Y811342D01*
X1509001Y811331D01*
X1509027Y811313D01*
X1509049Y811289D01*
X1509068Y811259D01*
X1509081Y811225D01*
X1509090Y811188D01*
X1509093Y811149D01*
G01X1508945Y808197D02*
X1508974Y808193D01*
X1509001Y808182D01*
X1509027Y808164D01*
X1509049Y808139D01*
X1509068Y808109D01*
X1509081Y808075D01*
X1509090Y808039D01*
X1509093Y808000D01*
G01X1508945Y805047D02*
X1508974Y805043D01*
X1509001Y805032D01*
X1509027Y805014D01*
X1509049Y804989D01*
X1509068Y804960D01*
X1509081Y804926D01*
X1509090Y804889D01*
X1509093Y804850D01*
G01X1508945Y801897D02*
X1508974Y801894D01*
X1509001Y801883D01*
X1509027Y801864D01*
X1509049Y801840D01*
X1509068Y801810D01*
X1509081Y801776D01*
X1509090Y801739D01*
X1509093Y801701D01*
G01X1508945Y798748D02*
X1508974Y798744D01*
X1509001Y798733D01*
X1509027Y798715D01*
X1509049Y798690D01*
X1509068Y798660D01*
X1509081Y798627D01*
X1509090Y798590D01*
X1509093Y798551D01*
G01X1508945Y795598D02*
X1508974Y795594D01*
X1509001Y795583D01*
X1509027Y795565D01*
X1509049Y795540D01*
X1509068Y795511D01*
X1509081Y795477D01*
X1509090Y795440D01*
X1509093Y795401D01*
G01X1503727Y812431D02*
X1510338D01*
G01Y812037D02*
X1503727D01*
G01X1503974Y811840D02*
X1510058D01*
G01X1509772Y811346D02*
X1503964D01*
G01X1510035Y811149D02*
X1503717D01*
G01Y810165D02*
X1510035D01*
G01X1509772Y809968D02*
X1503964D01*
G01X1503974Y809478D02*
X1510058D01*
G01X1503727Y809281D02*
X1510338D01*
G01Y808888D02*
X1503727D01*
G01X1503974Y808691D02*
X1510058D01*
G01X1509772Y808197D02*
X1503964D01*
G01X1510035Y808000D02*
X1503717D01*
G01Y807015D02*
X1510035D01*
G01X1509772Y806819D02*
X1503964D01*
G01X1503974Y806329D02*
X1510058D01*
G01X1503727Y806132D02*
X1510338D01*
G01Y805738D02*
X1503727D01*
G01X1503974Y805541D02*
X1510058D01*
G01X1509772Y805047D02*
X1503964D01*
G01X1510035Y804850D02*
X1503717D01*
G01Y803866D02*
X1510035D01*
G01X1509772Y803669D02*
X1503964D01*
G01X1503974Y803179D02*
X1510058D01*
G01X1503727Y802982D02*
X1510338D01*
G01Y802588D02*
X1503727D01*
G01X1503974Y802392D02*
X1510058D01*
G01X1509772Y801897D02*
X1503964D01*
G01X1510035Y801701D02*
X1503717D01*
G01Y800716D02*
X1510035D01*
G01X1509772Y800519D02*
X1503964D01*
G01X1503974Y800029D02*
X1510058D01*
G01X1503727Y799833D02*
X1510338D01*
G01Y799439D02*
X1503727D01*
G01X1503974Y799242D02*
X1510058D01*
G01X1509772Y798748D02*
X1503964D01*
G01X1510035Y798551D02*
X1503717D01*
G01Y797567D02*
X1510035D01*
G01X1509772Y797370D02*
X1503964D01*
G01X1503974Y796880D02*
X1510058D01*
G01X1503727Y796683D02*
X1510338D01*
G01Y796289D02*
X1503727D01*
G01X1503974Y796092D02*
X1510058D01*
G01X1509772Y795598D02*
X1503964D01*
G01X1510035Y795401D02*
X1503717D01*
G01Y794417D02*
X1510035D01*
G01X1509772Y794220D02*
X1503964D01*
G01X1503974Y793730D02*
X1510058D01*
G01X1503727Y793533D02*
X1510338D01*
G01Y793140D02*
X1503727D01*
G01X1506209Y793041D02*
X1528401D01*
G01X1520212Y793022D02*
X1501709D01*
G01X1503974Y792943D02*
X1510058D01*
G01X1506209Y791860D02*
X1499740D01*
G01X1509817Y791073D02*
X1503904D01*
G01X1528401Y790679D02*
X1501709D01*
G01X1503974Y790581D02*
X1510058D01*
G01X1510241Y790482D02*
X1503499D01*
G01X1503727Y790384D02*
X1510338D01*
G01X1503499Y790088D02*
X1510241D01*
G01X1510338Y789990D02*
X1503727D01*
G01X1503974Y789793D02*
X1510058D01*
G01X1509817Y789498D02*
X1503904D01*
G01X1503974Y787431D02*
X1510058D01*
G01X1503727Y787234D02*
X1510338D01*
G01Y786840D02*
X1503727D01*
G01X1503974Y786644D02*
X1510058D01*
G01X1500751Y786585D02*
X1520212D01*
G01X1509749Y786073D02*
X1504004D01*
G01X1510176Y785482D02*
X1503590D01*
G01Y785088D02*
X1510176D01*
G01X1504004Y784498D02*
X1509749D01*
G01X1503974Y784281D02*
X1510058D01*
G01X1503727Y784085D02*
X1510338D01*
G01Y783691D02*
X1503727D01*
G01X1503974Y783494D02*
X1510058D01*
G01X1503974Y781132D02*
X1510058D01*
G01X1509749Y781073D02*
X1504004D01*
G01X1503727Y780935D02*
X1510338D01*
G01Y780541D02*
X1503727D01*
G01X1510176Y780482D02*
X1503590D01*
G01X1503974Y780344D02*
X1510058D01*
G01X1503590Y780088D02*
X1510176D01*
G01X1504004Y779498D02*
X1509749D01*
G01X1503974Y777982D02*
X1510058D01*
G01X1503727Y777785D02*
X1510338D01*
G01Y777392D02*
X1503727D01*
G01X1503974Y777195D02*
X1510058D01*
G01X1507941Y794417D02*
X1507940Y794379D01*
X1507938Y794342D01*
X1507935Y794308D01*
X1507931Y794278D01*
X1507926Y794253D01*
X1507921Y794235D01*
X1507915Y794224D01*
X1507908Y794220D01*
G01X1507941Y797567D02*
X1507940Y797528D01*
X1507938Y797492D01*
X1507935Y797458D01*
X1507931Y797427D01*
X1507926Y797403D01*
X1507921Y797385D01*
X1507915Y797374D01*
X1507908Y797370D01*
G01X1507941Y800716D02*
X1507940Y800678D01*
X1507938Y800641D01*
X1507935Y800607D01*
X1507931Y800577D01*
X1507926Y800553D01*
X1507921Y800535D01*
X1507915Y800523D01*
X1507908Y800519D01*
G01X1507941Y803866D02*
X1507940Y803828D01*
X1507938Y803791D01*
X1507935Y803757D01*
X1507931Y803727D01*
X1507926Y803702D01*
X1507921Y803684D01*
X1507915Y803673D01*
X1507908Y803669D01*
G01X1507941Y807015D02*
X1507940Y806977D01*
X1507938Y806940D01*
X1507935Y806907D01*
X1507931Y806876D01*
X1507926Y806852D01*
X1507921Y806834D01*
X1507915Y806823D01*
X1507908Y806819D01*
G01X1507941Y810165D02*
X1507940Y810127D01*
X1507938Y810090D01*
X1507935Y810056D01*
X1507931Y810026D01*
X1507926Y810001D01*
X1507921Y809983D01*
X1507915Y809972D01*
X1507908Y809968D01*
G01X1510338Y843533D02*
Y843927D01*
G01Y840384D02*
Y840777D01*
G01Y837234D02*
Y837628D01*
G01Y834085D02*
Y834478D01*
G01Y830935D02*
Y831329D01*
G01Y827785D02*
Y828179D01*
G01Y824636D02*
Y825029D01*
G01Y821486D02*
Y821880D01*
G01Y818337D02*
Y818730D01*
G01Y815187D02*
Y815581D01*
G01Y808888D02*
Y809281D01*
G01Y812037D02*
Y812431D01*
G01Y805738D02*
Y806132D01*
G01Y799439D02*
Y799833D01*
G01Y802588D02*
Y802982D01*
G01Y796289D02*
Y796683D01*
G01Y793140D02*
Y793533D01*
G01Y789990D02*
Y790384D01*
G01Y786840D02*
Y787234D01*
G01Y783691D02*
Y784085D01*
G01Y780541D02*
Y780935D01*
G01Y777392D02*
Y777785D01*
G01X1510241Y790482D02*
Y790088D01*
G01Y815482D02*
Y815088D01*
G01X1510176Y780482D02*
Y780088D01*
G01Y785482D02*
Y785088D01*
G01Y820482D02*
Y820088D01*
G01Y825482D02*
Y825088D01*
G01Y830482D02*
Y830088D01*
G01Y835482D02*
Y835088D01*
G01Y840482D02*
Y840088D01*
G01Y845482D02*
Y845088D01*
G01X1510035Y798551D02*
Y797567D01*
G01Y795401D02*
Y794417D01*
G01Y801701D02*
Y800716D01*
G01Y804850D02*
Y803866D01*
G01Y808000D02*
Y807015D01*
G01Y811149D02*
Y810165D01*
G01X1509332Y780482D02*
Y780088D01*
G01Y785482D02*
Y785088D01*
G01Y790482D02*
Y790088D01*
G01Y815482D02*
Y815088D01*
G01Y820482D02*
Y820088D01*
G01Y825482D02*
Y825088D01*
G01Y830482D02*
Y830088D01*
G01Y835482D02*
Y835088D01*
G01Y840482D02*
Y840088D01*
G01Y845482D02*
Y845088D01*
G01X1509161Y843533D02*
Y843927D01*
G01Y840384D02*
Y840777D01*
G01Y837234D02*
Y837628D01*
G01Y834085D02*
Y834478D01*
G01Y830935D02*
Y831329D01*
G01Y827785D02*
Y828179D01*
G01Y824636D02*
Y825029D01*
G01Y821486D02*
Y821880D01*
G01Y818337D02*
Y818730D01*
G01Y815187D02*
Y815581D01*
G01Y808888D02*
Y809281D01*
G01Y812037D02*
Y812431D01*
G01Y805738D02*
Y806132D01*
G01Y799439D02*
Y799833D01*
G01Y802588D02*
Y802982D01*
G01Y796289D02*
Y796683D01*
G01Y793140D02*
Y793533D01*
G01Y789990D02*
Y790384D01*
G01Y786840D02*
Y787234D01*
G01Y783691D02*
Y784085D01*
G01Y780541D02*
Y780935D01*
G01Y777392D02*
Y777785D01*
G01X1509093Y798551D02*
Y797567D01*
G01Y795401D02*
Y794417D01*
G01Y801701D02*
Y800716D01*
G01Y804850D02*
Y803866D01*
G01Y808000D02*
Y807015D01*
G01Y811149D02*
Y810165D01*
G01X1508648Y777785D02*
Y777392D01*
G01Y784085D02*
Y783691D01*
G01Y780935D02*
Y780541D01*
G01Y787234D02*
Y786840D01*
G01Y793533D02*
Y793140D01*
G01Y790384D02*
Y789990D01*
G01Y796683D02*
Y796289D01*
G01Y799833D02*
Y799439D01*
G01Y802982D02*
Y802588D01*
G01Y806132D02*
Y805738D01*
G01Y809281D02*
Y808888D01*
G01Y812431D02*
Y812037D01*
G01Y815581D02*
Y815187D01*
G01Y821880D02*
Y821486D01*
G01Y818730D02*
Y818337D01*
G01Y825029D02*
Y824636D01*
G01Y831329D02*
Y830935D01*
G01Y828179D02*
Y827785D01*
G01Y834478D02*
Y834085D01*
G01Y840777D02*
Y840384D01*
G01Y837628D02*
Y837234D01*
G01Y843927D02*
Y843533D01*
G01X1508208Y845088D02*
Y845482D01*
G01Y840088D02*
Y840482D01*
G01Y835088D02*
Y835482D01*
G01Y830088D02*
Y830482D01*
G01Y825088D02*
Y825482D01*
G01Y820088D02*
Y820482D01*
G01Y815088D02*
Y815482D01*
G01Y790088D02*
Y790482D01*
G01Y785088D02*
Y785482D01*
G01Y780088D02*
Y780482D01*
G01X1507941Y798551D02*
Y797567D01*
G01Y795401D02*
Y794417D01*
G01Y801701D02*
Y800716D01*
G01Y804850D02*
Y803866D01*
G01Y808000D02*
Y807015D01*
G01Y811149D02*
Y810165D01*
G01X1506209Y812529D02*
Y813711D01*
G01Y791860D02*
Y793041D01*
G01X1503727Y777785D02*
Y777392D01*
G01Y784085D02*
Y783691D01*
G01Y780935D02*
Y780541D01*
G01Y787234D02*
Y786840D01*
G01Y793533D02*
Y793140D01*
G01Y790384D02*
Y789990D01*
G01Y796683D02*
Y796289D01*
G01Y799833D02*
Y799439D01*
G01Y802982D02*
Y802588D01*
G01Y806132D02*
Y805738D01*
G01Y809281D02*
Y808888D01*
G01Y812431D02*
Y812037D01*
G01Y815581D02*
Y815187D01*
G01Y821880D02*
Y821486D01*
G01Y818730D02*
Y818337D01*
G01Y825029D02*
Y824636D01*
G01Y831329D02*
Y830935D01*
G01Y828179D02*
Y827785D01*
G01Y834478D02*
Y834085D01*
G01Y840777D02*
Y840384D01*
G01Y837628D02*
Y837234D01*
G01Y843927D02*
Y843533D01*
G01X1503717Y810165D02*
Y811149D01*
G01Y803866D02*
Y804850D01*
G01Y807015D02*
Y808000D01*
G01Y800716D02*
Y801701D01*
G01Y797567D02*
Y798551D01*
G01Y794417D02*
Y795401D01*
G01X1503590Y845088D02*
Y845482D01*
G01Y840088D02*
Y840482D01*
G01Y835088D02*
Y835482D01*
G01Y830088D02*
Y830482D01*
G01Y825088D02*
Y825482D01*
G01Y820088D02*
Y820482D01*
G01Y785088D02*
Y785482D01*
G01Y780088D02*
Y780482D01*
G01X1503499Y815088D02*
Y815482D01*
G01Y790088D02*
Y790482D01*
G01X1500921Y818888D02*
Y849892D01*
G01Y813711D02*
Y791860D01*
G01X1500751Y813506D02*
Y818888D01*
G01Y786585D02*
Y792064D01*
G01X1509161Y843927D02*
X1509158Y843965D01*
X1509151Y844002D01*
X1509138Y844036D01*
X1509121Y844066D01*
X1509100Y844091D01*
X1509076Y844109D01*
X1509050Y844120D01*
X1509023Y844124D01*
G01X1509161Y840777D02*
X1509158Y840816D01*
X1509151Y840852D01*
X1509138Y840886D01*
X1509121Y840917D01*
X1509100Y840941D01*
X1509076Y840959D01*
X1509050Y840970D01*
X1509023Y840974D01*
G01X1509161Y837628D02*
X1509158Y837666D01*
X1509151Y837703D01*
X1509138Y837737D01*
X1509121Y837767D01*
X1509100Y837791D01*
X1509076Y837810D01*
X1509050Y837821D01*
X1509023Y837825D01*
G01X1509161Y834478D02*
X1509158Y834516D01*
X1509151Y834553D01*
X1509138Y834587D01*
X1509121Y834617D01*
X1509100Y834642D01*
X1509076Y834660D01*
X1509050Y834671D01*
X1509023Y834675D01*
G01X1509161Y831329D02*
X1509158Y831367D01*
X1509151Y831404D01*
X1509138Y831438D01*
X1509121Y831468D01*
X1509100Y831492D01*
X1509076Y831510D01*
X1509050Y831522D01*
X1509023Y831525D01*
G01X1509161Y828179D02*
X1509158Y828217D01*
X1509151Y828254D01*
X1509138Y828288D01*
X1509121Y828318D01*
X1509100Y828343D01*
X1509076Y828361D01*
X1509050Y828372D01*
X1509023Y828376D01*
G01X1509161Y825029D02*
X1509158Y825068D01*
X1509151Y825104D01*
X1509138Y825138D01*
X1509121Y825169D01*
X1509100Y825193D01*
X1509076Y825211D01*
X1509050Y825222D01*
X1509023Y825226D01*
G01X1509161Y821880D02*
X1509158Y821918D01*
X1509151Y821955D01*
X1509138Y821989D01*
X1509121Y822019D01*
X1509100Y822043D01*
X1509076Y822062D01*
X1509050Y822073D01*
X1509023Y822077D01*
G01X1509161Y818730D02*
X1509158Y818768D01*
X1509151Y818805D01*
X1509138Y818839D01*
X1509121Y818869D01*
X1509100Y818894D01*
X1509076Y818912D01*
X1509050Y818923D01*
X1509023Y818927D01*
G01X1509161Y815581D02*
X1509158Y815619D01*
X1509151Y815656D01*
X1509138Y815690D01*
X1509121Y815720D01*
X1509100Y815744D01*
X1509076Y815762D01*
X1509050Y815774D01*
X1509023Y815777D01*
G01X1509161Y812431D02*
X1509158Y812469D01*
X1509151Y812506D01*
X1509138Y812540D01*
X1509121Y812570D01*
X1509100Y812595D01*
X1509076Y812613D01*
X1509050Y812624D01*
X1509023Y812628D01*
G01X1509161Y809281D02*
X1509158Y809320D01*
X1509151Y809356D01*
X1509138Y809390D01*
X1509121Y809421D01*
X1509100Y809445D01*
X1509076Y809463D01*
X1509050Y809474D01*
X1509023Y809478D01*
G01X1509161Y806132D02*
X1509158Y806170D01*
X1509151Y806207D01*
X1509138Y806241D01*
X1509121Y806271D01*
X1509100Y806295D01*
X1509076Y806314D01*
X1509050Y806325D01*
X1509023Y806329D01*
G01X1509161Y802982D02*
X1509158Y803020D01*
X1509151Y803057D01*
X1509138Y803091D01*
X1509121Y803121D01*
X1509100Y803146D01*
X1509076Y803164D01*
X1509050Y803175D01*
X1509023Y803179D01*
G01X1509161Y799833D02*
X1509158Y799871D01*
X1509151Y799908D01*
X1509138Y799942D01*
X1509121Y799972D01*
X1509100Y799996D01*
X1509076Y800014D01*
X1509050Y800026D01*
X1509023Y800029D01*
G01X1509161Y796683D02*
X1509158Y796721D01*
X1509151Y796758D01*
X1509138Y796792D01*
X1509121Y796822D01*
X1509100Y796847D01*
X1509076Y796865D01*
X1509050Y796876D01*
X1509023Y796880D01*
G01X1509161Y793533D02*
X1509158Y793572D01*
X1509151Y793608D01*
X1509138Y793642D01*
X1509121Y793673D01*
X1509100Y793697D01*
X1509076Y793715D01*
X1509050Y793726D01*
X1509023Y793730D01*
G01X1509161Y790384D02*
X1509158Y790422D01*
X1509151Y790459D01*
X1509138Y790493D01*
X1509121Y790523D01*
X1509100Y790547D01*
X1509076Y790565D01*
X1509050Y790577D01*
X1509023Y790581D01*
G01X1509161Y787234D02*
X1509158Y787272D01*
X1509151Y787309D01*
X1509138Y787343D01*
X1509121Y787373D01*
X1509100Y787398D01*
X1509076Y787416D01*
X1509050Y787427D01*
X1509023Y787431D01*
G01X1509161Y784085D02*
X1509158Y784123D01*
X1509151Y784160D01*
X1509138Y784193D01*
X1509121Y784224D01*
X1509100Y784248D01*
X1509076Y784266D01*
X1509050Y784278D01*
X1509023Y784281D01*
G01X1509161Y780935D02*
X1509158Y780973D01*
X1509151Y781010D01*
X1509138Y781044D01*
X1509121Y781074D01*
X1509100Y781099D01*
X1509076Y781117D01*
X1509050Y781128D01*
X1509023Y781132D01*
G01X1509161Y777785D02*
X1509158Y777824D01*
X1509151Y777860D01*
X1509138Y777894D01*
X1509121Y777925D01*
X1509100Y777949D01*
X1509076Y777967D01*
X1509050Y777978D01*
X1509023Y777982D01*
G01X1503727Y843533D02*
X1503758Y843436D01*
X1503847Y843364D01*
X1503974Y843337D01*
G01X1503727Y840384D02*
X1503758Y840287D01*
X1503847Y840215D01*
X1503974Y840187D01*
G01X1503727Y837234D02*
X1503758Y837137D01*
X1503847Y837065D01*
X1503974Y837037D01*
G01X1503727Y834085D02*
X1503758Y833988D01*
X1503847Y833915D01*
X1503974Y833888D01*
G01X1503727Y830935D02*
X1503758Y830838D01*
X1503847Y830766D01*
X1503974Y830738D01*
G01X1503727Y827785D02*
X1503758Y827688D01*
X1503847Y827616D01*
X1503974Y827588D01*
G01X1503727Y824636D02*
X1503758Y824539D01*
X1503847Y824467D01*
X1503974Y824439D01*
G01X1503727Y821486D02*
X1503758Y821389D01*
X1503847Y821317D01*
X1503974Y821289D01*
G01X1503727Y818337D02*
X1503758Y818240D01*
X1503847Y818167D01*
X1503974Y818140D01*
G01X1503727Y815187D02*
X1503758Y815090D01*
X1503847Y815018D01*
X1503974Y814990D01*
G01X1503727Y812037D02*
X1503758Y811940D01*
X1503847Y811868D01*
X1503974Y811840D01*
G01X1503727Y808888D02*
X1503758Y808791D01*
X1503847Y808719D01*
X1503974Y808691D01*
G01X1503727Y805738D02*
X1503758Y805641D01*
X1503847Y805569D01*
X1503974Y805541D01*
G01X1503727Y802588D02*
X1503758Y802491D01*
X1503847Y802419D01*
X1503974Y802392D01*
G01X1503727Y799439D02*
X1503758Y799342D01*
X1503847Y799270D01*
X1503974Y799242D01*
G01X1503727Y796289D02*
X1503758Y796192D01*
X1503847Y796120D01*
X1503974Y796092D01*
G01X1503727Y793140D02*
X1503758Y793043D01*
X1503847Y792970D01*
X1503974Y792943D01*
G01X1503727Y789990D02*
X1503758Y789893D01*
X1503847Y789821D01*
X1503974Y789793D01*
G01X1503727Y786840D02*
X1503758Y786743D01*
X1503847Y786671D01*
X1503974Y786644D01*
G01X1503727Y783691D02*
X1503758Y783594D01*
X1503847Y783522D01*
X1503974Y783494D01*
G01X1503727Y780541D02*
X1503758Y780444D01*
X1503847Y780372D01*
X1503974Y780344D01*
G01X1503727Y777392D02*
X1503758Y777295D01*
X1503847Y777222D01*
X1503974Y777195D01*
G01X1503717Y810165D02*
X1503750Y810066D01*
X1503838Y809995D01*
X1503964Y809968D01*
G01X1503717Y807015D02*
X1503750Y806916D01*
X1503838Y806846D01*
X1503964Y806819D01*
G01X1503717Y803866D02*
X1503750Y803767D01*
X1503838Y803696D01*
X1503964Y803669D01*
G01X1503717Y800716D02*
X1503750Y800617D01*
X1503838Y800546D01*
X1503964Y800519D01*
G01X1503717Y797567D02*
X1503750Y797468D01*
X1503838Y797397D01*
X1503964Y797370D01*
G01X1503717Y794417D02*
X1503750Y794318D01*
X1503838Y794247D01*
X1503964Y794220D01*
G01X1509060Y846073D02*
X1509332Y845482D01*
G01X1509060Y841073D02*
X1509332Y840482D01*
G01X1509060Y836073D02*
X1509332Y835482D01*
G01X1509060Y831073D02*
X1509332Y830482D01*
G01X1509060Y826073D02*
X1509332Y825482D01*
G01X1509060Y821073D02*
X1509332Y820482D01*
G01X1509060Y816073D02*
X1509332Y815482D01*
G01X1509060Y791073D02*
X1509332Y790482D01*
G01X1509060Y786073D02*
X1509332Y785482D01*
G01X1509060Y781073D02*
X1509332Y780482D01*
G01X1503499Y815088D02*
X1503633Y814891D01*
X1503768Y814694D01*
X1503904Y814498D01*
G01X1503499Y790088D02*
X1503633Y789891D01*
X1503768Y789694D01*
X1503904Y789498D01*
G01X1503590Y845088D02*
X1503727Y844891D01*
X1503865Y844694D01*
X1504004Y844498D01*
G01X1503590Y840088D02*
X1503727Y839891D01*
X1503865Y839694D01*
X1504004Y839498D01*
G01X1503590Y835088D02*
X1503727Y834891D01*
X1503865Y834694D01*
X1504004Y834498D01*
G01X1503590Y830088D02*
X1503727Y829891D01*
X1503865Y829694D01*
X1504004Y829498D01*
G01X1503590Y825088D02*
X1503727Y824891D01*
X1503865Y824694D01*
X1504004Y824498D01*
G01X1503590Y820088D02*
X1503727Y819891D01*
X1503865Y819694D01*
X1504004Y819498D01*
G01X1503590Y785088D02*
X1503727Y784891D01*
X1503865Y784694D01*
X1504004Y784498D01*
G01X1503590Y780088D02*
X1503727Y779891D01*
X1503865Y779694D01*
X1504004Y779498D01*
G01X1509817Y816073D02*
X1510241Y815482D01*
G01X1509817Y791073D02*
X1510241Y790482D01*
G01X1509749Y846073D02*
X1510176Y845482D01*
G01X1509749Y841073D02*
X1510176Y840482D01*
G01X1509749Y836073D02*
X1510176Y835482D01*
G01X1509749Y831073D02*
X1510176Y830482D01*
G01X1509749Y826073D02*
X1510176Y825482D01*
G01X1509749Y821073D02*
X1510176Y820482D01*
G01X1509749Y786073D02*
X1510176Y785482D01*
G01X1509749Y781073D02*
X1510176Y780482D01*
G01X1501709Y812549D02*
X1499740Y814518D01*
G01X1508572Y844124D02*
X1508610Y844097D01*
X1508638Y844025D01*
X1508648Y843927D01*
G01X1508572Y840974D02*
X1508610Y840948D01*
X1508638Y840876D01*
X1508648Y840777D01*
G01X1508572Y837825D02*
X1508610Y837798D01*
X1508638Y837726D01*
X1508648Y837628D01*
G01X1508572Y834675D02*
X1508610Y834649D01*
X1508638Y834577D01*
X1508648Y834478D01*
G01X1508572Y831525D02*
X1508610Y831499D01*
X1508638Y831427D01*
X1508648Y831329D01*
G01X1508572Y828376D02*
X1508610Y828349D01*
X1508638Y828277D01*
X1508648Y828179D01*
G01X1508572Y825226D02*
X1508610Y825200D01*
X1508638Y825128D01*
X1508648Y825029D01*
G01X1508572Y822077D02*
X1508610Y822050D01*
X1508638Y821978D01*
X1508648Y821880D01*
G01X1508572Y818927D02*
X1508610Y818901D01*
X1508638Y818829D01*
X1508648Y818730D01*
G01X1508572Y815777D02*
X1508610Y815751D01*
X1508638Y815679D01*
X1508648Y815581D01*
G01X1508572Y812628D02*
X1508610Y812601D01*
X1508638Y812529D01*
X1508648Y812431D01*
G01X1508572Y809478D02*
X1508610Y809452D01*
X1508638Y809380D01*
X1508648Y809281D01*
G01X1508572Y806329D02*
X1508610Y806302D01*
X1508638Y806230D01*
X1508648Y806132D01*
G01X1508572Y803179D02*
X1508610Y803153D01*
X1508638Y803081D01*
X1508648Y802982D01*
G01X1508572Y800029D02*
X1508610Y800003D01*
X1508638Y799931D01*
X1508648Y799833D01*
G01X1508572Y796880D02*
X1508610Y796853D01*
X1508638Y796781D01*
X1508648Y796683D01*
G01X1508572Y793730D02*
X1508610Y793704D01*
X1508638Y793632D01*
X1508648Y793533D01*
G01X1508572Y790581D02*
X1508610Y790554D01*
X1508638Y790482D01*
X1508648Y790384D01*
G01X1508572Y787431D02*
X1508610Y787405D01*
X1508638Y787333D01*
X1508648Y787234D01*
G01X1508572Y784281D02*
X1508610Y784255D01*
X1508638Y784183D01*
X1508648Y784085D01*
G01X1508572Y781132D02*
X1508610Y781105D01*
X1508638Y781033D01*
X1508648Y780935D01*
G01X1508572Y777982D02*
X1508610Y777956D01*
X1508638Y777884D01*
X1508648Y777785D01*
G01X1507908Y811346D02*
X1507914Y811342D01*
X1507920Y811331D01*
X1507926Y811313D01*
X1507931Y811289D01*
X1507935Y811259D01*
X1507938Y811225D01*
X1507940Y811188D01*
X1507941Y811149D01*
G01X1507908Y808197D02*
X1507914Y808193D01*
X1507920Y808182D01*
X1507926Y808164D01*
X1507931Y808139D01*
X1507935Y808109D01*
X1507938Y808075D01*
X1507940Y808039D01*
X1507941Y808000D01*
G01X1507908Y805047D02*
X1507914Y805043D01*
X1507920Y805032D01*
X1507926Y805014D01*
X1507931Y804989D01*
X1507935Y804960D01*
X1507938Y804926D01*
X1507940Y804889D01*
X1507941Y804850D01*
G01X1507908Y801897D02*
X1507914Y801894D01*
X1507920Y801883D01*
X1507926Y801864D01*
X1507931Y801840D01*
X1507935Y801810D01*
X1507938Y801776D01*
X1507940Y801739D01*
X1507941Y801701D01*
G01X1507908Y798748D02*
X1507914Y798744D01*
X1507920Y798733D01*
X1507926Y798715D01*
X1507931Y798690D01*
X1507935Y798660D01*
X1507938Y798627D01*
X1507940Y798590D01*
X1507941Y798551D01*
G01X1507908Y795598D02*
X1507914Y795594D01*
X1507920Y795583D01*
X1507926Y795565D01*
X1507931Y795540D01*
X1507935Y795511D01*
X1507938Y795477D01*
X1507940Y795440D01*
X1507941Y795401D01*
G01X1533008Y776663D02*
X1532024D01*
G01X1533008Y776270D02*
X1532024D01*
G01X1531551Y776073D02*
X1537142D01*
G01X1531945Y844498D02*
G03X1531551Y844104I0J-394D01*
G01Y846466D02*
G03X1531945Y846073I394J1D01*
G01Y834498D02*
G03X1531551Y834104I0J-394D01*
G01Y836466D02*
G03X1531945Y836073I394J1D01*
G01Y839498D02*
G03X1531551Y839104I0J-394D01*
G01Y841466D02*
G03X1531945Y841073I394J1D01*
G01Y784498D02*
G03X1531551Y784104I0J-394D01*
G01Y786466D02*
G03X1531945Y786073I394J1D01*
G01Y779498D02*
G03X1531551Y779104I0J-394D01*
G01Y781466D02*
G03X1531945Y781073I394J1D01*
G01Y814498D02*
G03X1531551Y814104I0J-394D01*
G01Y816466D02*
G03X1531945Y816073I394J1D01*
G01Y819498D02*
G03X1531551Y819104I0J-394D01*
G01Y821466D02*
G03X1531945Y821073I394J1D01*
G01Y789498D02*
G03X1531551Y789104I0J-394D01*
G01Y791466D02*
G03X1531945Y791073I394J1D01*
G01Y824498D02*
G03X1531551Y824104I0J-394D01*
G01Y826466D02*
G03X1531945Y826073I394J1D01*
G01Y829498D02*
G03X1531551Y829104I0J-394D01*
G01Y831466D02*
G03X1531945Y831073I394J1D01*
G01X1528526Y844885D02*
X1528787Y844970D01*
G01X1528003Y846932D02*
X1528265Y847018D01*
G01X1526261Y847188D02*
X1526522Y847274D01*
G01X1528700Y845482D02*
X1528526Y845397D01*
G01X1526784Y844629D02*
X1527132Y844800D01*
G01X1526174Y847700D02*
X1525738Y847444D01*
G01X1526958Y845312D02*
X1526696Y845141D01*
G01X1528787Y844970D02*
X1529136Y845226D01*
G01X1528874Y845653D02*
X1528700Y845482D01*
G01X1527132Y844800D02*
X1527480Y845141D01*
G01X1527829Y847444D02*
X1527480Y847103D01*
G01X1525999Y846932D02*
X1526261Y847188D01*
G01X1529136Y845226D02*
X1529397Y845567D01*
G01X1527132D02*
X1526958Y845312D01*
G01X1527829Y846676D02*
X1528003Y846932D01*
G01X1525738Y847444D02*
X1525477Y847018D01*
G01X1527480Y845141D02*
X1527655Y845482D01*
G01X1527480Y847103D02*
X1527306Y846762D01*
G01X1528961Y845909D02*
X1528874Y845653D01*
G01X1527742Y846421D02*
X1527829Y846676D01*
G01X1526522Y847785D02*
X1526174Y847700D01*
G01X1528177Y847529D02*
X1527829Y847444D01*
G01X1527219Y845909D02*
X1527132Y845567D01*
G01X1527306Y846762D02*
X1527219Y846421D01*
G01X1525912Y846591D02*
X1525999Y846932D01*
G01X1529397Y845567D02*
X1529484Y845994D01*
G01X1527655Y845482D02*
X1527742Y845909D01*
G01X1525477Y847018D02*
X1525390Y846591D01*
G01X1528526Y847529D02*
X1528177D01*
G01X1528265Y847018D02*
X1528439D01*
G01X1534976Y846860D02*
X1533992D01*
G01X1535567Y846703D02*
X1544551D01*
G01X1534976Y846663D02*
X1533992D01*
G01X1534976Y846270D02*
X1533992D01*
G01X1540075Y846250D02*
X1532004D01*
G01X1531945Y846073D02*
X1539110D01*
G01X1526696Y845141D02*
X1526435D01*
G01X1526348Y844629D02*
X1526784D01*
G01X1531945Y844498D02*
X1539110D01*
G01X1534976Y844301D02*
X1533992D01*
G01X1532004Y844281D02*
X1540075D01*
G01X1542605Y844124D02*
X1549937D01*
G01X1542457D02*
X1530449D01*
G01X1528177Y843947D02*
X1528874D01*
G01X1534976Y843907D02*
X1533992D01*
G01X1534976Y843711D02*
X1533992D01*
G01X1525390Y843435D02*
X1528787D01*
G01X1542457Y843337D02*
X1530449D01*
G01X1549937D02*
X1542605D01*
G01X1529484Y842923D02*
X1525390D01*
G01X1534976Y841860D02*
X1533992D01*
G01X1534976Y841663D02*
X1533992D01*
G01X1534976Y841270D02*
X1533992D01*
G01X1531945Y841073D02*
X1539110D01*
G01X1542605Y840974D02*
X1549937D01*
G01X1542457D02*
X1530449D01*
G01X1542457Y840187D02*
X1530449D01*
G01X1549937D02*
X1542605D01*
G01X1531945Y839498D02*
X1539110D01*
G01X1534976Y839301D02*
X1533992D01*
G01X1534976Y838907D02*
X1533992D01*
G01X1534976Y838711D02*
X1533992D01*
G01X1542605Y837825D02*
X1549937D01*
G01X1542457D02*
X1530449D01*
G01X1542457Y837037D02*
X1530449D01*
G01X1549937D02*
X1542605D01*
G01X1534976Y836860D02*
X1533992D01*
G01X1534976Y836663D02*
X1533992D01*
G01X1534976Y836270D02*
X1533992D01*
G01X1531945Y836073D02*
X1539110D01*
G01X1542605Y834675D02*
X1549937D01*
G01X1542457D02*
X1530449D01*
G01X1531945Y834498D02*
X1539110D01*
G01X1534976Y834301D02*
X1533992D01*
G01X1534976Y833907D02*
X1533992D01*
G01X1542457Y833888D02*
X1530449D01*
G01X1549937D02*
X1542605D01*
G01X1534976Y833711D02*
X1533992D01*
G01X1534976Y831860D02*
X1533992D01*
G01X1534976Y831663D02*
X1533992D01*
G01X1542605Y831525D02*
X1549937D01*
G01X1542457D02*
X1530449D01*
G01X1534976Y831270D02*
X1533992D01*
G01X1531945Y831073D02*
X1539110D01*
G01X1542457Y830738D02*
X1530449D01*
G01X1549937D02*
X1542605D01*
G01X1531945Y829498D02*
X1539110D01*
G01X1534976Y829301D02*
X1533992D01*
G01X1534976Y828907D02*
X1533992D01*
G01X1534976Y828711D02*
X1533992D01*
G01X1542605Y828376D02*
X1549937D01*
G01X1542457D02*
X1530449D01*
G01X1542457Y827588D02*
X1530449D01*
G01X1549937D02*
X1542605D01*
G01X1534976Y826860D02*
X1533992D01*
G01X1534976Y826663D02*
X1533992D01*
G01X1534976Y826270D02*
X1533992D01*
G01X1531945Y826073D02*
X1539110D01*
G01X1542605Y825226D02*
X1549937D01*
G01X1542457D02*
X1530449D01*
G01X1531945Y824498D02*
X1539110D01*
G01X1542457Y824439D02*
X1530449D01*
G01X1549937D02*
X1542605D01*
G01X1534976Y824301D02*
X1533992D01*
G01X1534976Y823907D02*
X1533992D01*
G01X1534976Y823711D02*
X1533992D01*
G01X1542605Y822077D02*
X1549937D01*
G01X1542457D02*
X1530449D01*
G01X1534976Y821860D02*
X1533992D01*
G01X1534976Y821663D02*
X1533992D01*
G01X1542457Y821289D02*
X1530449D01*
G01X1549937D02*
X1542605D01*
G01X1534976Y821270D02*
X1533992D01*
G01X1531945Y821073D02*
X1539110D01*
G01X1531945Y819498D02*
X1539110D01*
G01X1534976Y819301D02*
X1533992D01*
G01X1542605Y818927D02*
X1549937D01*
G01X1542457D02*
X1530449D01*
G01X1534976Y818907D02*
X1533992D01*
G01X1534976Y818711D02*
X1533992D01*
G01X1542457Y818140D02*
X1530449D01*
G01X1549937D02*
X1542605D01*
G01X1534976Y816860D02*
X1533992D01*
G01X1534976Y816663D02*
X1533992D01*
G01X1534976Y816270D02*
X1533992D01*
G01X1531945Y816073D02*
X1539110D01*
G01X1542605Y815777D02*
X1549937D01*
G01X1542457D02*
X1530449D01*
G01X1542457Y814990D02*
X1530449D01*
G01X1549937D02*
X1542605D01*
G01X1531945Y814498D02*
X1539110D01*
G01X1534976Y814301D02*
X1533992D01*
G01X1534976Y813907D02*
X1533992D01*
G01X1534976Y813711D02*
X1533992D01*
G01X1542605Y812628D02*
X1549937D01*
G01X1542457D02*
X1530449D01*
G01X1531551Y812549D02*
X1530449D01*
G01X1549937Y777982D02*
Y777195D01*
G01Y784281D02*
Y783494D01*
G01Y781132D02*
Y780344D01*
G01Y787431D02*
Y786644D01*
G01Y793730D02*
Y792943D01*
G01Y790581D02*
Y789793D01*
G01Y796880D02*
Y796092D01*
G01Y803179D02*
Y802392D01*
G01Y800029D02*
Y799242D01*
G01Y806329D02*
Y805541D01*
G01Y812628D02*
Y811840D01*
G01Y809478D02*
Y808691D01*
G01Y815777D02*
Y814990D01*
G01Y822077D02*
Y821289D01*
G01Y818927D02*
Y818140D01*
G01Y825226D02*
Y824439D01*
G01Y831525D02*
Y830738D01*
G01Y828376D02*
Y827588D01*
G01Y834675D02*
Y833888D01*
G01Y840974D02*
Y840187D01*
G01Y837825D02*
Y837037D01*
G01Y844124D02*
Y843337D01*
G01X1548163Y777982D02*
Y777195D01*
G01Y784281D02*
Y783494D01*
G01Y781132D02*
Y780344D01*
G01Y787431D02*
Y786644D01*
G01Y793730D02*
Y792943D01*
G01Y790581D02*
Y789793D01*
G01Y796880D02*
Y796092D01*
G01Y803179D02*
Y802392D01*
G01Y800029D02*
Y799242D01*
G01Y806329D02*
Y805541D01*
G01Y812628D02*
Y811840D01*
G01Y809478D02*
Y808691D01*
G01Y815777D02*
Y814990D01*
G01Y822077D02*
Y821289D01*
G01Y818927D02*
Y818140D01*
G01Y825226D02*
Y824439D01*
G01Y831525D02*
Y830738D01*
G01Y828376D02*
Y827588D01*
G01Y834675D02*
Y833888D01*
G01Y840974D02*
Y840187D01*
G01Y837825D02*
Y837037D01*
G01Y844124D02*
Y843337D01*
G01X1547975D02*
Y844124D01*
G01Y840187D02*
Y840974D01*
G01Y837037D02*
Y837825D01*
G01Y833888D02*
Y834675D01*
G01Y830738D02*
Y831525D01*
G01Y827588D02*
Y828376D01*
G01Y824439D02*
Y825226D01*
G01Y821289D02*
Y822077D01*
G01Y818140D02*
Y818927D01*
G01Y814990D02*
Y815777D01*
G01Y811840D02*
Y812628D01*
G01Y808691D02*
Y809478D01*
G01Y805541D02*
Y806329D01*
G01Y802392D02*
Y803179D01*
G01Y799242D02*
Y800029D01*
G01Y796092D02*
Y796880D01*
G01Y792943D02*
Y793730D01*
G01Y789793D02*
Y790581D01*
G01Y786644D02*
Y787431D01*
G01Y783494D02*
Y784281D01*
G01Y780344D02*
Y781132D01*
G01Y777195D02*
Y777982D01*
G01X1545138Y843337D02*
Y844124D01*
G01Y840187D02*
Y840974D01*
G01Y837037D02*
Y837825D01*
G01Y833888D02*
Y834675D01*
G01Y830738D02*
Y831525D01*
G01Y827588D02*
Y828376D01*
G01Y824439D02*
Y825226D01*
G01Y821289D02*
Y822077D01*
G01Y818140D02*
Y818927D01*
G01Y814990D02*
Y815777D01*
G01Y811840D02*
Y812628D01*
G01Y808691D02*
Y809478D01*
G01Y805541D02*
Y806329D01*
G01Y802392D02*
Y803179D01*
G01Y799242D02*
Y800029D01*
G01Y796092D02*
Y796880D01*
G01Y792943D02*
Y793730D01*
G01Y789793D02*
Y790581D01*
G01Y786644D02*
Y787431D01*
G01Y783494D02*
Y784281D01*
G01Y780344D02*
Y781132D01*
G01Y777195D02*
Y777982D01*
G01X1544197D02*
Y777195D01*
G01Y784281D02*
Y783494D01*
G01Y781132D02*
Y780344D01*
G01Y787431D02*
Y786644D01*
G01Y793730D02*
Y792943D01*
G01Y790581D02*
Y789793D01*
G01Y796880D02*
Y796092D01*
G01Y803179D02*
Y802392D01*
G01Y800029D02*
Y799242D01*
G01Y806329D02*
Y805541D01*
G01Y812628D02*
Y811840D01*
G01Y809478D02*
Y808691D01*
G01Y815777D02*
Y814990D01*
G01Y822077D02*
Y821289D01*
G01Y818927D02*
Y818140D01*
G01Y825226D02*
Y824439D01*
G01Y831525D02*
Y830738D01*
G01Y828376D02*
Y827588D01*
G01Y834675D02*
Y833888D01*
G01Y840974D02*
Y840187D01*
G01Y837825D02*
Y837037D01*
G01Y844124D02*
Y843337D01*
G01X1542605Y777982D02*
Y777195D01*
G01Y784281D02*
Y783494D01*
G01Y781132D02*
Y780344D01*
G01Y787431D02*
Y786644D01*
G01Y793730D02*
Y792943D01*
G01Y790581D02*
Y789793D01*
G01Y796880D02*
Y796092D01*
G01Y803179D02*
Y802392D01*
G01Y800029D02*
Y799242D01*
G01Y806329D02*
Y805541D01*
G01Y812628D02*
Y811840D01*
G01Y809478D02*
Y808691D01*
G01Y815777D02*
Y814990D01*
G01Y822077D02*
Y821289D01*
G01Y818927D02*
Y818140D01*
G01Y825226D02*
Y824439D01*
G01Y831525D02*
Y830738D01*
G01Y828376D02*
Y827588D01*
G01Y834675D02*
Y833888D01*
G01Y840974D02*
Y840187D01*
G01Y837825D02*
Y837037D01*
G01Y844124D02*
Y843337D01*
G01X1542457Y777982D02*
Y777195D01*
G01Y784281D02*
Y783494D01*
G01Y781132D02*
Y780344D01*
G01Y787431D02*
Y786644D01*
G01Y793730D02*
Y792943D01*
G01Y790581D02*
Y789793D01*
G01Y796880D02*
Y796092D01*
G01Y803179D02*
Y802392D01*
G01Y800029D02*
Y799242D01*
G01Y806329D02*
Y805541D01*
G01Y812628D02*
Y811840D01*
G01Y809478D02*
Y808691D01*
G01Y815777D02*
Y814990D01*
G01Y822077D02*
Y821289D01*
G01Y818927D02*
Y818140D01*
G01Y825226D02*
Y824439D01*
G01Y831525D02*
Y830738D01*
G01Y828376D02*
Y827588D01*
G01Y834675D02*
Y833888D01*
G01Y840974D02*
Y840187D01*
G01Y837825D02*
Y837037D01*
G01Y844124D02*
Y843337D01*
G01X1541519Y844124D02*
Y846703D01*
G01Y840974D02*
Y843337D01*
G01Y837825D02*
Y840187D01*
G01Y834675D02*
Y837037D01*
G01Y831525D02*
Y833888D01*
G01Y828376D02*
Y830738D01*
G01Y825226D02*
Y827588D01*
G01Y822077D02*
Y824439D01*
G01Y818927D02*
Y821289D01*
G01Y815777D02*
Y818140D01*
G01Y812628D02*
Y814990D01*
G01Y809478D02*
Y811840D01*
G01Y806329D02*
Y808691D01*
G01Y803179D02*
Y805541D01*
G01Y800029D02*
Y802392D01*
G01Y796880D02*
Y799242D01*
G01Y793730D02*
Y796092D01*
G01Y790581D02*
Y792943D01*
G01Y787431D02*
Y789793D01*
G01Y784281D02*
Y786644D01*
G01Y781132D02*
Y783494D01*
G01Y777982D02*
Y780344D01*
G01X1540075Y844281D02*
Y846250D01*
G01X1539791Y777982D02*
Y777195D01*
G01Y784281D02*
Y783494D01*
G01Y781132D02*
Y780344D01*
G01Y787431D02*
Y786644D01*
G01Y793730D02*
Y792943D01*
G01Y790581D02*
Y789793D01*
G01Y796880D02*
Y796092D01*
G01Y803179D02*
Y802392D01*
G01Y800029D02*
Y799242D01*
G01Y806329D02*
Y805541D01*
G01Y812628D02*
Y811840D01*
G01Y809478D02*
Y808691D01*
G01Y815777D02*
Y814990D01*
G01Y822077D02*
Y821289D01*
G01Y818927D02*
Y818140D01*
G01Y825226D02*
Y824439D01*
G01Y831525D02*
Y830738D01*
G01Y828376D02*
Y827588D01*
G01Y834675D02*
Y833888D01*
G01Y840974D02*
Y840187D01*
G01Y837825D02*
Y837037D01*
G01Y844124D02*
Y843337D01*
G01X1539440Y799163D02*
Y796959D01*
G01Y808612D02*
Y806407D01*
G01X1539110Y844498D02*
Y846073D01*
G01Y839498D02*
Y841073D01*
G01Y834498D02*
Y836073D01*
G01Y829498D02*
Y831073D01*
G01Y824498D02*
Y826073D01*
G01Y819498D02*
Y821073D01*
G01Y814498D02*
Y816073D01*
G01Y789498D02*
Y791073D01*
G01Y784498D02*
Y786073D01*
G01Y779498D02*
Y781073D01*
G01X1538139Y843337D02*
Y844124D01*
G01Y840187D02*
Y840974D01*
G01Y837037D02*
Y837825D01*
G01Y833888D02*
Y834675D01*
G01Y830738D02*
Y831525D01*
G01Y827588D02*
Y828376D01*
G01Y824439D02*
Y825226D01*
G01Y821289D02*
Y822077D01*
G01Y818140D02*
Y818927D01*
G01Y814990D02*
Y815777D01*
G01Y811840D02*
Y812628D01*
G01Y808691D02*
Y809478D01*
G01Y805541D02*
Y806329D01*
G01Y802392D02*
Y803179D01*
G01Y799242D02*
Y800029D01*
G01Y796092D02*
Y796880D01*
G01Y792943D02*
Y793730D01*
G01Y789793D02*
Y790581D01*
G01Y786644D02*
Y787431D01*
G01Y783494D02*
Y784281D01*
G01Y780344D02*
Y781132D01*
G01Y777195D02*
Y777982D01*
G01X1537984Y796959D02*
Y793140D01*
G01Y806407D02*
Y799163D01*
G01Y812431D02*
Y808612D01*
G01X1537576Y810069D02*
Y811250D01*
G01Y806919D02*
Y808100D01*
G01Y803770D02*
Y804951D01*
G01Y800620D02*
Y801801D01*
G01Y794321D02*
Y795502D01*
G01Y797470D02*
Y798651D01*
G01X1537558Y806407D02*
Y808612D01*
G01Y796959D02*
Y799163D01*
G01X1537506Y812431D02*
Y793140D01*
G01X1536156Y843337D02*
Y844124D01*
G01Y840187D02*
Y840974D01*
G01Y837037D02*
Y837825D01*
G01Y833888D02*
Y834675D01*
G01Y830738D02*
Y831525D01*
G01Y827588D02*
Y828376D01*
G01Y824439D02*
Y825226D01*
G01Y821289D02*
Y822077D01*
G01Y818140D02*
Y818927D01*
G01Y814990D02*
Y815777D01*
G01Y811840D02*
Y812628D01*
G01Y808691D02*
Y809478D01*
G01Y805541D02*
Y806329D01*
G01Y802392D02*
Y803179D01*
G01Y799242D02*
Y800029D01*
G01Y796092D02*
Y796880D01*
G01Y792943D02*
Y793730D01*
G01Y789793D02*
Y790581D01*
G01Y786644D02*
Y787431D01*
G01Y783494D02*
Y784281D01*
G01Y780344D02*
Y781132D01*
G01Y777195D02*
Y777982D01*
G01X1535961Y781073D02*
Y779498D01*
G01Y786073D02*
Y784498D01*
G01Y791073D02*
Y789498D01*
G01Y816073D02*
Y814498D01*
G01Y821073D02*
Y819498D01*
G01Y826073D02*
Y824498D01*
G01Y831073D02*
Y829498D01*
G01Y836073D02*
Y834498D01*
G01Y841073D02*
Y839498D01*
G01Y846073D02*
Y844498D01*
G01X1534976Y781860D02*
Y778711D01*
G01Y786860D02*
Y783711D01*
G01Y791860D02*
Y788711D01*
G01Y816860D02*
Y813711D01*
G01Y821860D02*
Y818711D01*
G01Y826860D02*
Y823711D01*
G01Y831860D02*
Y828711D01*
G01Y836860D02*
Y833711D01*
G01Y841860D02*
Y838711D01*
G01Y846860D02*
Y843711D01*
G01X1534427Y795502D02*
Y794321D01*
G01Y798651D02*
Y797470D01*
G01Y801801D02*
Y800620D01*
G01Y808100D02*
Y806919D01*
G01Y804951D02*
Y803770D01*
G01Y811250D02*
Y810069D01*
G01X1534149Y812431D02*
Y793140D01*
G01X1533992Y781860D02*
Y778711D01*
G01Y786860D02*
Y783711D01*
G01Y791860D02*
Y788711D01*
G01Y816860D02*
Y813711D01*
G01Y821860D02*
Y818711D01*
G01Y826860D02*
Y823711D01*
G01Y831860D02*
Y828711D01*
G01Y836860D02*
Y833711D01*
G01Y841860D02*
Y838711D01*
G01Y846860D02*
Y843711D01*
G01X1533442Y811939D02*
Y793632D01*
G01X1533232Y793140D02*
Y812431D01*
G01X1533008Y781073D02*
Y779498D01*
G01Y786073D02*
Y784498D01*
G01Y791073D02*
Y789498D01*
G01Y816073D02*
Y814498D01*
G01Y821073D02*
Y819498D01*
G01Y826073D02*
Y824498D01*
G01Y831073D02*
Y829498D01*
G01Y836073D02*
Y834498D01*
G01Y841073D02*
Y839498D01*
G01Y846073D02*
Y844498D01*
G01X1532793Y777982D02*
Y777195D01*
G01Y784281D02*
Y783494D01*
G01Y781132D02*
Y780344D01*
G01Y787431D02*
Y786644D01*
G01Y793730D02*
Y792943D01*
G01Y790581D02*
Y789793D01*
G01Y796880D02*
Y796092D01*
G01Y803179D02*
Y802392D01*
G01Y800029D02*
Y799242D01*
G01Y806329D02*
Y805541D01*
G01Y812628D02*
Y811840D01*
G01Y809478D02*
Y808691D01*
G01Y815777D02*
Y814990D01*
G01Y822077D02*
Y821289D01*
G01Y818927D02*
Y818140D01*
G01Y825226D02*
Y824439D01*
G01Y831525D02*
Y830738D01*
G01Y828376D02*
Y827588D01*
G01Y834675D02*
Y833888D01*
G01Y840974D02*
Y840187D01*
G01Y837825D02*
Y837037D01*
G01Y844124D02*
Y843337D01*
G01X1532732Y812431D02*
Y793140D01*
G01X1532458Y796092D02*
Y793730D01*
G01Y799242D02*
Y796880D01*
G01Y802392D02*
Y800029D01*
G01Y805541D02*
Y803179D01*
G01Y811840D02*
Y809478D01*
G01Y808691D02*
Y806329D01*
G01X1532417Y777982D02*
Y777195D01*
G01Y784281D02*
Y783494D01*
G01Y781132D02*
Y780344D01*
G01Y787431D02*
Y786644D01*
G01Y793730D02*
Y792943D01*
G01Y790581D02*
Y789793D01*
G01Y796880D02*
Y796092D01*
G01Y803179D02*
Y802392D01*
G01Y800029D02*
Y799242D01*
G01Y806329D02*
Y805541D01*
G01Y812628D02*
Y811840D01*
G01Y809478D02*
Y808691D01*
G01Y815777D02*
Y814990D01*
G01Y822077D02*
Y821289D01*
G01Y818927D02*
Y818140D01*
G01Y825226D02*
Y824439D01*
G01Y831525D02*
Y830738D01*
G01Y828376D02*
Y827588D01*
G01Y834675D02*
Y833888D01*
G01Y840974D02*
Y840187D01*
G01Y837825D02*
Y837037D01*
G01Y844124D02*
Y843337D01*
G01X1532391Y777982D02*
Y777195D01*
G01Y784281D02*
Y783494D01*
G01Y781132D02*
Y780344D01*
G01Y787431D02*
Y786644D01*
G01Y793730D02*
Y792943D01*
G01Y790581D02*
Y789793D01*
G01Y796880D02*
Y796092D01*
G01Y803179D02*
Y802392D01*
G01Y800029D02*
Y799242D01*
G01Y806329D02*
Y805541D01*
G01Y812628D02*
Y811840D01*
G01Y809478D02*
Y808691D01*
G01Y815777D02*
Y814990D01*
G01Y822077D02*
Y821289D01*
G01Y818927D02*
Y818140D01*
G01Y825226D02*
Y824439D01*
G01Y831525D02*
Y830738D01*
G01Y828376D02*
Y827588D01*
G01Y834675D02*
Y833888D01*
G01Y840974D02*
Y840187D01*
G01Y837825D02*
Y837037D01*
G01Y844124D02*
Y843337D01*
G01X1532004Y846250D02*
Y844281D01*
G01X1531945Y812431D02*
Y793140D01*
G01X1531630D02*
Y812431D01*
G01X1529484Y845994D02*
Y846421D01*
G01Y843435D02*
Y842923D01*
G01X1528961Y846421D02*
Y845909D01*
G01X1528526Y845397D02*
Y844885D01*
G01X1527742Y845909D02*
Y846421D01*
G01X1527219D02*
Y845909D01*
G01X1526522Y847274D02*
Y847785D01*
G01X1526433Y832490D02*
Y848907D01*
G01Y814892D02*
Y830128D01*
G01Y793041D02*
Y812529D01*
G01X1525912Y845909D02*
Y846591D01*
G01X1525390Y842923D02*
Y843435D01*
G01Y846591D02*
Y845909D01*
G01D02*
X1525477Y845482D01*
G01X1529484Y846421D02*
X1529397Y846762D01*
G01X1528874Y847444D02*
X1528526Y847529D01*
G01X1530449Y812431D02*
X1537984D01*
G01X1535567Y811939D02*
X1533442D01*
G01X1542457Y811840D02*
X1530449D01*
G01X1549937D02*
X1542605D01*
G01X1533442Y811644D02*
X1532458D01*
G01X1533442Y811447D02*
X1532458D01*
G01X1531551Y811250D02*
X1537576D01*
G01X1531551Y810069D02*
X1537576D01*
G01X1533442Y809872D02*
X1532458D01*
G01X1533442Y809675D02*
X1532458D01*
G01X1542605Y809478D02*
X1549937D01*
G01X1542457D02*
X1530449D01*
G01X1542457Y808691D02*
X1530449D01*
G01X1549937D02*
X1542605D01*
G01X1539440Y808612D02*
X1537558D01*
G01X1533442Y808494D02*
X1532458D01*
G01X1533442Y808297D02*
X1532458D01*
G01X1531551Y808100D02*
X1537576D01*
G01X1531551Y806919D02*
X1537576D01*
G01X1533442Y806722D02*
X1532458D01*
G01X1533442Y806525D02*
X1532458D01*
G01X1539440Y806407D02*
X1537558D01*
G01X1542605Y806329D02*
X1549937D01*
G01X1542457D02*
X1530449D01*
G01X1542457Y805541D02*
X1530449D01*
G01X1549937D02*
X1542605D01*
G01X1533442Y805344D02*
X1532458D01*
G01X1533442Y805148D02*
X1532458D01*
G01X1531551Y804951D02*
X1537576D01*
G01X1531551Y803770D02*
X1537576D01*
G01X1533442Y803573D02*
X1532458D01*
G01X1533442Y803376D02*
X1532458D01*
G01X1542605Y803179D02*
X1549937D01*
G01X1542457D02*
X1530449D01*
G01X1542457Y802392D02*
X1530449D01*
G01X1549937D02*
X1542605D01*
G01X1533442Y802195D02*
X1532458D01*
G01X1533442Y801998D02*
X1532458D01*
G01X1531551Y801801D02*
X1537576D01*
G01X1531551Y800620D02*
X1537576D01*
G01X1533442Y800423D02*
X1532458D01*
G01X1533442Y800226D02*
X1532458D01*
G01X1542605Y800029D02*
X1549937D01*
G01X1542457D02*
X1530449D01*
G01X1542457Y799242D02*
X1530449D01*
G01X1549937D02*
X1542605D01*
G01X1539440Y799163D02*
X1537558D01*
G01X1533442Y799045D02*
X1532458D01*
G01X1533442Y798848D02*
X1532458D01*
G01X1531551Y798651D02*
X1537576D01*
G01X1531551Y797470D02*
X1537576D01*
G01X1533442Y797274D02*
X1532458D01*
G01X1533442Y797077D02*
X1532458D01*
G01X1539440Y796959D02*
X1537558D01*
G01X1542605Y796880D02*
X1549937D01*
G01X1542457D02*
X1530449D01*
G01X1542457Y796092D02*
X1530449D01*
G01X1549937D02*
X1542605D01*
G01X1533442Y795896D02*
X1532458D01*
G01X1533442Y795699D02*
X1532458D01*
G01X1531551Y795502D02*
X1537576D01*
G01X1531551Y794321D02*
X1537576D01*
G01X1533442Y794124D02*
X1532458D01*
G01X1533442Y793927D02*
X1532458D01*
G01X1542605Y793730D02*
X1549937D01*
G01X1542457D02*
X1530449D01*
G01X1533442Y793632D02*
X1535567D01*
G01X1530449Y793140D02*
X1537984D01*
G01X1531551Y793022D02*
X1530449D01*
G01X1542457Y792943D02*
X1530449D01*
G01X1549937D02*
X1542605D01*
G01X1534976Y791860D02*
X1533992D01*
G01X1534976Y791663D02*
X1533992D01*
G01X1534976Y791270D02*
X1533992D01*
G01X1531945Y791073D02*
X1539110D01*
G01X1542605Y790581D02*
X1549937D01*
G01X1542457D02*
X1530449D01*
G01X1542457Y789793D02*
X1530449D01*
G01X1549937D02*
X1542605D01*
G01X1531945Y789498D02*
X1539110D01*
G01X1534976Y789301D02*
X1533992D01*
G01X1534976Y788907D02*
X1533992D01*
G01X1534976Y788711D02*
X1533992D01*
G01X1542605Y787431D02*
X1549937D01*
G01X1542457D02*
X1530449D01*
G01X1534976Y786860D02*
X1533992D01*
G01X1534976Y786663D02*
X1533992D01*
G01X1542457Y786644D02*
X1530449D01*
G01X1549937D02*
X1542605D01*
G01X1534976Y786270D02*
X1533992D01*
G01X1531945Y786073D02*
X1539110D01*
G01X1531945Y784498D02*
X1539110D01*
G01X1534976Y784301D02*
X1533992D01*
G01X1542605Y784281D02*
X1549937D01*
G01X1542457D02*
X1530449D01*
G01X1534976Y783907D02*
X1533992D01*
G01X1534976Y783711D02*
X1533992D01*
G01X1542457Y783494D02*
X1530449D01*
G01X1549937D02*
X1542605D01*
G01X1534976Y781860D02*
X1533992D01*
G01X1534976Y781663D02*
X1533992D01*
G01X1534976Y781270D02*
X1533992D01*
G01X1542605Y781132D02*
X1549937D01*
G01X1542457D02*
X1530449D01*
G01X1531945Y781073D02*
X1539110D01*
G01X1542457Y780344D02*
X1530449D01*
G01X1549937D02*
X1542605D01*
G01X1531945Y779498D02*
X1539110D01*
G01X1534976Y779301D02*
X1533992D01*
G01X1534976Y778907D02*
X1533992D01*
G01X1534976Y778711D02*
X1533992D01*
G01X1542605Y777982D02*
X1549937D01*
G01X1542457D02*
X1530449D01*
G01Y777490D02*
X1531551D01*
G01X1542457Y777195D02*
X1530449D01*
G01X1549937D02*
X1542605D01*
G01X1533008Y776860D02*
X1532024D01*
G01X1525999Y845567D02*
X1525912Y845909D01*
G01X1528874Y846676D02*
X1528961Y846421D01*
G01X1529397Y846762D02*
X1529223Y847103D01*
G01X1525477Y845482D02*
X1525651Y845141D01*
G01X1528700Y846932D02*
X1528874Y846676D01*
G01X1526174Y845312D02*
X1525999Y845567D01*
G01X1529223Y847103D02*
X1528874Y847444D01*
G01Y843947D02*
X1529484Y843435D01*
G01X1528787D02*
X1528177Y843947D01*
G01X1526435Y845141D02*
X1526174Y845312D01*
G01X1525999Y844800D02*
X1526348Y844629D01*
G01X1528439Y847018D02*
X1528700Y846932D01*
G01X1525651Y845141D02*
X1525999Y844800D01*
G01X1530449Y849498D02*
X1499740D01*
G01X1520212Y849104D02*
X1501709D01*
G01X1499740Y851073D02*
X1501709Y849104D01*
G01Y854025D02*
X1499740Y852057D01*
G01X1497740Y862341D02*
X1497683Y862206D01*
X1497677Y861971D01*
X1497714Y861642D01*
G01X1497740Y862341D02*
X1497682Y862201D01*
X1497677Y861961D01*
G01X1497772Y862372D02*
X1551709D01*
G01X1524149Y861191D02*
X1497772D01*
G01X1501709Y854025D02*
X1551709D01*
G01X1499740D02*
X1496457D01*
G01X1497712Y861650D02*
X1497767Y861264D01*
G01X1497772Y861191D02*
Y854025D01*
G01X1521866Y848907D02*
X1528401D01*
G01X1531551Y848691D02*
X1551709D01*
G01X1531551Y848317D02*
X1522181D01*
G01X1551709Y848691D02*
Y862372D01*
G01X1551391Y848691D02*
Y854025D01*
G01X1550916Y848691D02*
Y851270D01*
G01X1522181Y850088D02*
Y848317D01*
G01X1521866Y848907D02*
Y875305D01*
G01X1547119Y855984D02*
G03X1549334Y861151I-6937J6032D01*
G01X1546234Y855910D02*
G03X1548448Y861151I-7143J6105D01*
G01X1541472Y857588D02*
G03I-2165J0D01*
G01X1542653D02*
G03I-3346J0D01*
G01X1542811D02*
G03I-3504J0D01*
G01X1543835D02*
G03I-4528J0D01*
G01X1533205Y886604D02*
G03Y885423I0J-591D01*
G01Y889360D02*
G03Y888179I0J-591D01*
G01X1532220Y867825D02*
G03Y870974I0J1575D01*
G01X1533648Y858885D02*
G03X1534718Y860709I-2810J2874D01*
G01X1533143Y859429D02*
G03X1533685Y860413I-1276J1344D01*
G01X1526905Y885423D02*
G03Y886604I0J591D01*
G01Y888179D02*
G03Y889360I0J590D01*
G01X1527890Y870974D02*
G03Y867825I0J-1574D01*
G01X1526672Y855984D02*
G03X1528886Y861151I-6938J6031D01*
G01X1525786Y855910D02*
G03X1528001Y861151I-7142J6107D01*
G01X1533354Y856225D02*
X1533067Y856046D01*
X1532713Y855984D01*
G01X1543408Y856049D02*
X1543691Y856227D01*
X1543878Y856492D01*
X1543945Y856794D01*
X1543881Y857094D01*
X1543695Y857361D01*
X1543410Y857543D01*
X1543059Y857608D01*
G01X1542711Y857543D02*
X1542428Y857365D01*
X1542241Y857100D01*
X1542174Y856798D01*
X1542238Y856498D01*
X1542424Y856231D01*
X1542709Y856050D01*
X1543059Y855984D01*
G01X1538241Y856049D02*
X1538524Y856227D01*
X1538711Y856492D01*
X1538778Y856794D01*
X1538713Y857094D01*
X1538528Y857361D01*
X1538243Y857543D01*
X1537892Y857608D01*
G01X1537543Y857543D02*
X1537261Y857365D01*
X1537073Y857100D01*
X1537006Y856798D01*
X1537071Y856498D01*
X1537256Y856231D01*
X1537542Y856050D01*
X1537892Y855984D01*
G01X1543482Y858350D02*
X1543843Y858586D01*
X1544081Y858937D01*
X1544167Y859340D01*
X1544084Y859742D01*
X1543848Y860095D01*
X1543484Y860335D01*
X1543059Y860419D01*
G01X1542636Y860335D02*
X1542276Y860099D01*
X1542038Y859749D01*
X1541952Y859346D01*
X1542035Y858943D01*
X1542271Y858591D01*
X1542635Y858351D01*
X1543059Y858266D01*
G01X1538315Y858350D02*
X1538675Y858586D01*
X1538914Y858937D01*
X1538999Y859340D01*
X1538917Y859742D01*
X1538680Y860095D01*
X1538317Y860335D01*
X1537892Y860419D01*
G01X1537469Y860335D02*
X1537109Y860099D01*
X1536870Y859749D01*
X1536785Y859346D01*
X1536867Y858943D01*
X1537104Y858591D01*
X1537467Y858351D01*
X1537892Y858266D01*
G01X1533143Y859429D02*
X1531514Y857883D01*
G01X1544257Y857895D02*
X1544709Y858335D01*
X1544979Y858871D01*
X1545049Y859441D01*
X1544908Y860005D01*
X1544561Y860530D01*
X1544034Y860923D01*
X1543391Y861127D01*
X1542712Y861124D01*
X1542072Y860916D01*
X1541549Y860520D01*
X1541207Y859996D01*
X1541069Y859435D01*
X1541141Y858868D01*
X1541411Y858334D01*
G01X1539090Y857895D02*
X1539542Y858335D01*
X1539812Y858871D01*
X1539882Y859441D01*
X1539740Y860005D01*
X1539394Y860530D01*
X1538866Y860923D01*
X1538224Y861127D01*
X1537544Y861124D01*
X1536904Y860916D01*
X1536381Y860520D01*
X1536040Y859996D01*
X1535902Y859435D01*
X1535974Y858868D01*
X1536244Y858334D01*
G01X1533648Y858885D02*
X1532086Y857358D01*
G01X1526916Y886225D02*
X1526823Y886114D01*
G01Y886241D02*
X1526916Y886352D01*
G01X1541862Y857895D02*
X1541539Y857476D01*
X1541376Y856992D01*
X1541398Y856487D01*
X1541601Y856011D01*
X1541968Y855607D01*
X1542474Y855340D01*
X1543065Y855246D01*
X1543654Y855343D01*
X1544157Y855612D01*
X1544521Y856016D01*
X1544722Y856494D01*
X1544741Y856999D01*
X1544578Y857480D01*
X1544257Y857895D01*
G01X1536694D02*
X1536372Y857476D01*
X1536209Y856992D01*
X1536231Y856487D01*
X1536434Y856011D01*
X1536801Y855607D01*
X1537307Y855340D01*
X1537898Y855246D01*
X1538487Y855343D01*
X1538989Y855612D01*
X1539354Y856016D01*
X1539555Y856494D01*
X1539574Y856999D01*
X1539410Y857480D01*
X1539090Y857895D01*
G01X1531514Y857883D02*
X1531177Y857421D01*
X1531031Y856903D01*
X1531092Y856385D01*
X1531343Y855901D01*
X1531779Y855506D01*
X1532352Y855283D01*
X1532987Y855264D01*
X1533571Y855450D01*
X1534026Y855803D01*
X1534319Y856275D01*
X1534423Y856796D01*
G01X1533354Y856224D02*
X1533544Y856492D01*
G01X1532086Y857358D02*
X1531903Y857092D01*
X1531839Y856795D01*
X1531904Y856497D01*
G01X1533205Y889951D02*
X1526905D01*
G01X1531630Y889655D02*
X1534779D01*
G01X1528480D02*
X1525331D01*
G01X1533543Y856492D02*
X1533611Y856796D01*
G01X1534423D02*
X1534336Y856319D01*
X1534088Y855877D01*
X1533700Y855525D01*
X1533193Y855305D01*
X1532616Y855249D01*
X1532052Y855371D01*
X1531576Y855654D01*
X1531237Y856058D01*
X1531057Y856515D01*
X1531042Y856995D01*
X1531199Y857466D01*
X1531514Y857883D01*
G01X1525331Y887687D02*
X1528480D01*
G01X1534779D02*
X1531630D01*
G01X1525331Y887096D02*
X1528480D01*
G01X1534779D02*
X1531630D01*
G01X1526916Y886352D02*
X1527010D01*
G01Y885604D02*
X1526916D01*
G01X1531630Y885128D02*
X1534779D01*
G01X1528480D02*
X1525331D01*
G01X1526905Y884833D02*
X1533205D01*
G01X1538244Y875305D02*
X1521866D01*
G01X1527890Y870974D02*
X1532220D01*
G01X1527264Y870187D02*
X1532846D01*
G01Y868612D02*
X1527264D01*
G01X1532220Y867825D02*
X1527890D01*
G01X1538244Y865128D02*
X1521866D01*
G01X1528886Y861151D02*
X1528000D01*
G01X1534718D02*
X1530806D01*
G01X1549334D02*
X1548448D01*
G01X1530806Y860413D02*
X1533684D01*
G01X1551709Y860403D02*
X1528087D01*
G01X1534423Y856944D02*
X1533611D01*
G01X1528087Y856624D02*
X1551709D01*
G01X1529624Y855984D02*
X1526672D01*
G01X1550072D02*
X1547119D01*
G01X1546234Y855246D02*
X1550072D01*
G01X1525786D02*
X1529624D01*
G01X1551709Y854655D02*
X1528087D01*
G01Y852214D02*
X1551709D01*
G01X1536549Y851722D02*
X1530449D01*
G01X1536549Y851663D02*
X1530449D01*
G01X1550916Y851270D02*
X1530449D01*
G01X1531551Y850088D02*
X1522181D01*
G01X1550072Y855246D02*
Y855984D01*
G01X1546234Y855910D02*
Y855246D01*
G01X1545062Y854025D02*
Y851270D01*
G01X1538244Y875305D02*
Y862372D01*
G01X1537188Y854025D02*
Y851270D01*
G01X1536549Y851663D02*
Y851722D01*
G01X1534779Y885128D02*
Y887096D01*
G01Y889655D02*
Y887687D01*
G01X1534718Y860709D02*
Y861151D01*
G01X1534423Y856796D02*
Y856944D01*
G01X1533992Y851722D02*
Y854025D01*
G01X1533611Y856944D02*
Y856796D01*
G01X1533205Y889360D02*
Y889951D01*
G01Y886604D02*
Y888179D01*
G01Y884833D02*
Y885423D01*
G01X1532846Y868612D02*
Y870187D01*
G01X1532811D02*
Y868612D01*
G01X1532787Y870187D02*
Y868612D01*
G01X1532220Y884833D02*
Y889951D01*
G01X1532024D02*
Y884833D01*
G01X1531630Y887687D02*
Y889655D01*
G01Y887096D02*
Y885128D01*
G01X1531464Y868612D02*
Y870187D01*
G01X1531094D02*
Y868612D01*
G01X1530806Y861151D02*
Y860413D01*
G01X1529624Y855246D02*
Y855984D01*
G01X1529016Y868612D02*
Y870187D01*
G01X1528646D02*
Y868612D01*
G01X1528480Y887687D02*
Y889655D01*
G01Y887096D02*
Y885128D01*
G01X1528087Y852214D02*
Y854655D01*
G01Y860403D02*
Y856624D01*
G01Y889951D02*
Y884833D01*
G01X1527890D02*
Y889951D01*
G01X1527324Y868612D02*
Y870187D01*
G01X1527299Y868612D02*
Y870187D01*
G01X1527264D02*
Y868612D01*
G01X1527010Y886352D02*
Y885604D01*
G01X1526916D02*
Y886225D01*
G01X1526905Y885423D02*
Y884833D01*
G01Y888179D02*
Y886604D01*
G01Y889951D02*
Y889360D01*
G01X1526823Y886114D02*
Y886241D01*
G01X1525786Y855910D02*
Y855246D01*
G01X1525331Y885128D02*
Y887096D01*
G01Y889655D02*
Y887687D01*
G01X1524149Y862372D02*
Y854025D01*
G01X1532712Y855984D02*
X1532365Y856053D01*
G01X1536804Y851270D02*
X1536549Y851663D01*
G01X1532086Y856234D02*
X1531903Y856499D01*
X1531839Y856798D01*
X1531904Y857094D01*
G01X1544257Y857895D02*
X1544580Y857476D01*
X1544742Y856992D01*
X1544721Y856487D01*
X1544518Y856011D01*
X1544151Y855607D01*
X1543645Y855340D01*
X1543054Y855246D01*
X1542464Y855343D01*
X1541962Y855612D01*
X1541598Y856016D01*
X1541397Y856494D01*
X1541377Y856999D01*
X1541541Y857480D01*
X1541862Y857895D01*
G01X1539090D02*
X1539413Y857476D01*
X1539575Y856992D01*
X1539553Y856487D01*
X1539350Y856011D01*
X1538984Y855607D01*
X1538477Y855340D01*
X1537886Y855246D01*
X1537297Y855343D01*
X1536795Y855612D01*
X1536431Y856016D01*
X1536229Y856494D01*
X1536210Y856999D01*
X1536374Y857480D01*
X1536694Y857895D01*
G01X1541862D02*
X1541410Y858335D01*
X1541140Y858871D01*
X1541070Y859441D01*
X1541211Y860005D01*
X1541558Y860530D01*
X1542085Y860923D01*
X1542728Y861127D01*
X1543407Y861124D01*
X1544047Y860916D01*
X1544570Y860520D01*
X1544912Y859996D01*
X1545050Y859435D01*
X1544978Y858868D01*
X1544708Y858334D01*
G01X1536694Y857895D02*
X1536243Y858335D01*
X1535973Y858871D01*
X1535902Y859441D01*
X1536044Y860005D01*
X1536391Y860530D01*
X1536918Y860923D01*
X1537561Y861127D01*
X1538240Y861124D01*
X1538880Y860916D01*
X1539403Y860520D01*
X1539744Y859996D01*
X1539882Y859435D01*
X1539811Y858868D01*
X1539540Y858334D01*
G01X1543482Y860335D02*
X1543843Y860099D01*
X1544081Y859749D01*
X1544167Y859346D01*
X1544084Y858943D01*
X1543848Y858591D01*
X1543484Y858351D01*
X1543059Y858266D01*
G01X1542636Y858350D02*
X1542276Y858586D01*
X1542038Y858937D01*
X1541952Y859340D01*
X1542035Y859742D01*
X1542271Y860095D01*
X1542635Y860335D01*
X1543059Y860419D01*
G01X1538315Y860335D02*
X1538675Y860099D01*
X1538914Y859749D01*
X1538999Y859346D01*
X1538917Y858943D01*
X1538680Y858591D01*
X1538317Y858351D01*
X1537892Y858266D01*
G01X1537469Y858350D02*
X1537109Y858586D01*
X1536870Y858937D01*
X1536785Y859340D01*
X1536867Y859742D01*
X1537104Y860095D01*
X1537467Y860335D01*
X1537892Y860419D01*
G01X1532366Y856053D02*
X1532086Y856234D01*
G01X1543408Y857543D02*
X1543691Y857365D01*
X1543878Y857100D01*
X1543945Y856798D01*
X1543881Y856498D01*
X1543695Y856231D01*
X1543410Y856050D01*
X1543059Y855984D01*
G01X1542711Y856049D02*
X1542428Y856227D01*
X1542241Y856492D01*
X1542174Y856794D01*
X1542238Y857094D01*
X1542424Y857361D01*
X1542709Y857543D01*
X1543059Y857608D01*
G01X1538241Y857543D02*
X1538524Y857365D01*
X1538711Y857100D01*
X1538778Y856798D01*
X1538713Y856498D01*
X1538528Y856231D01*
X1538243Y856050D01*
X1537892Y855984D01*
G01X1537543Y856049D02*
X1537261Y856227D01*
X1537073Y856492D01*
X1537006Y856794D01*
X1537071Y857094D01*
X1537256Y857361D01*
X1537542Y857543D01*
X1537892Y857608D01*
G01X1509023Y1138612D02*
X1509050Y1138616D01*
X1509075Y1138627D01*
X1509099Y1138645D01*
X1509121Y1138670D01*
X1509138Y1138699D01*
X1509150Y1138733D01*
X1509158Y1138770D01*
X1509161Y1138809D01*
G01X1509023Y1135463D02*
X1509050Y1135466D01*
X1509075Y1135477D01*
X1509099Y1135495D01*
X1509121Y1135520D01*
X1509138Y1135550D01*
X1509150Y1135584D01*
X1509158Y1135620D01*
X1509161Y1135659D01*
G01X1503974Y1136250D02*
X1503846Y1136222D01*
X1503758Y1136149D01*
X1503727Y1136053D01*
G01X1503974Y1133100D02*
X1503846Y1133073D01*
X1503758Y1133000D01*
X1503727Y1132903D01*
G01X1503974Y1129951D02*
X1503846Y1129923D01*
X1503758Y1129850D01*
X1503727Y1129754D01*
G01X1503974Y1126801D02*
X1503846Y1126773D01*
X1503758Y1126700D01*
X1503727Y1126604D01*
G01X1510338Y1138809D02*
X1503727D01*
G01X1503974Y1138612D02*
X1510058D01*
G01X1509749Y1136585D02*
X1504004D01*
G01X1503974Y1136250D02*
X1510058D01*
G01X1503727Y1136053D02*
X1510338D01*
G01X1510176Y1135994D02*
X1503590D01*
G01X1510338Y1135659D02*
X1503727D01*
G01X1503590Y1135600D02*
X1510176D01*
G01X1503974Y1135463D02*
X1510058D01*
G01X1504004Y1135010D02*
X1509749D01*
G01X1503974Y1133100D02*
X1510058D01*
G01X1503727Y1132903D02*
X1510338D01*
G01Y1132510D02*
X1503727D01*
G01X1503974Y1132313D02*
X1510058D01*
G01X1509749Y1131585D02*
X1504004D01*
G01X1510176Y1130994D02*
X1503590D01*
G01Y1130600D02*
X1510176D01*
G01X1504004Y1130010D02*
X1509749D01*
G01X1503974Y1129951D02*
X1510058D01*
G01X1503727Y1129754D02*
X1510338D01*
G01Y1129360D02*
X1503727D01*
G01X1503974Y1129163D02*
X1510058D01*
G01X1503974Y1126801D02*
X1510058D01*
G01X1503727Y1126604D02*
X1510338D01*
G01X1509749Y1126585D02*
X1504004D01*
G01X1510338Y1126211D02*
X1503727D01*
G01X1503974Y1126014D02*
X1510058D01*
G01X1510176Y1125994D02*
X1503590D01*
G01Y1125600D02*
X1510176D01*
G01X1504004Y1125010D02*
X1509749D01*
G01X1501709Y1121978D02*
X1520212D01*
G01X1499740Y1121585D02*
X1530449D01*
G01X1509023Y1132313D02*
X1509050Y1132317D01*
X1509075Y1132328D01*
X1509099Y1132346D01*
X1509121Y1132371D01*
X1509138Y1132400D01*
X1509150Y1132434D01*
X1509158Y1132471D01*
X1509161Y1132510D01*
G01X1509023Y1129163D02*
X1509050Y1129167D01*
X1509075Y1129178D01*
X1509099Y1129196D01*
X1509121Y1129221D01*
X1509138Y1129251D01*
X1509150Y1129284D01*
X1509158Y1129321D01*
X1509161Y1129360D01*
G01X1509023Y1126014D02*
X1509050Y1126017D01*
X1509075Y1126029D01*
X1509099Y1126047D01*
X1509121Y1126071D01*
X1509138Y1126101D01*
X1509150Y1126135D01*
X1509158Y1126172D01*
X1509161Y1126211D01*
G01X1503974Y1138612D02*
X1503847Y1138639D01*
X1503758Y1138712D01*
X1503727Y1138809D01*
G01X1501709Y1117057D02*
X1551709D01*
G01X1499740D02*
X1496457D01*
G01X1497772Y1109892D02*
X1524149D01*
G01X1551709Y1108711D02*
X1497772D01*
G01X1501709Y1121978D02*
X1499740Y1120010D01*
G01X1509749Y1125010D02*
X1510176Y1125600D01*
G01X1509749Y1130010D02*
X1510176Y1130600D01*
G01X1509749Y1135010D02*
X1510176Y1135600D01*
G01X1508572Y1136250D02*
X1508610Y1136223D01*
X1508638Y1136151D01*
X1508648Y1136053D01*
G01X1508572Y1133100D02*
X1508610Y1133074D01*
X1508638Y1133002D01*
X1508648Y1132903D01*
G01X1508572Y1129951D02*
X1508610Y1129924D01*
X1508638Y1129852D01*
X1508648Y1129754D01*
G01X1508572Y1126801D02*
X1508610Y1126775D01*
X1508638Y1126703D01*
X1508648Y1126604D01*
G01X1504004Y1126585D02*
X1503865Y1126389D01*
X1503727Y1126192D01*
X1503590Y1125994D01*
G01X1504004Y1131585D02*
X1503865Y1131389D01*
X1503727Y1131192D01*
X1503590Y1130994D01*
G01X1504004Y1136585D02*
X1503865Y1136389D01*
X1503727Y1136192D01*
X1503590Y1135994D01*
G01X1509332Y1125600D02*
X1509060Y1125010D01*
G01X1509332Y1130600D02*
X1509060Y1130010D01*
G01X1509332Y1135600D02*
X1509060Y1135010D01*
G01X1509749Y1136585D02*
X1510176Y1135994D01*
G01X1509749Y1131585D02*
X1510176Y1130994D01*
G01X1499740Y1119025D02*
X1501709Y1117057D01*
G01X1497714Y1109441D02*
X1497767Y1109818D01*
G01X1508208Y1125600D02*
X1508130Y1125010D01*
G01Y1130010D02*
X1508208Y1130600D01*
G01Y1135600D02*
X1508130Y1135010D01*
G01X1497714Y1109442D02*
X1497677Y1109119D01*
X1497683Y1108878D01*
X1497740Y1108742D01*
G01X1508648Y1126211D02*
X1508638Y1126112D01*
X1508610Y1126040D01*
X1508572Y1126014D01*
G01X1508648Y1129360D02*
X1508638Y1129262D01*
X1508610Y1129190D01*
X1508572Y1129163D01*
G01X1508648Y1132510D02*
X1508638Y1132411D01*
X1508610Y1132339D01*
X1508572Y1132313D01*
G01X1508648Y1135659D02*
X1508638Y1135561D01*
X1508610Y1135489D01*
X1508572Y1135463D01*
G01X1508648Y1138809D02*
X1508638Y1138711D01*
X1508610Y1138639D01*
X1508572Y1138612D01*
G01X1508208Y1135994D02*
X1508130Y1136585D01*
G01Y1131585D02*
X1508208Y1130994D01*
G01Y1125994D02*
X1508130Y1126585D01*
G01X1503727Y1135659D02*
X1503758Y1135562D01*
X1503847Y1135490D01*
X1503974Y1135463D01*
G01X1503727Y1132510D02*
X1503758Y1132413D01*
X1503847Y1132341D01*
X1503974Y1132313D01*
G01X1503727Y1129360D02*
X1503758Y1129263D01*
X1503847Y1129191D01*
X1503974Y1129163D01*
G01X1503727Y1126211D02*
X1503758Y1126114D01*
X1503847Y1126041D01*
X1503974Y1126014D01*
G01X1497740Y1108742D02*
X1497682Y1108882D01*
X1497677Y1109122D01*
G01X1509060Y1136585D02*
X1509332Y1135994D01*
G01X1509060Y1131585D02*
X1509332Y1130994D01*
G01X1509060Y1126585D02*
X1509332Y1125994D01*
G01X1503590Y1135600D02*
X1503727Y1135403D01*
X1503865Y1135206D01*
X1504004Y1135010D01*
G01X1503590Y1130600D02*
X1503727Y1130403D01*
X1503865Y1130206D01*
X1504004Y1130010D01*
G01X1503590Y1125600D02*
X1503727Y1125403D01*
X1503865Y1125206D01*
X1504004Y1125010D01*
G01X1509749Y1126585D02*
X1510176Y1125994D01*
G01X1510338Y1138809D02*
Y1139203D01*
G01Y1135659D02*
Y1136053D01*
G01Y1132510D02*
Y1132903D01*
G01Y1129360D02*
Y1129754D01*
G01Y1126211D02*
Y1126604D01*
G01X1510176Y1125994D02*
Y1125600D01*
G01Y1130994D02*
Y1130600D01*
G01Y1135994D02*
Y1135600D01*
G01X1509332Y1125994D02*
Y1125600D01*
G01Y1130994D02*
Y1130600D01*
G01Y1135994D02*
Y1135600D01*
G01X1509161Y1138809D02*
Y1139203D01*
G01Y1135659D02*
Y1136053D01*
G01Y1132510D02*
Y1132903D01*
G01Y1129360D02*
Y1129754D01*
G01Y1126211D02*
Y1126604D01*
G01X1508648D02*
Y1126211D01*
G01Y1129754D02*
Y1129360D01*
G01Y1136053D02*
Y1135659D01*
G01Y1132903D02*
Y1132510D01*
G01Y1139203D02*
Y1138809D01*
G01X1508208Y1135600D02*
Y1135994D01*
G01Y1125600D02*
Y1125994D01*
G01Y1130994D02*
Y1130600D01*
G01X1503727Y1126604D02*
Y1126211D01*
G01Y1129754D02*
Y1129360D01*
G01Y1136053D02*
Y1135659D01*
G01Y1132903D02*
Y1132510D01*
G01Y1139203D02*
Y1138809D01*
G01X1503590Y1135600D02*
Y1135994D01*
G01Y1130600D02*
Y1130994D01*
G01Y1125600D02*
Y1125994D01*
G01X1501709Y1254616D02*
Y1121978D01*
G01X1500921Y1121191D02*
Y1192096D01*
G01X1500862Y1121585D02*
Y1255010D01*
G01X1499740Y1259537D02*
Y1117057D01*
G01X1497772D02*
Y1109892D01*
G01X1509161Y1136053D02*
X1509158Y1136091D01*
X1509151Y1136128D01*
X1509138Y1136162D01*
X1509121Y1136192D01*
X1509100Y1136217D01*
X1509076Y1136235D01*
X1509050Y1136246D01*
X1509023Y1136250D01*
G01X1509161Y1132903D02*
X1509158Y1132942D01*
X1509151Y1132978D01*
X1509138Y1133012D01*
X1509121Y1133043D01*
X1509100Y1133067D01*
X1509076Y1133085D01*
X1509050Y1133096D01*
X1509023Y1133100D01*
G01X1509161Y1129754D02*
X1509158Y1129792D01*
X1509151Y1129829D01*
X1509138Y1129863D01*
X1509121Y1129893D01*
X1509100Y1129917D01*
X1509076Y1129936D01*
X1509050Y1129947D01*
X1509023Y1129951D01*
G01X1509161Y1126604D02*
X1509158Y1126642D01*
X1509151Y1126679D01*
X1509138Y1126713D01*
X1509121Y1126743D01*
X1509100Y1126768D01*
X1509076Y1126786D01*
X1509050Y1126797D01*
X1509023Y1126801D01*
G01X1543875Y1112537D02*
G03X1542450I-713J83D01*
G01X1542889Y1109913D02*
G03X1544475Y1110199I265J3073D01*
G01X1543223Y1110903D02*
G03X1543814Y1111268I9J646D01*
G01X1542450Y1111711D02*
G03X1543223Y1110903I792J-16D01*
G01X1544475Y1110199D02*
G03X1545318Y1111268I-704J1422D01*
G01X1545109Y1113154D02*
G03X1543875Y1114128I-1735J-930D01*
G01X1542232Y1114084D02*
G03X1541068Y1112946I730J-1911D01*
G01X1541154Y1110930D02*
G03X1542893Y1109912I1807J1093D01*
G01X1543875Y1114128D02*
G03X1542232Y1114084I-756J-2475D01*
G01X1540894Y1111790D02*
G03X1541156Y1110927I2971J431D01*
G01X1545448Y1111712D02*
G03X1545109Y1113154I-3015J52D01*
G01X1540894Y1112285D02*
G03Y1111788I3524J-249D01*
G01X1541068Y1112946D02*
G03X1540894Y1112285I4018J-1411D01*
G01X1541472Y1113494D02*
G03I-2165J0D01*
G01X1541261Y1110777D02*
G03Y1116211I-1954J2717D01*
G01X1537353D02*
G03Y1110777I1954J-2717D01*
G01X1542811Y1113494D02*
G03I-3504J0D01*
G01X1537003Y1117392D02*
G03Y1109596I2304J-3898D01*
G01X1541611D02*
G03Y1117392I-2304J3898D01*
G01X1535250Y1111221D02*
G03X1536723I736J278D01*
G01Y1112906D02*
G03X1535250I-737J-278D01*
G01X1533978Y1110886D02*
G03X1534499Y1110321I1351J723D01*
G01X1537545Y1110323D02*
G03X1538065Y1110888I-832J1287D01*
G01Y1113200D02*
G03X1537544Y1113766I-1352J-722D01*
G01X1534498Y1113765D02*
G03X1533977Y1113200I830J-1288D01*
G01X1535250Y1112906D02*
G03Y1111221I2236J-842D01*
G01X1533977Y1113200D02*
G03X1533978Y1110886I2163J-1156D01*
G01X1538065Y1110888D02*
G03Y1113200I-2163J1156D01*
G01X1534499Y1110321D02*
G03X1537545Y1110323I1521J2363D01*
G01X1537544Y1113766D02*
G03X1534498Y1113765I-1522J-2362D01*
G01X1531945Y1125010D02*
G03X1531551Y1124616I0J-394D01*
G01Y1126978D02*
G03X1531945Y1126585I394J1D01*
G01Y1135010D02*
G03X1531551Y1134616I0J-394D01*
G01Y1136978D02*
G03X1531945Y1136585I394J1D01*
G01Y1130010D02*
G03X1531551Y1129616I0J-394D01*
G01Y1131978D02*
G03X1531945Y1131585I394J1D01*
G01X1533043Y1113041D02*
G03X1532749Y1113713I-913J1D01*
G01X1532220Y1100108D02*
G03Y1103258I0J1575D01*
G01X1536723Y1111221D02*
G03Y1112906I-2237J843D01*
G01X1528761Y1112637D02*
G03X1527330I-716J0D01*
G01X1531651D02*
G03X1530220I-716J0D01*
G01X1527890Y1103258D02*
G03Y1100108I0J-1575D01*
G01X1532749Y1113713D02*
G03X1530114Y1113568I-1247J-1352D01*
G01D02*
G03X1527333Y1113562I-1388J-1207D01*
G01X1542457Y1138612D02*
X1530449D01*
G01X1549937D02*
X1542605D01*
G01X1530449Y1138592D02*
X1531551D01*
G01X1534976Y1137372D02*
X1533992D01*
G01X1534976Y1137175D02*
X1533992D01*
G01X1534976Y1136781D02*
X1533992D01*
G01X1531945Y1136585D02*
X1539110D01*
G01X1542605Y1136250D02*
X1549937D01*
G01X1542457D02*
X1530449D01*
G01X1542457Y1135463D02*
X1530449D01*
G01X1549937D02*
X1542605D01*
G01X1531945Y1135010D02*
X1539110D01*
G01X1534976Y1134813D02*
X1533992D01*
G01X1534976Y1134419D02*
X1533992D01*
G01X1534976Y1134222D02*
X1533992D01*
G01X1542605Y1133100D02*
X1549937D01*
G01X1542457D02*
X1530449D01*
G01X1534976Y1132372D02*
X1533992D01*
G01X1542457Y1132313D02*
X1530449D01*
G01X1549937D02*
X1542605D01*
G01X1534976Y1132175D02*
X1533992D01*
G01X1534976Y1131781D02*
X1533992D01*
G01X1539110Y1131585D02*
X1531945D01*
G01X1539110Y1130010D02*
X1531945D01*
G01X1542605Y1129951D02*
X1549937D01*
G01X1542457D02*
X1530449D01*
G01X1534976Y1129813D02*
X1533992D01*
G01X1534976Y1129419D02*
X1533992D01*
G01X1534976Y1129222D02*
X1533992D01*
G01X1542457Y1129163D02*
X1530449D01*
G01X1549937D02*
X1542605D01*
G01X1534976Y1127372D02*
X1533992D01*
G01X1534976Y1127175D02*
X1533992D01*
G01X1542605Y1126801D02*
X1549937D01*
G01X1542457D02*
X1530449D01*
G01X1534976Y1126781D02*
X1533992D01*
G01X1531945Y1126585D02*
X1539110D01*
G01X1542457Y1126014D02*
X1530449D01*
G01X1549937D02*
X1542605D01*
G01X1531945Y1125010D02*
X1539110D01*
G01X1534976Y1124813D02*
X1533992D01*
G01X1534976Y1124419D02*
X1533992D01*
G01X1544551Y1124340D02*
X1535567D01*
G01X1534976Y1124222D02*
X1533992D01*
G01X1531551Y1122766D02*
X1522181D01*
G01X1551709Y1122588D02*
X1531551D01*
G01X1521866Y1122175D02*
X1528401D01*
G01X1531551Y1120994D02*
X1522181D01*
G01X1550916Y1119813D02*
X1530449D01*
G01X1536549Y1119419D02*
X1530449D01*
G01X1536549Y1119360D02*
X1530449D01*
G01X1551709Y1118829D02*
X1528087D01*
G01X1541611Y1117392D02*
X1537003D01*
G01X1551709Y1116427D02*
X1528087D01*
G01X1537353Y1116211D02*
X1541261D01*
G01X1540303Y1115866D02*
X1538843D01*
G01X1551709Y1114459D02*
X1528087D01*
G01X1527333Y1114119D02*
X1525890D01*
G01X1549942D02*
X1548560D01*
G01X1547265D02*
X1545648D01*
G01X1543875Y1112537D02*
X1542450D01*
G01X1545448Y1111712D02*
X1542449D01*
G01X1545318Y1111268D02*
X1543814D01*
G01X1541261Y1110777D02*
X1537353D01*
G01X1551709Y1110679D02*
X1528087D01*
G01X1527330Y1110112D02*
X1525890D01*
G01X1530220D02*
X1528761D01*
G01X1533043D02*
X1531651D01*
G01X1540303D02*
X1538843D01*
G01X1549968D02*
X1548419D01*
G01X1546882D02*
X1545474D01*
G01X1537003Y1109596D02*
X1541611D01*
G01X1538244Y1105955D02*
X1521866D01*
G01X1527890Y1103258D02*
X1532220D01*
G01X1527264Y1102470D02*
X1532846D01*
G01Y1100896D02*
X1527264D01*
G01X1532220Y1100108D02*
X1527890D01*
G01X1521866Y1095777D02*
X1538244D01*
G01X1549942Y1114119D02*
X1548647Y1112268D01*
G01X1548560Y1114119D02*
X1547870Y1113133D01*
G01X1546917Y1112259D02*
X1545474Y1110112D01*
G01X1536549Y1119419D02*
X1536804Y1119813D01*
G01X1547673Y1111390D02*
X1546882Y1110112D01*
G01X1541261Y1116211D02*
X1541279Y1116266D01*
X1541331Y1116431D01*
X1541410Y1116690D01*
X1541506Y1117017D01*
X1541611Y1117392D01*
G01X1537003Y1109596D02*
X1537106Y1109965D01*
X1537203Y1110295D01*
X1537283Y1110557D01*
X1537335Y1110723D01*
X1537353Y1110777D01*
G01X1547673Y1111390D02*
X1548419Y1110112D01*
G01X1548647Y1112268D02*
X1549968Y1110112D01*
G01X1547265Y1114119D02*
X1547870Y1113133D01*
G01X1545648Y1114119D02*
X1546917Y1112259D01*
G01X1551709Y1108711D02*
Y1122588D01*
G01X1551391Y1117057D02*
Y1122588D01*
G01X1550916Y1119813D02*
Y1122588D01*
G01X1549937Y1126801D02*
Y1126014D01*
G01Y1129951D02*
Y1129163D01*
G01Y1136250D02*
Y1135463D01*
G01Y1133100D02*
Y1132313D01*
G01Y1139400D02*
Y1138612D01*
G01X1548163Y1126801D02*
Y1126014D01*
G01Y1129951D02*
Y1129163D01*
G01Y1136250D02*
Y1135463D01*
G01Y1133100D02*
Y1132313D01*
G01Y1139400D02*
Y1138612D01*
G01X1547975D02*
Y1139400D01*
G01Y1135463D02*
Y1136250D01*
G01Y1132313D02*
Y1133100D01*
G01Y1129163D02*
Y1129951D01*
G01Y1126014D02*
Y1126801D01*
G01X1545138Y1138612D02*
Y1139400D01*
G01Y1135463D02*
Y1136250D01*
G01Y1132313D02*
Y1133100D01*
G01Y1129163D02*
Y1129951D01*
G01Y1126014D02*
Y1126801D01*
G01X1545062Y1119813D02*
Y1117057D01*
G01X1544551Y1119813D02*
Y1256781D01*
G01X1544197Y1126801D02*
Y1126014D01*
G01Y1129951D02*
Y1129163D01*
G01Y1136250D02*
Y1135463D01*
G01Y1133100D02*
Y1132313D01*
G01Y1139400D02*
Y1138612D01*
G01X1542605Y1126801D02*
Y1126014D01*
G01Y1129951D02*
Y1129163D01*
G01Y1136250D02*
Y1135463D01*
G01Y1133100D02*
Y1132313D01*
G01Y1139400D02*
Y1138612D01*
G01X1542457Y1126801D02*
Y1126014D01*
G01Y1129951D02*
Y1129163D01*
G01Y1136250D02*
Y1135463D01*
G01Y1133100D02*
Y1132313D01*
G01Y1139400D02*
Y1138612D01*
G01X1541519Y1136250D02*
Y1138612D01*
G01Y1133100D02*
Y1135463D01*
G01Y1129951D02*
Y1132313D01*
G01Y1126801D02*
Y1129163D01*
G01Y1124340D02*
Y1126014D01*
G01X1540303Y1115866D02*
Y1110112D01*
G01X1539791Y1126801D02*
Y1126014D01*
G01Y1129951D02*
Y1129163D01*
G01Y1136250D02*
Y1135463D01*
G01Y1133100D02*
Y1132313D01*
G01Y1139400D02*
Y1138612D01*
G01X1539110Y1135010D02*
Y1136585D01*
G01Y1130010D02*
Y1131585D01*
G01Y1125010D02*
Y1126585D01*
G01X1538843Y1110112D02*
Y1115866D01*
G01X1538244Y1108711D02*
Y1095777D01*
G01X1538139Y1138612D02*
Y1139400D01*
G01Y1135463D02*
Y1136250D01*
G01Y1132313D02*
Y1133100D01*
G01Y1129163D02*
Y1129951D01*
G01Y1126014D02*
Y1126801D01*
G01X1537188Y1119813D02*
Y1117057D01*
G01X1536549Y1119360D02*
Y1119419D01*
G01X1536156Y1138612D02*
Y1139400D01*
G01Y1135463D02*
Y1136250D01*
G01Y1132313D02*
Y1133100D01*
G01Y1129163D02*
Y1129951D01*
G01Y1126014D02*
Y1126801D01*
G01X1536021Y1254203D02*
Y1122588D01*
G01X1535961Y1126585D02*
Y1125010D01*
G01Y1131585D02*
Y1130010D01*
G01Y1136585D02*
Y1135010D01*
G01X1535567Y1256781D02*
Y1119813D01*
G01X1534976Y1127372D02*
Y1124222D01*
G01Y1132372D02*
Y1129222D01*
G01Y1137372D02*
Y1134222D01*
G01X1533992Y1117057D02*
Y1119360D01*
G01Y1127372D02*
Y1124222D01*
G01Y1132372D02*
Y1129222D01*
G01Y1137372D02*
Y1134222D01*
G01X1533043Y1113041D02*
Y1110112D01*
G01X1533008Y1126585D02*
Y1125010D01*
G01Y1131585D02*
Y1130010D01*
G01Y1136585D02*
Y1135010D01*
G01X1532846Y1100896D02*
Y1102470D01*
G01X1532811D02*
Y1100896D01*
G01X1532793Y1126801D02*
Y1126014D01*
G01Y1129951D02*
Y1129163D01*
G01Y1136250D02*
Y1135463D01*
G01Y1133100D02*
Y1132313D01*
G01Y1139400D02*
Y1138612D01*
G01X1532787Y1102470D02*
Y1100896D01*
G01X1532417Y1126801D02*
Y1126014D01*
G01Y1129951D02*
Y1129163D01*
G01Y1136250D02*
Y1135463D01*
G01Y1133100D02*
Y1132313D01*
G01Y1139400D02*
Y1138612D01*
G01X1532391Y1126801D02*
Y1126014D01*
G01Y1129951D02*
Y1129163D01*
G01Y1136250D02*
Y1135463D01*
G01Y1133100D02*
Y1132313D01*
G01Y1139400D02*
Y1138612D01*
G01X1531651Y1110112D02*
Y1112637D01*
G01X1531551Y1256781D02*
Y1119813D01*
G01X1531464Y1100896D02*
Y1102470D01*
G01X1531094D02*
Y1100896D01*
G01X1530449Y1119360D02*
Y1257234D01*
G01X1530220Y1112637D02*
Y1110112D01*
G01X1529016Y1100896D02*
Y1102470D01*
G01X1528761Y1110112D02*
Y1112637D01*
G01X1528646Y1102470D02*
Y1100896D01*
G01X1528401Y1254419D02*
Y1122175D01*
G01X1528087Y1114459D02*
Y1110679D01*
G01Y1118829D02*
Y1116427D01*
G01X1527333Y1114119D02*
Y1113562D01*
G01X1527330Y1112637D02*
Y1110112D01*
G01X1527324Y1100896D02*
Y1102470D01*
G01X1527299Y1100896D02*
Y1102470D01*
G01X1527264D02*
Y1100896D01*
G01X1526433Y1139695D02*
Y1122175D01*
G01X1525890Y1114119D02*
Y1110112D01*
G01X1524149Y1108711D02*
Y1117057D01*
G01X1522181Y1122766D02*
Y1120994D01*
G01X1521866Y1122175D02*
Y1095777D01*
G01X1520212Y1121978D02*
Y1254616D01*
G01X1541261Y1110777D02*
X1541279Y1110722D01*
X1541331Y1110556D01*
X1541410Y1110297D01*
X1541506Y1109970D01*
X1541611Y1109596D01*
G01X1537353Y1116211D02*
X1537335Y1116266D01*
X1537283Y1116432D01*
X1537204Y1116691D01*
X1537108Y1117018D01*
X1537003Y1117392D01*
G01X1508207Y1140994D02*
X1501621D01*
G01Y1140600D02*
X1508207D01*
G01X1502036Y1140010D02*
X1507781D01*
G01X1528401Y1139695D02*
X1501709D01*
G01X1503974Y1139400D02*
X1510058D01*
G01X1503727Y1139203D02*
X1510338D01*
G01X1508572Y1139400D02*
X1508610Y1139373D01*
X1508638Y1139301D01*
X1508648Y1139203D01*
G01X1507781Y1140010D02*
X1508207Y1140600D01*
G01X1502036Y1141585D02*
X1501896Y1141389D01*
X1501758Y1141192D01*
X1501621Y1140994D01*
G01X1507364Y1140600D02*
X1507091Y1140010D01*
G01X1507781Y1141585D02*
X1508207Y1140994D01*
G01X1503727Y1139203D02*
X1503760Y1139302D01*
X1503848Y1139373D01*
X1503974Y1139400D01*
G01X1506239Y1140600D02*
X1506161Y1140010D01*
G01X1506239Y1140994D02*
X1506161Y1141585D01*
G01X1507091D02*
X1507364Y1140994D01*
G01X1501621Y1140600D02*
X1501758Y1140403D01*
X1501896Y1140206D01*
X1502036Y1140010D01*
G01X1508207Y1140994D02*
Y1140600D01*
G01X1507364Y1140994D02*
Y1140600D01*
G01X1506239D02*
Y1140994D01*
G01X1501621Y1140600D02*
Y1140994D01*
G01X1509161Y1139203D02*
X1509158Y1139241D01*
X1509151Y1139278D01*
X1509138Y1139312D01*
X1509121Y1139342D01*
X1509100Y1139366D01*
X1509076Y1139384D01*
X1509050Y1139396D01*
X1509023Y1139400D01*
G01Y1211053D02*
X1509050Y1211057D01*
X1509075Y1211068D01*
X1509099Y1211086D01*
X1509121Y1211111D01*
X1509138Y1211140D01*
X1509150Y1211174D01*
X1509158Y1211211D01*
X1509161Y1211250D01*
G01X1503964Y1210559D02*
X1503838Y1210531D01*
X1503748Y1210459D01*
X1503717Y1210362D01*
G01X1503964Y1207409D02*
X1503838Y1207382D01*
X1503748Y1207309D01*
X1503717Y1207212D01*
G01X1503964Y1204260D02*
X1503838Y1204232D01*
X1503748Y1204159D01*
X1503717Y1204063D01*
G01X1503964Y1201110D02*
X1503838Y1201083D01*
X1503748Y1201010D01*
X1503717Y1200913D01*
G01X1503974Y1211840D02*
X1503846Y1211813D01*
X1503758Y1211740D01*
X1503727Y1211644D01*
G01X1503974Y1208691D02*
X1503846Y1208663D01*
X1503758Y1208590D01*
X1503727Y1208494D01*
G01X1503974Y1205541D02*
X1503846Y1205513D01*
X1503758Y1205441D01*
X1503727Y1205344D01*
G01X1503974Y1202392D02*
X1503846Y1202364D01*
X1503758Y1202291D01*
X1503727Y1202195D01*
G01X1503974Y1199242D02*
X1503846Y1199214D01*
X1503758Y1199141D01*
X1503727Y1199045D01*
G01X1503974Y1196092D02*
X1503846Y1196065D01*
X1503758Y1195992D01*
X1503727Y1195896D01*
G01X1503974Y1192943D02*
X1503846Y1192915D01*
X1503758Y1192842D01*
X1503727Y1192746D01*
G01X1503974Y1189793D02*
X1503846Y1189765D01*
X1503758Y1189693D01*
X1503727Y1189596D01*
G01X1503974Y1186644D02*
X1503846Y1186616D01*
X1503758Y1186543D01*
X1503727Y1186447D01*
G01X1503974Y1183494D02*
X1503846Y1183466D01*
X1503758Y1183393D01*
X1503727Y1183297D01*
G01X1503974Y1180344D02*
X1503846Y1180317D01*
X1503758Y1180244D01*
X1503727Y1180148D01*
G01X1503974Y1177195D02*
X1503846Y1177167D01*
X1503758Y1177094D01*
X1503727Y1176998D01*
G01X1503974Y1174045D02*
X1503846Y1174017D01*
X1503758Y1173945D01*
X1503727Y1173848D01*
G01Y1211644D02*
X1510338D01*
G01Y1211250D02*
X1503727D01*
G01X1503974Y1211053D02*
X1510058D01*
G01X1509772Y1210559D02*
X1503964D01*
G01X1510035Y1210362D02*
X1503717D01*
G01Y1209378D02*
X1510035D01*
G01X1509772Y1209181D02*
X1503964D01*
G01X1503974Y1208691D02*
X1510058D01*
G01X1503727Y1208494D02*
X1510338D01*
G01Y1208100D02*
X1503727D01*
G01X1503974Y1207903D02*
X1510058D01*
G01X1509772Y1207409D02*
X1503964D01*
G01X1510035Y1207212D02*
X1503717D01*
G01Y1206228D02*
X1510035D01*
G01X1509772Y1206031D02*
X1503964D01*
G01X1503974Y1205541D02*
X1510058D01*
G01X1503727Y1205344D02*
X1510338D01*
G01Y1204951D02*
X1503727D01*
G01X1503974Y1204754D02*
X1510058D01*
G01X1509772Y1204260D02*
X1503964D01*
G01X1510035Y1204063D02*
X1503717D01*
G01Y1203078D02*
X1510035D01*
G01X1509772Y1202882D02*
X1503964D01*
G01X1503974Y1202392D02*
X1510058D01*
G01X1503727Y1202195D02*
X1510338D01*
G01Y1201801D02*
X1503727D01*
G01X1503974Y1201604D02*
X1510058D01*
G01X1509772Y1201110D02*
X1503964D01*
G01X1510035Y1200913D02*
X1503717D01*
G01Y1199929D02*
X1510035D01*
G01X1509772Y1199732D02*
X1503964D01*
G01X1503974Y1199242D02*
X1510058D01*
G01X1503727Y1199045D02*
X1510338D01*
G01Y1198651D02*
X1503727D01*
G01X1506209Y1198553D02*
X1528401D01*
G01X1520212Y1198533D02*
X1501709D01*
G01X1503974Y1198455D02*
X1510058D01*
G01X1506209Y1197372D02*
X1499740D01*
G01X1509023Y1207903D02*
X1509050Y1207907D01*
X1509075Y1207918D01*
X1509099Y1207936D01*
X1509121Y1207961D01*
X1509138Y1207991D01*
X1509150Y1208025D01*
X1509158Y1208061D01*
X1509161Y1208100D01*
G01X1509023Y1204754D02*
X1509050Y1204758D01*
X1509075Y1204769D01*
X1509099Y1204787D01*
X1509121Y1204811D01*
X1509138Y1204841D01*
X1509150Y1204875D01*
X1509158Y1204912D01*
X1509161Y1204951D01*
G01X1509023Y1201604D02*
X1509050Y1201608D01*
X1509075Y1201619D01*
X1509099Y1201637D01*
X1509121Y1201662D01*
X1509138Y1201692D01*
X1509150Y1201725D01*
X1509158Y1201762D01*
X1509161Y1201801D01*
G01X1509023Y1198455D02*
X1509050Y1198458D01*
X1509075Y1198469D01*
X1509099Y1198488D01*
X1509121Y1198512D01*
X1509138Y1198542D01*
X1509150Y1198576D01*
X1509158Y1198613D01*
X1509161Y1198651D01*
G01X1509023Y1195305D02*
X1509050Y1195309D01*
X1509075Y1195320D01*
X1509099Y1195338D01*
X1509121Y1195363D01*
X1509138Y1195392D01*
X1509150Y1195426D01*
X1509158Y1195463D01*
X1509161Y1195502D01*
G01X1509023Y1192155D02*
X1509050Y1192159D01*
X1509075Y1192170D01*
X1509099Y1192188D01*
X1509121Y1192213D01*
X1509138Y1192243D01*
X1509150Y1192277D01*
X1509158Y1192313D01*
X1509161Y1192352D01*
G01X1509023Y1189006D02*
X1509050Y1189010D01*
X1509075Y1189021D01*
X1509099Y1189039D01*
X1509121Y1189063D01*
X1509138Y1189093D01*
X1509150Y1189127D01*
X1509158Y1189164D01*
X1509161Y1189203D01*
G01X1509023Y1185856D02*
X1509050Y1185860D01*
X1509075Y1185871D01*
X1509099Y1185889D01*
X1509121Y1185914D01*
X1509138Y1185944D01*
X1509150Y1185977D01*
X1509158Y1186014D01*
X1509161Y1186053D01*
G01X1509023Y1182707D02*
X1509050Y1182710D01*
X1509075Y1182721D01*
X1509099Y1182739D01*
X1509121Y1182764D01*
X1509138Y1182794D01*
X1509150Y1182828D01*
X1509158Y1182865D01*
X1509161Y1182903D01*
G01X1509023Y1179557D02*
X1509050Y1179561D01*
X1509075Y1179572D01*
X1509099Y1179590D01*
X1509121Y1179615D01*
X1509138Y1179644D01*
X1509150Y1179678D01*
X1509158Y1179715D01*
X1509161Y1179754D01*
G01X1509023Y1176407D02*
X1509050Y1176411D01*
X1509075Y1176422D01*
X1509099Y1176440D01*
X1509121Y1176465D01*
X1509138Y1176495D01*
X1509150Y1176529D01*
X1509158Y1176565D01*
X1509161Y1176604D01*
G01X1509023Y1173258D02*
X1509050Y1173262D01*
X1509075Y1173273D01*
X1509099Y1173291D01*
X1509121Y1173315D01*
X1509138Y1173345D01*
X1509150Y1173379D01*
X1509158Y1173416D01*
X1509161Y1173455D01*
G01X1509023Y1170108D02*
X1509050Y1170112D01*
X1509075Y1170123D01*
X1509099Y1170141D01*
X1509121Y1170166D01*
X1509138Y1170196D01*
X1509150Y1170229D01*
X1509158Y1170266D01*
X1509161Y1170305D01*
G01X1509023Y1166959D02*
X1509050Y1166962D01*
X1509075Y1166973D01*
X1509099Y1166991D01*
X1509121Y1167016D01*
X1509138Y1167046D01*
X1509150Y1167080D01*
X1509158Y1167117D01*
X1509161Y1167155D01*
G01X1509023Y1163809D02*
X1509050Y1163813D01*
X1509075Y1163824D01*
X1509099Y1163842D01*
X1509121Y1163867D01*
X1509138Y1163896D01*
X1509150Y1163930D01*
X1509158Y1163967D01*
X1509161Y1164006D01*
G01X1509023Y1160659D02*
X1509050Y1160663D01*
X1509075Y1160674D01*
X1509099Y1160692D01*
X1509121Y1160717D01*
X1509138Y1160747D01*
X1509150Y1160781D01*
X1509158Y1160817D01*
X1509161Y1160856D01*
G01X1509023Y1157510D02*
X1509050Y1157513D01*
X1509075Y1157525D01*
X1509099Y1157543D01*
X1509121Y1157567D01*
X1509138Y1157597D01*
X1509150Y1157631D01*
X1509158Y1157668D01*
X1509161Y1157707D01*
G01X1509023Y1154360D02*
X1509050Y1154364D01*
X1509075Y1154375D01*
X1509099Y1154393D01*
X1509121Y1154418D01*
X1509138Y1154447D01*
X1509150Y1154481D01*
X1509158Y1154518D01*
X1509161Y1154557D01*
G01X1509023Y1151211D02*
X1509050Y1151214D01*
X1509075Y1151225D01*
X1509099Y1151243D01*
X1509121Y1151268D01*
X1509138Y1151298D01*
X1509150Y1151332D01*
X1509158Y1151368D01*
X1509161Y1151407D01*
G01X1509023Y1148061D02*
X1509050Y1148065D01*
X1509075Y1148076D01*
X1509099Y1148094D01*
X1509121Y1148119D01*
X1509138Y1148148D01*
X1509150Y1148182D01*
X1509158Y1148219D01*
X1509161Y1148258D01*
G01X1509023Y1144911D02*
X1509050Y1144915D01*
X1509075Y1144926D01*
X1509099Y1144944D01*
X1509121Y1144969D01*
X1509138Y1144999D01*
X1509150Y1145033D01*
X1509158Y1145069D01*
X1509161Y1145108D01*
G01X1509023Y1141762D02*
X1509050Y1141765D01*
X1509075Y1141777D01*
X1509099Y1141795D01*
X1509121Y1141819D01*
X1509138Y1141849D01*
X1509150Y1141883D01*
X1509158Y1141920D01*
X1509161Y1141959D01*
G01X1503974Y1170896D02*
X1503846Y1170868D01*
X1503758Y1170795D01*
X1503727Y1170699D01*
G01X1503974Y1164596D02*
X1503846Y1164569D01*
X1503758Y1164496D01*
X1503727Y1164400D01*
G01X1503974Y1161447D02*
X1503846Y1161419D01*
X1503758Y1161346D01*
X1503727Y1161250D01*
G01X1503974Y1158297D02*
X1503846Y1158269D01*
X1503758Y1158197D01*
X1503727Y1158100D01*
G01X1503974Y1155148D02*
X1503846Y1155120D01*
X1503758Y1155047D01*
X1503727Y1154951D01*
G01X1503974Y1151998D02*
X1503846Y1151970D01*
X1503758Y1151897D01*
X1503727Y1151801D01*
G01X1503974Y1148848D02*
X1503846Y1148821D01*
X1503758Y1148748D01*
X1503727Y1148651D01*
G01X1503974Y1145699D02*
X1503846Y1145671D01*
X1503758Y1145598D01*
X1503727Y1145502D01*
G01X1503974Y1142549D02*
X1503846Y1142521D01*
X1503758Y1142448D01*
X1503727Y1142352D01*
G01X1508945Y1210559D02*
X1508974Y1210555D01*
X1509001Y1210544D01*
X1509027Y1210526D01*
X1509049Y1210501D01*
X1509068Y1210471D01*
X1509081Y1210438D01*
X1509090Y1210401D01*
X1509093Y1210362D01*
G01X1508945Y1207409D02*
X1508974Y1207405D01*
X1509001Y1207394D01*
X1509027Y1207376D01*
X1509049Y1207352D01*
X1509068Y1207322D01*
X1509081Y1207288D01*
X1509090Y1207251D01*
X1509093Y1207212D01*
G01X1508945Y1204260D02*
X1508974Y1204256D01*
X1509001Y1204245D01*
X1509027Y1204227D01*
X1509049Y1204202D01*
X1509068Y1204172D01*
X1509081Y1204138D01*
X1509090Y1204102D01*
X1509093Y1204063D01*
G01X1508945Y1201110D02*
X1508974Y1201106D01*
X1509001Y1201095D01*
X1509027Y1201077D01*
X1509049Y1201052D01*
X1509068Y1201023D01*
X1509081Y1200989D01*
X1509090Y1200952D01*
X1509093Y1200913D01*
G01X1509817Y1196585D02*
X1503904D01*
G01X1528401Y1196191D02*
X1501709D01*
G01X1503974Y1196092D02*
X1510058D01*
G01X1510241Y1195994D02*
X1503499D01*
G01X1503727Y1195896D02*
X1510338D01*
G01X1503499Y1195600D02*
X1510241D01*
G01X1510338Y1195502D02*
X1503727D01*
G01X1503974Y1195305D02*
X1510058D01*
G01X1509817Y1195010D02*
X1503904D01*
G01X1503974Y1192943D02*
X1510058D01*
G01X1503727Y1192746D02*
X1510338D01*
G01Y1192352D02*
X1503727D01*
G01X1503974Y1192155D02*
X1510058D01*
G01X1500751Y1192096D02*
X1520212D01*
G01X1509749Y1191585D02*
X1504004D01*
G01X1510176Y1190994D02*
X1503590D01*
G01Y1190600D02*
X1510176D01*
G01X1504004Y1190010D02*
X1509749D01*
G01X1503974Y1189793D02*
X1510058D01*
G01X1503727Y1189596D02*
X1510338D01*
G01Y1189203D02*
X1503727D01*
G01X1503974Y1189006D02*
X1510058D01*
G01X1503974Y1186644D02*
X1510058D01*
G01X1509749Y1186585D02*
X1504004D01*
G01X1503727Y1186447D02*
X1510338D01*
G01Y1186053D02*
X1503727D01*
G01X1510176Y1185994D02*
X1503590D01*
G01X1503974Y1185856D02*
X1510058D01*
G01X1503590Y1185600D02*
X1510176D01*
G01X1504004Y1185010D02*
X1509749D01*
G01X1503974Y1183494D02*
X1510058D01*
G01X1503727Y1183297D02*
X1510338D01*
G01Y1182903D02*
X1503727D01*
G01X1503974Y1182707D02*
X1510058D01*
G01X1507781Y1181585D02*
X1502036D01*
G01X1508207Y1180994D02*
X1501621D01*
G01Y1180600D02*
X1508207D01*
G01X1503974Y1180344D02*
X1510058D01*
G01X1503727Y1180148D02*
X1510338D01*
G01X1502036Y1180010D02*
X1507781D01*
G01X1501709Y1179852D02*
X1528401D01*
G01X1510338Y1179754D02*
X1503727D01*
G01X1503974Y1179557D02*
X1510058D01*
G01X1528401Y1177490D02*
X1501709D01*
G01X1503974Y1177195D02*
X1510058D01*
G01X1503727Y1176998D02*
X1510338D01*
G01Y1176604D02*
X1503727D01*
G01X1509749Y1176585D02*
X1504004D01*
G01X1503974Y1176407D02*
X1510058D01*
G01X1510176Y1175994D02*
X1503590D01*
G01Y1175600D02*
X1510176D01*
G01X1504004Y1175010D02*
X1509749D01*
G01X1503974Y1174045D02*
X1510058D01*
G01X1503727Y1173848D02*
X1510338D01*
G01Y1173455D02*
X1503727D01*
G01X1503974Y1173258D02*
X1510058D01*
G01X1509749Y1171585D02*
X1504004D01*
G01X1510176Y1170994D02*
X1503590D01*
G01X1503974Y1170896D02*
X1510058D01*
G01X1503727Y1170699D02*
X1510338D01*
G01X1503590Y1170600D02*
X1510176D01*
G01X1510338Y1170305D02*
X1503727D01*
G01X1503974Y1170108D02*
X1510058D01*
G01X1504004Y1170010D02*
X1509749D01*
G01X1503974Y1167746D02*
X1510058D01*
G01X1503727Y1167549D02*
X1510338D01*
G01Y1167155D02*
X1503727D01*
G01X1503974Y1166959D02*
X1510058D01*
G01X1509749Y1166585D02*
X1504004D01*
G01X1510176Y1165994D02*
X1503590D01*
G01Y1165600D02*
X1510176D01*
G01X1504004Y1165010D02*
X1509749D01*
G01X1503974Y1164596D02*
X1510058D01*
G01X1503727Y1164400D02*
X1510338D01*
G01Y1164006D02*
X1503727D01*
G01X1503974Y1163809D02*
X1510058D01*
G01X1509749Y1161585D02*
X1504004D01*
G01X1503974Y1161447D02*
X1510058D01*
G01X1503727Y1161250D02*
X1510338D01*
G01X1510176Y1160994D02*
X1503590D01*
G01X1501709Y1160955D02*
X1528401D01*
G01X1510338Y1160856D02*
X1503727D01*
G01X1503974Y1160659D02*
X1510058D01*
G01X1503590Y1160600D02*
X1510176D01*
G01X1504004Y1160010D02*
X1509749D01*
G01X1528401Y1158592D02*
X1501709D01*
G01X1503974Y1158297D02*
X1510058D01*
G01X1503727Y1158100D02*
X1510338D01*
G01Y1157707D02*
X1503727D01*
G01X1503974Y1157510D02*
X1510058D01*
G01X1509749Y1156585D02*
X1504004D01*
G01X1510176Y1155994D02*
X1503590D01*
G01Y1155600D02*
X1510176D01*
G01X1503974Y1155148D02*
X1510058D01*
G01X1504004Y1155010D02*
X1509749D01*
G01X1503727Y1154951D02*
X1510338D01*
G01Y1154557D02*
X1503727D01*
G01X1503974Y1154360D02*
X1510058D01*
G01X1503974Y1151998D02*
X1510058D01*
G01X1503727Y1151801D02*
X1510338D01*
G01X1509749Y1151585D02*
X1504004D01*
G01X1510338Y1151407D02*
X1503727D01*
G01X1503974Y1151211D02*
X1510058D01*
G01X1510176Y1150994D02*
X1503590D01*
G01Y1150600D02*
X1510176D01*
G01X1504004Y1150010D02*
X1509749D01*
G01X1503974Y1148848D02*
X1510058D01*
G01X1503727Y1148651D02*
X1510338D01*
G01Y1148258D02*
X1503727D01*
G01X1503974Y1148061D02*
X1510058D01*
G01X1509749Y1146585D02*
X1504004D01*
G01X1510176Y1145994D02*
X1503590D01*
G01X1503974Y1145699D02*
X1510058D01*
G01X1503590Y1145600D02*
X1510176D01*
G01X1503727Y1145502D02*
X1510338D01*
G01Y1145108D02*
X1503727D01*
G01X1504004Y1145010D02*
X1509749D01*
G01X1503974Y1144911D02*
X1510058D01*
G01X1503974Y1142549D02*
X1510058D01*
G01X1503727Y1142352D02*
X1510338D01*
G01X1501709Y1142057D02*
X1528401D01*
G01X1510338Y1141959D02*
X1503727D01*
G01X1503974Y1141762D02*
X1510058D01*
G01X1507781Y1141585D02*
X1502036D01*
G01X1503974Y1166959D02*
X1503847Y1166986D01*
X1503758Y1167059D01*
X1503727Y1167155D01*
G01X1508572Y1204754D02*
X1508610Y1204780D01*
X1508638Y1204852D01*
X1508648Y1204951D01*
G01X1507908Y1210559D02*
X1507914Y1210555D01*
X1507920Y1210544D01*
X1507926Y1210526D01*
X1507931Y1210501D01*
X1507935Y1210471D01*
X1507938Y1210438D01*
X1507940Y1210401D01*
X1507941Y1210362D01*
G01X1507908Y1207409D02*
X1507914Y1207405D01*
X1507920Y1207394D01*
X1507926Y1207376D01*
X1507931Y1207352D01*
X1507935Y1207322D01*
X1507938Y1207288D01*
X1507940Y1207251D01*
X1507941Y1207212D01*
G01X1507908Y1204260D02*
X1507914Y1204256D01*
X1507920Y1204245D01*
X1507926Y1204227D01*
X1507931Y1204202D01*
X1507935Y1204172D01*
X1507938Y1204138D01*
X1507940Y1204102D01*
X1507941Y1204063D01*
G01X1507908Y1201110D02*
X1507914Y1201106D01*
X1507920Y1201095D01*
X1507926Y1201077D01*
X1507931Y1201052D01*
X1507935Y1201023D01*
X1507938Y1200989D01*
X1507940Y1200952D01*
X1507941Y1200913D01*
G01X1499740Y1196565D02*
X1501709Y1198533D01*
G01X1508572Y1211840D02*
X1508610Y1211814D01*
X1508638Y1211742D01*
X1508648Y1211644D01*
G01X1508572Y1208691D02*
X1508610Y1208664D01*
X1508638Y1208592D01*
X1508648Y1208494D01*
G01X1508572Y1205541D02*
X1508610Y1205515D01*
X1508638Y1205443D01*
X1508648Y1205344D01*
G01X1508572Y1202392D02*
X1508610Y1202365D01*
X1508638Y1202293D01*
X1508648Y1202195D01*
G01X1508572Y1199242D02*
X1508610Y1199216D01*
X1508638Y1199144D01*
X1508648Y1199045D01*
G01X1508572Y1196092D02*
X1508610Y1196066D01*
X1508638Y1195994D01*
X1508648Y1195896D01*
G01X1508572Y1192943D02*
X1508610Y1192916D01*
X1508638Y1192844D01*
X1508648Y1192746D01*
G01X1508572Y1189793D02*
X1508610Y1189767D01*
X1508638Y1189695D01*
X1508648Y1189596D01*
G01X1508572Y1186644D02*
X1508610Y1186617D01*
X1508638Y1186545D01*
X1508648Y1186447D01*
G01X1508572Y1183494D02*
X1508610Y1183468D01*
X1508638Y1183395D01*
X1508648Y1183297D01*
G01X1508572Y1180344D02*
X1508610Y1180318D01*
X1508638Y1180246D01*
X1508648Y1180148D01*
G01X1508572Y1177195D02*
X1508610Y1177168D01*
X1508638Y1177096D01*
X1508648Y1176998D01*
G01X1508572Y1174045D02*
X1508610Y1174019D01*
X1508638Y1173947D01*
X1508648Y1173848D01*
G01X1508572Y1170896D02*
X1508610Y1170869D01*
X1508638Y1170797D01*
X1508648Y1170699D01*
G01X1508572Y1167746D02*
X1508610Y1167720D01*
X1508638Y1167647D01*
X1508648Y1167549D01*
G01X1508572Y1164596D02*
X1508610Y1164570D01*
X1508638Y1164498D01*
X1508648Y1164400D01*
G01X1508572Y1161447D02*
X1508610Y1161420D01*
X1508638Y1161348D01*
X1508648Y1161250D01*
G01X1508572Y1158297D02*
X1508610Y1158271D01*
X1508638Y1158199D01*
X1508648Y1158100D01*
G01X1508572Y1155148D02*
X1508610Y1155121D01*
X1508638Y1155049D01*
X1508648Y1154951D01*
G01X1508572Y1151998D02*
X1508610Y1151972D01*
X1508638Y1151899D01*
X1508648Y1151801D01*
G01X1508572Y1148848D02*
X1508610Y1148822D01*
X1508638Y1148750D01*
X1508648Y1148651D01*
G01X1508572Y1145699D02*
X1508610Y1145672D01*
X1508638Y1145600D01*
X1508648Y1145502D01*
G01X1508572Y1142549D02*
X1508610Y1142523D01*
X1508638Y1142451D01*
X1508648Y1142352D01*
G01X1509749Y1145010D02*
X1510176Y1145600D01*
G01X1509749Y1150010D02*
X1510176Y1150600D01*
G01X1509749Y1155010D02*
X1510176Y1155600D01*
G01X1509749Y1160010D02*
X1510176Y1160600D01*
G01X1509749Y1165010D02*
X1510176Y1165600D01*
G01X1509749Y1170010D02*
X1510176Y1170600D01*
G01X1509749Y1175010D02*
X1510176Y1175600D01*
G01X1507781Y1180010D02*
X1508207Y1180600D01*
G01X1509749Y1185010D02*
X1510176Y1185600D01*
G01X1509749Y1190010D02*
X1510176Y1190600D01*
G01X1509817Y1195010D02*
X1510241Y1195600D01*
G01X1504004Y1146585D02*
X1503865Y1146389D01*
X1503727Y1146192D01*
X1503590Y1145994D01*
G01X1504004Y1151585D02*
X1503865Y1151389D01*
X1503727Y1151192D01*
X1503590Y1150994D01*
G01X1504004Y1156585D02*
X1503865Y1156389D01*
X1503727Y1156192D01*
X1503590Y1155994D01*
G01X1504004Y1161585D02*
X1503865Y1161389D01*
X1503727Y1161192D01*
X1503590Y1160994D01*
G01X1504004Y1166585D02*
X1503865Y1166389D01*
X1503727Y1166192D01*
X1503590Y1165994D01*
G01X1504004Y1171585D02*
X1503865Y1171389D01*
X1503727Y1171192D01*
X1503590Y1170994D01*
G01X1504004Y1176585D02*
X1503865Y1176389D01*
X1503727Y1176192D01*
X1503590Y1175994D01*
G01X1502036Y1181585D02*
X1501896Y1181389D01*
X1501758Y1181192D01*
X1501621Y1180994D01*
G01X1504004Y1186585D02*
X1503865Y1186389D01*
X1503727Y1186192D01*
X1503590Y1185994D01*
G01X1504004Y1191585D02*
X1503865Y1191389D01*
X1503727Y1191192D01*
X1503590Y1190994D01*
G01X1503904Y1196585D02*
X1503768Y1196388D01*
X1503633Y1196192D01*
X1503499Y1195994D01*
G01X1509332Y1145600D02*
X1509060Y1145010D01*
G01X1509332Y1150600D02*
X1509060Y1150010D01*
G01X1509332Y1155600D02*
X1509060Y1155010D01*
G01X1509332Y1160600D02*
X1509060Y1160010D01*
G01Y1196585D02*
X1509332Y1195994D01*
G01X1509060Y1191585D02*
X1509332Y1190994D01*
G01X1509060Y1186585D02*
X1509332Y1185994D01*
G01X1503499Y1195600D02*
X1503633Y1195403D01*
X1503768Y1195206D01*
X1503904Y1195010D01*
G01X1503590Y1190600D02*
X1503727Y1190403D01*
X1503865Y1190206D01*
X1504004Y1190010D01*
G01X1503590Y1185600D02*
X1503727Y1185403D01*
X1503865Y1185206D01*
X1504004Y1185010D01*
G01X1501621Y1180600D02*
X1501758Y1180403D01*
X1501896Y1180206D01*
X1502036Y1180010D01*
G01X1503590Y1175600D02*
X1503727Y1175403D01*
X1503865Y1175206D01*
X1504004Y1175010D01*
G01X1503590Y1170600D02*
X1503727Y1170403D01*
X1503865Y1170206D01*
X1504004Y1170010D01*
G01X1503590Y1165600D02*
X1503727Y1165403D01*
X1503865Y1165206D01*
X1504004Y1165010D01*
G01X1503590Y1160600D02*
X1503727Y1160403D01*
X1503865Y1160206D01*
X1504004Y1160010D01*
G01X1503590Y1155600D02*
X1503727Y1155403D01*
X1503865Y1155206D01*
X1504004Y1155010D01*
G01X1503590Y1150600D02*
X1503727Y1150403D01*
X1503865Y1150206D01*
X1504004Y1150010D01*
G01X1503590Y1145600D02*
X1503727Y1145403D01*
X1503865Y1145206D01*
X1504004Y1145010D01*
G01X1509817Y1196585D02*
X1510241Y1195994D01*
G01X1509749Y1191585D02*
X1510176Y1190994D01*
G01X1509749Y1186585D02*
X1510176Y1185994D01*
G01X1507781Y1181585D02*
X1508207Y1180994D01*
G01X1509749Y1176585D02*
X1510176Y1175994D01*
G01X1509749Y1171585D02*
X1510176Y1170994D01*
G01X1509749Y1166585D02*
X1510176Y1165994D01*
G01X1509749Y1161585D02*
X1510176Y1160994D01*
G01X1509749Y1156585D02*
X1510176Y1155994D01*
G01X1509749Y1151585D02*
X1510176Y1150994D01*
G01X1509749Y1146585D02*
X1510176Y1145994D01*
G01X1509332Y1165600D02*
X1509060Y1165010D01*
G01X1509332Y1170600D02*
X1509060Y1170010D01*
G01X1509332Y1175600D02*
X1509060Y1175010D01*
G01X1507364Y1180600D02*
X1507091Y1180010D01*
G01X1509332Y1185600D02*
X1509060Y1185010D01*
G01X1509332Y1190600D02*
X1509060Y1190010D01*
G01X1509332Y1195600D02*
X1509060Y1195010D01*
G01X1503727Y1167549D02*
X1503760Y1167648D01*
X1503848Y1167719D01*
X1503974Y1167746D01*
G01X1508208Y1145600D02*
X1508130Y1145010D01*
G01X1508208Y1150600D02*
X1508130Y1150010D01*
G01X1508208Y1155600D02*
X1508130Y1155010D01*
G01X1508208Y1160600D02*
X1508130Y1160010D01*
G01X1508208Y1165600D02*
X1508130Y1165010D01*
G01X1508208Y1170600D02*
X1508130Y1170010D01*
G01X1508208Y1175600D02*
X1508130Y1175010D01*
G01X1508208Y1185600D02*
X1508130Y1185010D01*
G01X1508208Y1190600D02*
X1508130Y1190010D01*
G01X1506239Y1180600D02*
X1506161Y1180010D01*
G01X1508208Y1195600D02*
X1508130Y1195010D01*
G01X1508648Y1141959D02*
X1508638Y1141860D01*
X1508610Y1141788D01*
X1508572Y1141762D01*
G01X1508648Y1145108D02*
X1508638Y1145010D01*
X1508610Y1144938D01*
X1508572Y1144911D01*
G01X1508648Y1148258D02*
X1508638Y1148159D01*
X1508610Y1148087D01*
X1508572Y1148061D01*
G01X1508648Y1151407D02*
X1508638Y1151309D01*
X1508610Y1151237D01*
X1508572Y1151211D01*
G01X1508648Y1154557D02*
X1508638Y1154459D01*
X1508610Y1154387D01*
X1508572Y1154360D01*
G01X1508648Y1157707D02*
X1508638Y1157608D01*
X1508610Y1157536D01*
X1508572Y1157510D01*
G01X1508648Y1160856D02*
X1508638Y1160758D01*
X1508610Y1160686D01*
X1508572Y1160659D01*
G01X1508648Y1164006D02*
X1508638Y1163907D01*
X1508610Y1163835D01*
X1508572Y1163809D01*
G01X1508648Y1167155D02*
X1508638Y1167057D01*
X1508610Y1166985D01*
X1508572Y1166959D01*
G01X1508648Y1170305D02*
X1508638Y1170207D01*
X1508610Y1170135D01*
X1508572Y1170108D01*
G01X1508648Y1173455D02*
X1508638Y1173356D01*
X1508610Y1173284D01*
X1508572Y1173258D01*
G01X1508648Y1176604D02*
X1508638Y1176506D01*
X1508610Y1176434D01*
X1508572Y1176407D01*
G01X1508648Y1179754D02*
X1508638Y1179655D01*
X1508610Y1179583D01*
X1508572Y1179557D01*
G01X1508648Y1182903D02*
X1508638Y1182805D01*
X1508610Y1182733D01*
X1508572Y1182707D01*
G01X1508648Y1186053D02*
X1508638Y1185955D01*
X1508610Y1185883D01*
X1508572Y1185856D01*
G01X1508648Y1189203D02*
X1508638Y1189104D01*
X1508610Y1189032D01*
X1508572Y1189006D01*
G01X1508648Y1192352D02*
X1508638Y1192254D01*
X1508610Y1192182D01*
X1508572Y1192155D01*
G01X1508648Y1195502D02*
X1508638Y1195404D01*
X1508610Y1195331D01*
X1508572Y1195305D01*
G01X1508648Y1198651D02*
X1508638Y1198553D01*
X1508610Y1198481D01*
X1508572Y1198455D01*
G01X1508648Y1201801D02*
X1508638Y1201703D01*
X1508610Y1201631D01*
X1508572Y1201604D01*
G01X1508648Y1208100D02*
X1508638Y1208002D01*
X1508610Y1207930D01*
X1508572Y1207903D01*
G01X1508648Y1211250D02*
X1508638Y1211152D01*
X1508610Y1211079D01*
X1508572Y1211053D01*
G01X1508208Y1195994D02*
X1508130Y1196585D01*
G01X1508208Y1190994D02*
X1508130Y1191585D01*
G01X1508208Y1185994D02*
X1508130Y1186585D01*
G01X1508208Y1175994D02*
X1508130Y1176585D01*
G01X1508208Y1170994D02*
X1508130Y1171585D01*
G01X1506239Y1180994D02*
X1506161Y1181585D01*
G01X1508208Y1165994D02*
X1508130Y1166585D01*
G01X1508208Y1160994D02*
X1508130Y1161585D01*
G01X1508208Y1155994D02*
X1508130Y1156585D01*
G01X1508208Y1150994D02*
X1508130Y1151585D01*
G01X1508208Y1145994D02*
X1508130Y1146585D01*
G01X1503727Y1211250D02*
X1503758Y1211153D01*
X1503847Y1211081D01*
X1503974Y1211053D01*
G01X1503727Y1208100D02*
X1503758Y1208003D01*
X1503847Y1207931D01*
X1503974Y1207903D01*
G01X1503727Y1204951D02*
X1503758Y1204854D01*
X1503847Y1204781D01*
X1503974Y1204754D01*
G01X1503727Y1201801D02*
X1503758Y1201704D01*
X1503847Y1201632D01*
X1503974Y1201604D01*
G01X1503727Y1198651D02*
X1503758Y1198554D01*
X1503847Y1198482D01*
X1503974Y1198455D01*
G01X1503727Y1195502D02*
X1503758Y1195405D01*
X1503847Y1195333D01*
X1503974Y1195305D01*
G01X1503727Y1192352D02*
X1503758Y1192255D01*
X1503847Y1192183D01*
X1503974Y1192155D01*
G01X1503727Y1189203D02*
X1503758Y1189106D01*
X1503847Y1189033D01*
X1503974Y1189006D01*
G01X1503727Y1186053D02*
X1503758Y1185956D01*
X1503847Y1185884D01*
X1503974Y1185856D01*
G01X1503727Y1182903D02*
X1503758Y1182806D01*
X1503847Y1182734D01*
X1503974Y1182707D01*
G01X1503727Y1179754D02*
X1503758Y1179657D01*
X1503847Y1179585D01*
X1503974Y1179557D01*
G01X1503727Y1176604D02*
X1503758Y1176507D01*
X1503847Y1176435D01*
X1503974Y1176407D01*
G01X1503727Y1173455D02*
X1503758Y1173358D01*
X1503847Y1173285D01*
X1503974Y1173258D01*
G01X1503727Y1170305D02*
X1503758Y1170208D01*
X1503847Y1170136D01*
X1503974Y1170108D01*
G01X1503727Y1164006D02*
X1503758Y1163909D01*
X1503847Y1163837D01*
X1503974Y1163809D01*
G01X1503727Y1160856D02*
X1503758Y1160759D01*
X1503847Y1160687D01*
X1503974Y1160659D01*
G01X1503727Y1157707D02*
X1503758Y1157610D01*
X1503847Y1157537D01*
X1503974Y1157510D01*
G01X1503727Y1154557D02*
X1503758Y1154460D01*
X1503847Y1154388D01*
X1503974Y1154360D01*
G01X1503727Y1151407D02*
X1503758Y1151310D01*
X1503847Y1151238D01*
X1503974Y1151211D01*
G01X1503727Y1148258D02*
X1503758Y1148161D01*
X1503847Y1148089D01*
X1503974Y1148061D01*
G01X1503727Y1145108D02*
X1503758Y1145011D01*
X1503847Y1144939D01*
X1503974Y1144911D01*
G01X1503727Y1141959D02*
X1503758Y1141862D01*
X1503847Y1141789D01*
X1503974Y1141762D01*
G01X1503717Y1209378D02*
X1503750Y1209279D01*
X1503838Y1209208D01*
X1503964Y1209181D01*
G01X1503717Y1206228D02*
X1503750Y1206129D01*
X1503838Y1206058D01*
X1503964Y1206031D01*
G01X1503717Y1203078D02*
X1503750Y1202979D01*
X1503838Y1202909D01*
X1503964Y1202882D01*
G01X1503717Y1199929D02*
X1503750Y1199830D01*
X1503838Y1199759D01*
X1503964Y1199732D01*
G01X1507091Y1181585D02*
X1507364Y1180994D01*
G01X1509060Y1176585D02*
X1509332Y1175994D01*
G01X1509060Y1171585D02*
X1509332Y1170994D01*
G01X1509060Y1166585D02*
X1509332Y1165994D01*
G01X1509060Y1161585D02*
X1509332Y1160994D01*
G01X1509060Y1156585D02*
X1509332Y1155994D01*
G01X1509060Y1151585D02*
X1509332Y1150994D01*
G01X1509060Y1146585D02*
X1509332Y1145994D01*
G01X1509093Y1199929D02*
X1509090Y1199891D01*
X1509081Y1199854D01*
X1509068Y1199820D01*
X1509049Y1199790D01*
X1509027Y1199765D01*
X1509002Y1199747D01*
X1508974Y1199736D01*
X1508945Y1199732D01*
G01X1509093Y1203078D02*
X1509090Y1203040D01*
X1509081Y1203003D01*
X1509068Y1202970D01*
X1509049Y1202939D01*
X1509027Y1202915D01*
X1509002Y1202897D01*
X1508974Y1202885D01*
X1508945Y1202882D01*
G01X1509093Y1206228D02*
X1509090Y1206190D01*
X1509081Y1206153D01*
X1509068Y1206119D01*
X1509049Y1206089D01*
X1509027Y1206064D01*
X1509002Y1206046D01*
X1508974Y1206035D01*
X1508945Y1206031D01*
G01X1509093Y1209378D02*
X1509090Y1209339D01*
X1509081Y1209303D01*
X1509068Y1209269D01*
X1509049Y1209238D01*
X1509027Y1209214D01*
X1509002Y1209196D01*
X1508974Y1209185D01*
X1508945Y1209181D01*
G01X1507941Y1199929D02*
X1507940Y1199891D01*
X1507938Y1199854D01*
X1507935Y1199820D01*
X1507931Y1199790D01*
X1507926Y1199765D01*
X1507921Y1199747D01*
X1507915Y1199736D01*
X1507908Y1199732D01*
G01X1507941Y1203078D02*
X1507940Y1203040D01*
X1507938Y1203003D01*
X1507935Y1202970D01*
X1507931Y1202939D01*
X1507926Y1202915D01*
X1507921Y1202897D01*
X1507915Y1202885D01*
X1507908Y1202882D01*
G01X1507941Y1206228D02*
X1507940Y1206190D01*
X1507938Y1206153D01*
X1507935Y1206119D01*
X1507931Y1206089D01*
X1507926Y1206064D01*
X1507921Y1206046D01*
X1507915Y1206035D01*
X1507908Y1206031D01*
G01X1507941Y1209378D02*
X1507940Y1209339D01*
X1507938Y1209303D01*
X1507935Y1209269D01*
X1507931Y1209238D01*
X1507926Y1209214D01*
X1507921Y1209196D01*
X1507915Y1209185D01*
X1507908Y1209181D01*
G01X1510338Y1211250D02*
Y1211644D01*
G01Y1208100D02*
Y1208494D01*
G01Y1204951D02*
Y1205344D01*
G01Y1201801D02*
Y1202195D01*
G01Y1198651D02*
Y1199045D01*
G01Y1195502D02*
Y1195896D01*
G01Y1192352D02*
Y1192746D01*
G01Y1189203D02*
Y1189596D01*
G01Y1186053D02*
Y1186447D01*
G01Y1182903D02*
Y1183297D01*
G01Y1179754D02*
Y1180148D01*
G01Y1176604D02*
Y1176998D01*
G01Y1173455D02*
Y1173848D01*
G01Y1170305D02*
Y1170699D01*
G01Y1167155D02*
Y1167549D01*
G01Y1160856D02*
Y1161250D01*
G01Y1164006D02*
Y1164400D01*
G01Y1157707D02*
Y1158100D01*
G01Y1154557D02*
Y1154951D01*
G01Y1151407D02*
Y1151801D01*
G01Y1148258D02*
Y1148651D01*
G01Y1145108D02*
Y1145502D01*
G01Y1141959D02*
Y1142352D01*
G01X1510241Y1195994D02*
Y1195600D01*
G01X1510176Y1145994D02*
Y1145600D01*
G01Y1150994D02*
Y1150600D01*
G01Y1155994D02*
Y1155600D01*
G01Y1160994D02*
Y1160600D01*
G01Y1165994D02*
Y1165600D01*
G01Y1170994D02*
Y1170600D01*
G01Y1175994D02*
Y1175600D01*
G01Y1185994D02*
Y1185600D01*
G01Y1190994D02*
Y1190600D01*
G01X1510035Y1200913D02*
Y1199929D01*
G01Y1204063D02*
Y1203078D01*
G01Y1210362D02*
Y1209378D01*
G01Y1207212D02*
Y1206228D01*
G01X1509332Y1145994D02*
Y1145600D01*
G01Y1150994D02*
Y1150600D01*
G01Y1155994D02*
Y1155600D01*
G01Y1160994D02*
Y1160600D01*
G01Y1165994D02*
Y1165600D01*
G01Y1170994D02*
Y1170600D01*
G01Y1175994D02*
Y1175600D01*
G01Y1185994D02*
Y1185600D01*
G01Y1190994D02*
Y1190600D01*
G01Y1195994D02*
Y1195600D01*
G01X1509161Y1211250D02*
Y1211644D01*
G01Y1208100D02*
Y1208494D01*
G01Y1204951D02*
Y1205344D01*
G01Y1201801D02*
Y1202195D01*
G01Y1198651D02*
Y1199045D01*
G01Y1195502D02*
Y1195896D01*
G01Y1192352D02*
Y1192746D01*
G01Y1189203D02*
Y1189596D01*
G01Y1186053D02*
Y1186447D01*
G01Y1182903D02*
Y1183297D01*
G01Y1179754D02*
Y1180148D01*
G01Y1176604D02*
Y1176998D01*
G01Y1173455D02*
Y1173848D01*
G01Y1170305D02*
Y1170699D01*
G01Y1167155D02*
Y1167549D01*
G01Y1160856D02*
Y1161250D01*
G01Y1164006D02*
Y1164400D01*
G01Y1157707D02*
Y1158100D01*
G01Y1154557D02*
Y1154951D01*
G01Y1151407D02*
Y1151801D01*
G01Y1148258D02*
Y1148651D01*
G01Y1145108D02*
Y1145502D01*
G01Y1141959D02*
Y1142352D01*
G01X1509093Y1200913D02*
Y1199929D01*
G01Y1204063D02*
Y1203078D01*
G01Y1210362D02*
Y1209378D01*
G01Y1207212D02*
Y1206228D01*
G01X1508648Y1145502D02*
Y1145108D01*
G01Y1142352D02*
Y1141959D01*
G01Y1148651D02*
Y1148258D01*
G01Y1154951D02*
Y1154557D01*
G01Y1151801D02*
Y1151407D01*
G01Y1158100D02*
Y1157707D01*
G01Y1161250D02*
Y1160856D01*
G01Y1164400D02*
Y1164006D01*
G01Y1167549D02*
Y1167155D01*
G01Y1170699D02*
Y1170305D01*
G01Y1176998D02*
Y1176604D01*
G01Y1173848D02*
Y1173455D01*
G01Y1180148D02*
Y1179754D01*
G01Y1186447D02*
Y1186053D01*
G01Y1183297D02*
Y1182903D01*
G01Y1189596D02*
Y1189203D01*
G01Y1195896D02*
Y1195502D01*
G01Y1192746D02*
Y1192352D01*
G01Y1199045D02*
Y1198651D01*
G01Y1205344D02*
Y1204951D01*
G01Y1202195D02*
Y1201801D01*
G01Y1208494D02*
Y1208100D01*
G01Y1211644D02*
Y1211250D01*
G01X1508208Y1195600D02*
Y1195994D01*
G01Y1190600D02*
Y1190994D01*
G01Y1185600D02*
Y1185994D01*
G01Y1175600D02*
Y1175994D01*
G01Y1170600D02*
Y1170994D01*
G01Y1165600D02*
Y1165994D01*
G01Y1160600D02*
Y1160994D01*
G01Y1155600D02*
Y1155994D01*
G01Y1150600D02*
Y1150994D01*
G01Y1145600D02*
Y1145994D01*
G01X1508207Y1180994D02*
Y1180600D01*
G01X1507941Y1200913D02*
Y1199929D01*
G01Y1204063D02*
Y1203078D01*
G01Y1210362D02*
Y1209378D01*
G01Y1207212D02*
Y1206228D01*
G01X1507364Y1180994D02*
Y1180600D01*
G01X1506239D02*
Y1180994D01*
G01X1506209Y1197372D02*
Y1198553D01*
G01X1503727Y1145502D02*
Y1145108D01*
G01Y1142352D02*
Y1141959D01*
G01Y1148651D02*
Y1148258D01*
G01Y1154951D02*
Y1154557D01*
G01Y1151801D02*
Y1151407D01*
G01Y1158100D02*
Y1157707D01*
G01Y1161250D02*
Y1160856D01*
G01Y1164400D02*
Y1164006D01*
G01Y1167549D02*
Y1167155D01*
G01Y1170699D02*
Y1170305D01*
G01Y1176998D02*
Y1176604D01*
G01Y1173848D02*
Y1173455D01*
G01Y1180148D02*
Y1179754D01*
G01Y1186447D02*
Y1186053D01*
G01Y1183297D02*
Y1182903D01*
G01Y1189596D02*
Y1189203D01*
G01Y1195896D02*
Y1195502D01*
G01Y1192746D02*
Y1192352D01*
G01Y1199045D02*
Y1198651D01*
G01Y1205344D02*
Y1204951D01*
G01Y1202195D02*
Y1201801D01*
G01Y1208494D02*
Y1208100D01*
G01Y1211644D02*
Y1211250D01*
G01X1503717Y1209378D02*
Y1210362D01*
G01Y1206228D02*
Y1207212D01*
G01Y1203078D02*
Y1204063D01*
G01Y1199929D02*
Y1200913D01*
G01X1503590Y1190600D02*
Y1190994D01*
G01Y1185600D02*
Y1185994D01*
G01Y1175600D02*
Y1175994D01*
G01Y1170600D02*
Y1170994D01*
G01Y1165600D02*
Y1165994D01*
G01Y1160600D02*
Y1160994D01*
G01Y1155600D02*
Y1155994D01*
G01Y1150600D02*
Y1150994D01*
G01Y1145600D02*
Y1145994D01*
G01X1503499Y1195600D02*
Y1195994D01*
G01X1501621Y1180600D02*
Y1180994D01*
G01X1500921Y1219222D02*
Y1197372D01*
G01X1500751Y1192096D02*
Y1197576D01*
G01X1509161Y1211644D02*
X1509158Y1211682D01*
X1509151Y1211719D01*
X1509138Y1211753D01*
X1509121Y1211783D01*
X1509100Y1211807D01*
X1509076Y1211825D01*
X1509050Y1211837D01*
X1509023Y1211840D01*
G01X1509161Y1208494D02*
X1509158Y1208532D01*
X1509151Y1208569D01*
X1509138Y1208603D01*
X1509121Y1208633D01*
X1509100Y1208658D01*
X1509076Y1208676D01*
X1509050Y1208687D01*
X1509023Y1208691D01*
G01X1509161Y1205344D02*
X1509158Y1205383D01*
X1509151Y1205419D01*
X1509138Y1205453D01*
X1509121Y1205484D01*
X1509100Y1205508D01*
X1509076Y1205526D01*
X1509050Y1205537D01*
X1509023Y1205541D01*
G01X1509161Y1202195D02*
X1509158Y1202233D01*
X1509151Y1202270D01*
X1509138Y1202304D01*
X1509121Y1202334D01*
X1509100Y1202358D01*
X1509076Y1202377D01*
X1509050Y1202388D01*
X1509023Y1202392D01*
G01X1509161Y1199045D02*
X1509158Y1199083D01*
X1509151Y1199120D01*
X1509138Y1199154D01*
X1509121Y1199184D01*
X1509100Y1199209D01*
X1509076Y1199227D01*
X1509050Y1199238D01*
X1509023Y1199242D01*
G01X1509161Y1195896D02*
X1509158Y1195934D01*
X1509151Y1195971D01*
X1509138Y1196005D01*
X1509121Y1196035D01*
X1509100Y1196059D01*
X1509076Y1196077D01*
X1509050Y1196089D01*
X1509023Y1196092D01*
G01X1509161Y1192746D02*
X1509158Y1192784D01*
X1509151Y1192821D01*
X1509138Y1192855D01*
X1509121Y1192885D01*
X1509100Y1192910D01*
X1509076Y1192928D01*
X1509050Y1192939D01*
X1509023Y1192943D01*
G01X1509161Y1189596D02*
X1509158Y1189635D01*
X1509151Y1189671D01*
X1509138Y1189705D01*
X1509121Y1189736D01*
X1509100Y1189760D01*
X1509076Y1189778D01*
X1509050Y1189789D01*
X1509023Y1189793D01*
G01X1509161Y1186447D02*
X1509158Y1186485D01*
X1509151Y1186522D01*
X1509138Y1186556D01*
X1509121Y1186586D01*
X1509100Y1186610D01*
X1509076Y1186628D01*
X1509050Y1186640D01*
X1509023Y1186644D01*
G01X1509161Y1183297D02*
X1509158Y1183335D01*
X1509151Y1183372D01*
X1509138Y1183406D01*
X1509121Y1183436D01*
X1509100Y1183461D01*
X1509076Y1183479D01*
X1509050Y1183490D01*
X1509023Y1183494D01*
G01X1509161Y1180148D02*
X1509158Y1180186D01*
X1509151Y1180223D01*
X1509138Y1180256D01*
X1509121Y1180287D01*
X1509100Y1180311D01*
X1509076Y1180329D01*
X1509050Y1180341D01*
X1509023Y1180344D01*
G01X1509161Y1176998D02*
X1509158Y1177036D01*
X1509151Y1177073D01*
X1509138Y1177107D01*
X1509121Y1177137D01*
X1509100Y1177162D01*
X1509076Y1177180D01*
X1509050Y1177191D01*
X1509023Y1177195D01*
G01X1509161Y1173848D02*
X1509158Y1173887D01*
X1509151Y1173923D01*
X1509138Y1173957D01*
X1509121Y1173988D01*
X1509100Y1174012D01*
X1509076Y1174030D01*
X1509050Y1174041D01*
X1509023Y1174045D01*
G01X1509161Y1170699D02*
X1509158Y1170737D01*
X1509151Y1170774D01*
X1509138Y1170808D01*
X1509121Y1170838D01*
X1509100Y1170862D01*
X1509076Y1170880D01*
X1509050Y1170892D01*
X1509023Y1170896D01*
G01X1509161Y1167549D02*
X1509158Y1167587D01*
X1509151Y1167624D01*
X1509138Y1167658D01*
X1509121Y1167688D01*
X1509100Y1167713D01*
X1509076Y1167731D01*
X1509050Y1167742D01*
X1509023Y1167746D01*
G01X1509161Y1164400D02*
X1509158Y1164438D01*
X1509151Y1164475D01*
X1509138Y1164508D01*
X1509121Y1164539D01*
X1509100Y1164563D01*
X1509076Y1164581D01*
X1509050Y1164592D01*
X1509023Y1164596D01*
G01X1509161Y1161250D02*
X1509158Y1161288D01*
X1509151Y1161325D01*
X1509138Y1161359D01*
X1509121Y1161389D01*
X1509100Y1161413D01*
X1509076Y1161432D01*
X1509050Y1161443D01*
X1509023Y1161447D01*
G01X1509161Y1158100D02*
X1509158Y1158139D01*
X1509151Y1158175D01*
X1509138Y1158209D01*
X1509121Y1158239D01*
X1509100Y1158264D01*
X1509076Y1158282D01*
X1509050Y1158293D01*
X1509023Y1158297D01*
G01X1509161Y1154951D02*
X1509158Y1154989D01*
X1509151Y1155026D01*
X1509138Y1155060D01*
X1509121Y1155090D01*
X1509100Y1155114D01*
X1509076Y1155132D01*
X1509050Y1155144D01*
X1509023Y1155148D01*
G01X1509161Y1151801D02*
X1509158Y1151839D01*
X1509151Y1151876D01*
X1509138Y1151910D01*
X1509121Y1151940D01*
X1509100Y1151965D01*
X1509076Y1151983D01*
X1509050Y1151994D01*
X1509023Y1151998D01*
G01X1509161Y1148651D02*
X1509158Y1148690D01*
X1509151Y1148726D01*
X1509138Y1148760D01*
X1509121Y1148791D01*
X1509100Y1148815D01*
X1509076Y1148833D01*
X1509050Y1148844D01*
X1509023Y1148848D01*
G01X1509161Y1145502D02*
X1509158Y1145540D01*
X1509151Y1145577D01*
X1509138Y1145611D01*
X1509121Y1145641D01*
X1509100Y1145665D01*
X1509076Y1145684D01*
X1509050Y1145695D01*
X1509023Y1145699D01*
G01X1509161Y1142352D02*
X1509158Y1142391D01*
X1509151Y1142427D01*
X1509138Y1142461D01*
X1509121Y1142491D01*
X1509100Y1142516D01*
X1509076Y1142534D01*
X1509050Y1142545D01*
X1509023Y1142549D01*
G01X1531551Y1140010D02*
X1537142D01*
G01X1533008Y1139813D02*
X1532024D01*
G01X1533008Y1139419D02*
X1532024D01*
G01X1542605Y1139400D02*
X1549937D01*
G01X1542457D02*
X1530449D01*
G01X1533008Y1139222D02*
X1532024D01*
G01X1541519Y1139400D02*
Y1141762D01*
G01X1537142Y1140010D02*
Y1141585D01*
G01X1533992D02*
Y1140010D01*
G01X1533008Y1142372D02*
Y1139222D01*
G01X1532024Y1142372D02*
Y1139222D01*
G01X1531945Y1190010D02*
G03X1531551Y1189616I0J-394D01*
G01Y1191978D02*
G03X1531945Y1191585I394J1D01*
G01Y1185010D02*
G03X1531551Y1184616I0J-394D01*
G01Y1186978D02*
G03X1531945Y1186585I394J1D01*
G01Y1195010D02*
G03X1531551Y1194616I0J-394D01*
G01Y1196978D02*
G03X1531945Y1196585I394J1D01*
G01Y1175010D02*
G03X1531551Y1174616I0J-394D01*
G01Y1176978D02*
G03X1531945Y1176585I394J1D01*
G01Y1165010D02*
G03X1531551Y1164616I0J-394D01*
G01Y1166978D02*
G03X1531945Y1166585I394J1D01*
G01Y1160010D02*
G03X1531551Y1159616I0J-394D01*
G01Y1161978D02*
G03X1531945Y1161585I394J1D01*
G01Y1145010D02*
G03X1531551Y1144616I0J-394D01*
G01Y1146978D02*
G03X1531945Y1146585I394J1D01*
G01Y1150010D02*
G03X1531551Y1149616I0J-394D01*
G01Y1151978D02*
G03X1531945Y1151585I394J1D01*
G01Y1155010D02*
G03X1531551Y1154616I0J-394D01*
G01Y1156978D02*
G03X1531945Y1156585I394J1D01*
G01Y1170010D02*
G03X1531551Y1169616I0J-394D01*
G01Y1171978D02*
G03X1531945Y1171585I394J1D01*
G01X1542457Y1211053D02*
X1530449D01*
G01X1549937D02*
X1542605D01*
G01X1533442Y1210856D02*
X1532458D01*
G01X1533442Y1210659D02*
X1532458D01*
G01X1531551Y1210463D02*
X1537576D01*
G01X1531551Y1209281D02*
X1537576D01*
G01X1533442Y1209085D02*
X1532458D01*
G01X1533442Y1208888D02*
X1532458D01*
G01X1542605Y1208691D02*
X1549937D01*
G01X1542457D02*
X1530449D01*
G01X1542457Y1207903D02*
X1530449D01*
G01X1549937D02*
X1542605D01*
G01X1533442Y1207707D02*
X1532458D01*
G01X1533442Y1207510D02*
X1532458D01*
G01X1531551Y1207313D02*
X1537576D01*
G01X1531551Y1206132D02*
X1537576D01*
G01X1533442Y1205935D02*
X1532458D01*
G01X1533442Y1205738D02*
X1532458D01*
G01X1542605Y1205541D02*
X1549937D01*
G01X1542457D02*
X1530449D01*
G01X1542457Y1204754D02*
X1530449D01*
G01X1549937D02*
X1542605D01*
G01X1539440Y1204675D02*
X1537558D01*
G01X1533442Y1204557D02*
X1532458D01*
G01X1533442Y1204360D02*
X1532458D01*
G01X1531551Y1204163D02*
X1537576D01*
G01X1531551Y1202982D02*
X1537576D01*
G01X1533442Y1202785D02*
X1532458D01*
G01X1533442Y1202588D02*
X1532458D01*
G01X1539440Y1202470D02*
X1537558D01*
G01X1542605Y1202392D02*
X1549937D01*
G01X1542457D02*
X1530449D01*
G01X1542457Y1201604D02*
X1530449D01*
G01X1549937D02*
X1542605D01*
G01X1533442Y1201407D02*
X1532458D01*
G01X1533442Y1201211D02*
X1532458D01*
G01X1531551Y1201014D02*
X1537576D01*
G01X1531551Y1199833D02*
X1537576D01*
G01X1533442Y1199636D02*
X1532458D01*
G01X1533442Y1199439D02*
X1532458D01*
G01X1542605Y1199242D02*
X1549937D01*
G01X1542457D02*
X1530449D01*
G01X1533442Y1199144D02*
X1535567D01*
G01X1530449Y1198651D02*
X1537984D01*
G01X1531551Y1198533D02*
X1530449D01*
G01X1542457Y1198455D02*
X1530449D01*
G01X1549937D02*
X1542605D01*
G01X1534976Y1197372D02*
X1533992D01*
G01X1534976Y1197175D02*
X1533992D01*
G01X1534976Y1196781D02*
X1533992D01*
G01X1531945Y1196585D02*
X1539110D01*
G01X1542605Y1196092D02*
X1549937D01*
G01X1542457D02*
X1530449D01*
G01X1542457Y1195305D02*
X1530449D01*
G01X1549937D02*
X1542605D01*
G01X1531945Y1195010D02*
X1539110D01*
G01X1534976Y1194813D02*
X1533992D01*
G01X1534976Y1194419D02*
X1533992D01*
G01X1534976Y1194222D02*
X1533992D01*
G01X1542605Y1192943D02*
X1549937D01*
G01X1542457D02*
X1530449D01*
G01X1534976Y1192372D02*
X1533992D01*
G01X1534976Y1192175D02*
X1533992D01*
G01X1542457Y1192155D02*
X1530449D01*
G01X1549937D02*
X1542605D01*
G01X1534976Y1191781D02*
X1533992D01*
G01X1531945Y1191585D02*
X1539110D01*
G01X1531945Y1190010D02*
X1539110D01*
G01X1534976Y1189813D02*
X1533992D01*
G01X1542605Y1189793D02*
X1549937D01*
G01X1542457D02*
X1530449D01*
G01X1534976Y1189419D02*
X1533992D01*
G01X1534976Y1189222D02*
X1533992D01*
G01X1542457Y1189006D02*
X1530449D01*
G01X1549937D02*
X1542605D01*
G01X1534976Y1187372D02*
X1533992D01*
G01X1534976Y1187175D02*
X1533992D01*
G01X1534976Y1186781D02*
X1533992D01*
G01X1542605Y1186644D02*
X1549937D01*
G01X1542457D02*
X1530449D01*
G01X1531945Y1186585D02*
X1539110D01*
G01X1542457Y1185856D02*
X1530449D01*
G01X1549937D02*
X1542605D01*
G01X1531945Y1185010D02*
X1539110D01*
G01X1534976Y1184813D02*
X1533992D01*
G01X1534976Y1184419D02*
X1533992D01*
G01X1534976Y1184222D02*
X1533992D01*
G01X1542605Y1183494D02*
X1549937D01*
G01X1542457D02*
X1530449D01*
G01Y1183002D02*
X1531551D01*
G01X1542457Y1182707D02*
X1530449D01*
G01X1549937D02*
X1542605D01*
G01X1533008Y1182372D02*
X1532024D01*
G01X1533008Y1182175D02*
X1532024D01*
G01X1533008Y1181781D02*
X1532024D01*
G01X1531551Y1181585D02*
X1537142D01*
G01X1542605Y1180344D02*
X1549937D01*
G01X1542457D02*
X1530449D01*
G01X1531551Y1180010D02*
X1537142D01*
G01X1533008Y1179813D02*
X1532024D01*
G01X1542457Y1179557D02*
X1530449D01*
G01X1549937D02*
X1542605D01*
G01X1533008Y1179419D02*
X1532024D01*
G01X1533008Y1179222D02*
X1532024D01*
G01X1531551Y1178592D02*
X1530449D01*
G01X1534976Y1177372D02*
X1533992D01*
G01X1542605Y1177195D02*
X1549937D01*
G01X1542457D02*
X1530449D01*
G01X1534976Y1177175D02*
X1533992D01*
G01X1534976Y1176781D02*
X1533992D01*
G01X1531945Y1176585D02*
X1539110D01*
G01X1542457Y1176407D02*
X1530449D01*
G01X1549937D02*
X1542605D01*
G01X1531945Y1175010D02*
X1539110D01*
G01X1534976Y1174813D02*
X1533992D01*
G01X1534976Y1174419D02*
X1533992D01*
G01X1534976Y1174222D02*
X1533992D01*
G01X1542605Y1174045D02*
X1549937D01*
G01X1542457D02*
X1530449D01*
G01X1542457Y1173258D02*
X1530449D01*
G01X1549937D02*
X1542605D01*
G01X1534976Y1172372D02*
X1533992D01*
G01X1534976Y1172175D02*
X1533992D01*
G01X1534976Y1171781D02*
X1533992D01*
G01X1531945Y1171585D02*
X1539110D01*
G01X1542605Y1170896D02*
X1549937D01*
G01X1542457D02*
X1530449D01*
G01X1542457Y1170108D02*
X1530449D01*
G01X1549937D02*
X1542605D01*
G01X1531945Y1170010D02*
X1539110D01*
G01X1534976Y1169813D02*
X1533992D01*
G01X1534976Y1169419D02*
X1533992D01*
G01X1534976Y1169222D02*
X1533992D01*
G01X1542605Y1167746D02*
X1549937D01*
G01X1542457D02*
X1530449D01*
G01X1534976Y1167372D02*
X1533992D01*
G01X1534976Y1167175D02*
X1533992D01*
G01X1542457Y1166959D02*
X1530449D01*
G01X1549937D02*
X1542605D01*
G01X1534976Y1166781D02*
X1533992D01*
G01X1531945Y1166585D02*
X1539110D01*
G01X1531945Y1165010D02*
X1539110D01*
G01X1534976Y1164813D02*
X1533992D01*
G01X1542605Y1164596D02*
X1549937D01*
G01X1542457D02*
X1530449D01*
G01X1534976Y1164419D02*
X1533992D01*
G01X1534976Y1164222D02*
X1533992D01*
G01X1542457Y1163809D02*
X1530449D01*
G01X1549937D02*
X1542605D01*
G01X1534976Y1162372D02*
X1533992D01*
G01X1534976Y1162175D02*
X1533992D01*
G01X1534976Y1161781D02*
X1533992D01*
G01X1531945Y1161585D02*
X1539110D01*
G01X1542605Y1161447D02*
X1549937D01*
G01X1542457D02*
X1530449D01*
G01X1542457Y1160659D02*
X1530449D01*
G01X1549937D02*
X1542605D01*
G01X1531945Y1160010D02*
X1539110D01*
G01X1534976Y1159813D02*
X1533992D01*
G01X1534976Y1159419D02*
X1533992D01*
G01X1534976Y1159222D02*
X1533992D01*
G01X1542605Y1158297D02*
X1549937D01*
G01X1542457D02*
X1530449D01*
G01X1542457Y1157510D02*
X1530449D01*
G01X1549937D02*
X1542605D01*
G01X1534976Y1157372D02*
X1533992D01*
G01X1534976Y1157175D02*
X1533992D01*
G01X1534976Y1156781D02*
X1533992D01*
G01X1531945Y1156585D02*
X1539110D01*
G01X1542605Y1155148D02*
X1549937D01*
G01X1542457D02*
X1530449D01*
G01X1531945Y1155010D02*
X1539110D01*
G01X1534976Y1154813D02*
X1533992D01*
G01X1534976Y1154419D02*
X1533992D01*
G01X1542457Y1154360D02*
X1530449D01*
G01X1549937D02*
X1542605D01*
G01X1534976Y1154222D02*
X1533992D01*
G01X1534976Y1152372D02*
X1533992D01*
G01X1534976Y1152175D02*
X1533992D01*
G01X1542605Y1151998D02*
X1549937D01*
G01X1542457D02*
X1530449D01*
G01X1534976Y1151781D02*
X1533992D01*
G01X1531945Y1151585D02*
X1539110D01*
G01X1542457Y1151211D02*
X1530449D01*
G01X1549937D02*
X1542605D01*
G01X1531945Y1150010D02*
X1539110D01*
G01X1534976Y1149813D02*
X1533992D01*
G01X1534976Y1149419D02*
X1533992D01*
G01X1534976Y1149222D02*
X1533992D01*
G01X1542605Y1148848D02*
X1549937D01*
G01X1542457D02*
X1530449D01*
G01X1542457Y1148061D02*
X1530449D01*
G01X1549937D02*
X1542605D01*
G01X1534976Y1147372D02*
X1533992D01*
G01X1534976Y1147175D02*
X1533992D01*
G01X1534976Y1146781D02*
X1533992D01*
G01X1531945Y1146585D02*
X1539110D01*
G01X1542605Y1145699D02*
X1549937D01*
G01X1542457D02*
X1530449D01*
G01X1531945Y1145010D02*
X1539110D01*
G01X1542457Y1144911D02*
X1530449D01*
G01X1549937D02*
X1542605D01*
G01X1534976Y1144813D02*
X1533992D01*
G01X1534976Y1144419D02*
X1533992D01*
G01X1534976Y1144222D02*
X1533992D01*
G01X1530449Y1143002D02*
X1531551D01*
G01X1542605Y1142549D02*
X1549937D01*
G01X1542457D02*
X1530449D01*
G01X1533008Y1142372D02*
X1532024D01*
G01X1533008Y1142175D02*
X1532024D01*
G01X1533008Y1141781D02*
X1532024D01*
G01X1542457Y1141762D02*
X1530449D01*
G01X1549937D02*
X1542605D01*
G01X1531551Y1141585D02*
X1537142D01*
G01X1549937Y1142549D02*
Y1141762D01*
G01Y1148848D02*
Y1148061D01*
G01Y1145699D02*
Y1144911D01*
G01Y1151998D02*
Y1151211D01*
G01Y1158297D02*
Y1157510D01*
G01Y1155148D02*
Y1154360D01*
G01Y1161447D02*
Y1160659D01*
G01Y1167746D02*
Y1166959D01*
G01Y1164596D02*
Y1163809D01*
G01Y1170896D02*
Y1170108D01*
G01Y1177195D02*
Y1176407D01*
G01Y1174045D02*
Y1173258D01*
G01Y1180344D02*
Y1179557D01*
G01Y1186644D02*
Y1185856D01*
G01Y1183494D02*
Y1182707D01*
G01Y1189793D02*
Y1189006D01*
G01Y1196092D02*
Y1195305D01*
G01Y1192943D02*
Y1192155D01*
G01Y1199242D02*
Y1198455D01*
G01Y1205541D02*
Y1204754D01*
G01Y1202392D02*
Y1201604D01*
G01Y1208691D02*
Y1207903D01*
G01Y1211840D02*
Y1211053D01*
G01X1548163Y1142549D02*
Y1141762D01*
G01Y1148848D02*
Y1148061D01*
G01Y1145699D02*
Y1144911D01*
G01Y1151998D02*
Y1151211D01*
G01Y1158297D02*
Y1157510D01*
G01Y1155148D02*
Y1154360D01*
G01Y1161447D02*
Y1160659D01*
G01Y1167746D02*
Y1166959D01*
G01Y1164596D02*
Y1163809D01*
G01Y1170896D02*
Y1170108D01*
G01Y1177195D02*
Y1176407D01*
G01Y1174045D02*
Y1173258D01*
G01Y1180344D02*
Y1179557D01*
G01Y1186644D02*
Y1185856D01*
G01Y1183494D02*
Y1182707D01*
G01Y1189793D02*
Y1189006D01*
G01Y1196092D02*
Y1195305D01*
G01Y1192943D02*
Y1192155D01*
G01Y1199242D02*
Y1198455D01*
G01Y1205541D02*
Y1204754D01*
G01Y1202392D02*
Y1201604D01*
G01Y1208691D02*
Y1207903D01*
G01Y1211840D02*
Y1211053D01*
G01X1547975D02*
Y1211840D01*
G01Y1207903D02*
Y1208691D01*
G01Y1204754D02*
Y1205541D01*
G01Y1201604D02*
Y1202392D01*
G01Y1198455D02*
Y1199242D01*
G01Y1195305D02*
Y1196092D01*
G01Y1192155D02*
Y1192943D01*
G01Y1189006D02*
Y1189793D01*
G01Y1185856D02*
Y1186644D01*
G01Y1182707D02*
Y1183494D01*
G01Y1179557D02*
Y1180344D01*
G01Y1176407D02*
Y1177195D01*
G01Y1173258D02*
Y1174045D01*
G01Y1170108D02*
Y1170896D01*
G01Y1166959D02*
Y1167746D01*
G01Y1163809D02*
Y1164596D01*
G01Y1160659D02*
Y1161447D01*
G01Y1157510D02*
Y1158297D01*
G01Y1154360D02*
Y1155148D01*
G01Y1151211D02*
Y1151998D01*
G01Y1148061D02*
Y1148848D01*
G01Y1144911D02*
Y1145699D01*
G01Y1141762D02*
Y1142549D01*
G01X1545138Y1211053D02*
Y1211840D01*
G01Y1207903D02*
Y1208691D01*
G01Y1204754D02*
Y1205541D01*
G01Y1201604D02*
Y1202392D01*
G01Y1198455D02*
Y1199242D01*
G01Y1195305D02*
Y1196092D01*
G01Y1192155D02*
Y1192943D01*
G01Y1189006D02*
Y1189793D01*
G01Y1185856D02*
Y1186644D01*
G01Y1182707D02*
Y1183494D01*
G01Y1179557D02*
Y1180344D01*
G01Y1176407D02*
Y1177195D01*
G01Y1173258D02*
Y1174045D01*
G01Y1170108D02*
Y1170896D01*
G01Y1166959D02*
Y1167746D01*
G01Y1163809D02*
Y1164596D01*
G01Y1160659D02*
Y1161447D01*
G01Y1157510D02*
Y1158297D01*
G01Y1154360D02*
Y1155148D01*
G01Y1151211D02*
Y1151998D01*
G01Y1148061D02*
Y1148848D01*
G01Y1144911D02*
Y1145699D01*
G01Y1141762D02*
Y1142549D01*
G01X1544197D02*
Y1141762D01*
G01Y1148848D02*
Y1148061D01*
G01Y1145699D02*
Y1144911D01*
G01Y1151998D02*
Y1151211D01*
G01Y1158297D02*
Y1157510D01*
G01Y1155148D02*
Y1154360D01*
G01Y1161447D02*
Y1160659D01*
G01Y1167746D02*
Y1166959D01*
G01Y1164596D02*
Y1163809D01*
G01Y1170896D02*
Y1170108D01*
G01Y1177195D02*
Y1176407D01*
G01Y1174045D02*
Y1173258D01*
G01Y1180344D02*
Y1179557D01*
G01Y1186644D02*
Y1185856D01*
G01Y1183494D02*
Y1182707D01*
G01Y1189793D02*
Y1189006D01*
G01Y1196092D02*
Y1195305D01*
G01Y1192943D02*
Y1192155D01*
G01Y1199242D02*
Y1198455D01*
G01Y1205541D02*
Y1204754D01*
G01Y1202392D02*
Y1201604D01*
G01Y1208691D02*
Y1207903D01*
G01Y1211840D02*
Y1211053D01*
G01X1542605Y1142549D02*
Y1141762D01*
G01Y1148848D02*
Y1148061D01*
G01Y1145699D02*
Y1144911D01*
G01Y1151998D02*
Y1151211D01*
G01Y1158297D02*
Y1157510D01*
G01Y1155148D02*
Y1154360D01*
G01Y1161447D02*
Y1160659D01*
G01Y1167746D02*
Y1166959D01*
G01Y1164596D02*
Y1163809D01*
G01Y1170896D02*
Y1170108D01*
G01Y1177195D02*
Y1176407D01*
G01Y1174045D02*
Y1173258D01*
G01Y1180344D02*
Y1179557D01*
G01Y1186644D02*
Y1185856D01*
G01Y1183494D02*
Y1182707D01*
G01Y1189793D02*
Y1189006D01*
G01Y1196092D02*
Y1195305D01*
G01Y1192943D02*
Y1192155D01*
G01Y1199242D02*
Y1198455D01*
G01Y1205541D02*
Y1204754D01*
G01Y1202392D02*
Y1201604D01*
G01Y1208691D02*
Y1207903D01*
G01Y1211840D02*
Y1211053D01*
G01X1542457Y1142549D02*
Y1141762D01*
G01Y1148848D02*
Y1148061D01*
G01Y1145699D02*
Y1144911D01*
G01Y1151998D02*
Y1151211D01*
G01Y1158297D02*
Y1157510D01*
G01Y1155148D02*
Y1154360D01*
G01Y1161447D02*
Y1160659D01*
G01Y1167746D02*
Y1166959D01*
G01Y1164596D02*
Y1163809D01*
G01Y1170896D02*
Y1170108D01*
G01Y1177195D02*
Y1176407D01*
G01Y1174045D02*
Y1173258D01*
G01Y1180344D02*
Y1179557D01*
G01Y1186644D02*
Y1185856D01*
G01Y1183494D02*
Y1182707D01*
G01Y1189793D02*
Y1189006D01*
G01Y1196092D02*
Y1195305D01*
G01Y1192943D02*
Y1192155D01*
G01Y1199242D02*
Y1198455D01*
G01Y1205541D02*
Y1204754D01*
G01Y1202392D02*
Y1201604D01*
G01Y1208691D02*
Y1207903D01*
G01Y1211840D02*
Y1211053D01*
G01X1541519Y1208691D02*
Y1211053D01*
G01Y1205541D02*
Y1207903D01*
G01Y1202392D02*
Y1204754D01*
G01Y1199242D02*
Y1201604D01*
G01Y1196092D02*
Y1198455D01*
G01Y1192943D02*
Y1195305D01*
G01Y1189793D02*
Y1192155D01*
G01Y1186644D02*
Y1189006D01*
G01Y1183494D02*
Y1185856D01*
G01Y1180344D02*
Y1182707D01*
G01Y1177195D02*
Y1179557D01*
G01Y1174045D02*
Y1176407D01*
G01Y1170896D02*
Y1173258D01*
G01Y1167746D02*
Y1170108D01*
G01Y1164596D02*
Y1166959D01*
G01Y1161447D02*
Y1163809D01*
G01Y1158297D02*
Y1160659D01*
G01Y1155148D02*
Y1157510D01*
G01Y1151998D02*
Y1154360D01*
G01Y1148848D02*
Y1151211D01*
G01Y1145699D02*
Y1148061D01*
G01Y1142549D02*
Y1144911D01*
G01X1539791Y1142549D02*
Y1141762D01*
G01Y1148848D02*
Y1148061D01*
G01Y1145699D02*
Y1144911D01*
G01Y1151998D02*
Y1151211D01*
G01Y1158297D02*
Y1157510D01*
G01Y1155148D02*
Y1154360D01*
G01Y1161447D02*
Y1160659D01*
G01Y1167746D02*
Y1166959D01*
G01Y1164596D02*
Y1163809D01*
G01Y1170896D02*
Y1170108D01*
G01Y1177195D02*
Y1176407D01*
G01Y1174045D02*
Y1173258D01*
G01Y1180344D02*
Y1179557D01*
G01Y1186644D02*
Y1185856D01*
G01Y1183494D02*
Y1182707D01*
G01Y1189793D02*
Y1189006D01*
G01Y1196092D02*
Y1195305D01*
G01Y1192943D02*
Y1192155D01*
G01Y1199242D02*
Y1198455D01*
G01Y1205541D02*
Y1204754D01*
G01Y1202392D02*
Y1201604D01*
G01Y1208691D02*
Y1207903D01*
G01Y1211840D02*
Y1211053D01*
G01X1539440Y1204675D02*
Y1202470D01*
G01X1539110Y1195010D02*
Y1196585D01*
G01Y1190010D02*
Y1191585D01*
G01Y1185010D02*
Y1186585D01*
G01Y1175010D02*
Y1176585D01*
G01Y1170010D02*
Y1171585D01*
G01Y1165010D02*
Y1166585D01*
G01Y1160010D02*
Y1161585D01*
G01Y1155010D02*
Y1156585D01*
G01Y1150010D02*
Y1151585D01*
G01Y1145010D02*
Y1146585D01*
G01X1538139Y1211053D02*
Y1211840D01*
G01Y1207903D02*
Y1208691D01*
G01Y1204754D02*
Y1205541D01*
G01Y1201604D02*
Y1202392D01*
G01Y1198455D02*
Y1199242D01*
G01Y1195305D02*
Y1196092D01*
G01Y1192155D02*
Y1192943D01*
G01Y1189006D02*
Y1189793D01*
G01Y1185856D02*
Y1186644D01*
G01Y1182707D02*
Y1183494D01*
G01Y1179557D02*
Y1180344D01*
G01Y1176407D02*
Y1177195D01*
G01Y1173258D02*
Y1174045D01*
G01Y1170108D02*
Y1170896D01*
G01Y1166959D02*
Y1167746D01*
G01Y1163809D02*
Y1164596D01*
G01Y1160659D02*
Y1161447D01*
G01Y1157510D02*
Y1158297D01*
G01Y1154360D02*
Y1155148D01*
G01Y1151211D02*
Y1151998D01*
G01Y1148061D02*
Y1148848D01*
G01Y1144911D02*
Y1145699D01*
G01Y1141762D02*
Y1142549D01*
G01X1537984Y1202470D02*
Y1198651D01*
G01Y1211919D02*
Y1204675D01*
G01X1537576Y1209281D02*
Y1210463D01*
G01Y1206132D02*
Y1207313D01*
G01Y1202982D02*
Y1204163D01*
G01Y1199833D02*
Y1201014D01*
G01X1537558Y1202470D02*
Y1204675D01*
G01X1537506Y1217943D02*
Y1198651D01*
G01X1537142Y1180010D02*
Y1181585D01*
G01X1536156Y1211053D02*
Y1211840D01*
G01Y1207903D02*
Y1208691D01*
G01Y1204754D02*
Y1205541D01*
G01Y1201604D02*
Y1202392D01*
G01Y1198455D02*
Y1199242D01*
G01Y1195305D02*
Y1196092D01*
G01Y1192155D02*
Y1192943D01*
G01Y1189006D02*
Y1189793D01*
G01Y1185856D02*
Y1186644D01*
G01Y1182707D02*
Y1183494D01*
G01Y1179557D02*
Y1180344D01*
G01Y1176407D02*
Y1177195D01*
G01Y1173258D02*
Y1174045D01*
G01Y1170108D02*
Y1170896D01*
G01Y1166959D02*
Y1167746D01*
G01Y1163809D02*
Y1164596D01*
G01Y1160659D02*
Y1161447D01*
G01Y1157510D02*
Y1158297D01*
G01Y1154360D02*
Y1155148D01*
G01Y1151211D02*
Y1151998D01*
G01Y1148061D02*
Y1148848D01*
G01Y1144911D02*
Y1145699D01*
G01Y1141762D02*
Y1142549D01*
G01X1535961Y1146585D02*
Y1145010D01*
G01Y1151585D02*
Y1150010D01*
G01Y1156585D02*
Y1155010D01*
G01Y1161585D02*
Y1160010D01*
G01Y1166585D02*
Y1165010D01*
G01Y1171585D02*
Y1170010D01*
G01Y1176585D02*
Y1175010D01*
G01Y1186585D02*
Y1185010D01*
G01Y1191585D02*
Y1190010D01*
G01Y1196585D02*
Y1195010D01*
G01X1534976Y1147372D02*
Y1144222D01*
G01Y1152372D02*
Y1149222D01*
G01Y1157372D02*
Y1154222D01*
G01Y1162372D02*
Y1159222D01*
G01Y1167372D02*
Y1164222D01*
G01Y1172372D02*
Y1169222D01*
G01Y1177372D02*
Y1174222D01*
G01Y1187372D02*
Y1184222D01*
G01Y1192372D02*
Y1189222D01*
G01Y1197372D02*
Y1194222D01*
G01X1534427Y1201014D02*
Y1199833D01*
G01Y1204163D02*
Y1202982D01*
G01Y1210463D02*
Y1209281D01*
G01Y1207313D02*
Y1206132D01*
G01X1534149Y1217943D02*
Y1198651D01*
G01X1533992Y1147372D02*
Y1144222D01*
G01Y1152372D02*
Y1149222D01*
G01Y1157372D02*
Y1154222D01*
G01Y1162372D02*
Y1159222D01*
G01Y1167372D02*
Y1164222D01*
G01Y1172372D02*
Y1169222D01*
G01Y1177372D02*
Y1174222D01*
G01Y1181585D02*
Y1180010D01*
G01Y1187372D02*
Y1184222D01*
G01Y1192372D02*
Y1189222D01*
G01Y1197372D02*
Y1194222D01*
G01X1533442Y1217451D02*
Y1199144D01*
G01X1533232Y1198651D02*
Y1217943D01*
G01X1533008Y1146585D02*
Y1145010D01*
G01Y1151585D02*
Y1150010D01*
G01Y1156585D02*
Y1155010D01*
G01Y1161585D02*
Y1160010D01*
G01Y1166585D02*
Y1165010D01*
G01Y1171585D02*
Y1170010D01*
G01Y1176585D02*
Y1175010D01*
G01Y1182372D02*
Y1179222D01*
G01Y1186585D02*
Y1185010D01*
G01Y1191585D02*
Y1190010D01*
G01Y1196585D02*
Y1195010D01*
G01X1532793Y1142549D02*
Y1141762D01*
G01Y1148848D02*
Y1148061D01*
G01Y1145699D02*
Y1144911D01*
G01Y1151998D02*
Y1151211D01*
G01Y1158297D02*
Y1157510D01*
G01Y1155148D02*
Y1154360D01*
G01Y1161447D02*
Y1160659D01*
G01Y1167746D02*
Y1166959D01*
G01Y1164596D02*
Y1163809D01*
G01Y1170896D02*
Y1170108D01*
G01Y1177195D02*
Y1176407D01*
G01Y1174045D02*
Y1173258D01*
G01Y1180344D02*
Y1179557D01*
G01Y1186644D02*
Y1185856D01*
G01Y1183494D02*
Y1182707D01*
G01Y1189793D02*
Y1189006D01*
G01Y1196092D02*
Y1195305D01*
G01Y1192943D02*
Y1192155D01*
G01Y1199242D02*
Y1198455D01*
G01Y1205541D02*
Y1204754D01*
G01Y1202392D02*
Y1201604D01*
G01Y1208691D02*
Y1207903D01*
G01Y1211840D02*
Y1211053D01*
G01X1532732Y1217943D02*
Y1198651D01*
G01X1532458Y1201604D02*
Y1199242D01*
G01Y1204754D02*
Y1202392D01*
G01Y1211053D02*
Y1208691D01*
G01Y1207903D02*
Y1205541D01*
G01X1532417Y1142549D02*
Y1141762D01*
G01Y1148848D02*
Y1148061D01*
G01Y1145699D02*
Y1144911D01*
G01Y1151998D02*
Y1151211D01*
G01Y1158297D02*
Y1157510D01*
G01Y1155148D02*
Y1154360D01*
G01Y1161447D02*
Y1160659D01*
G01Y1167746D02*
Y1166959D01*
G01Y1164596D02*
Y1163809D01*
G01Y1170896D02*
Y1170108D01*
G01Y1177195D02*
Y1176407D01*
G01Y1174045D02*
Y1173258D01*
G01Y1180344D02*
Y1179557D01*
G01Y1186644D02*
Y1185856D01*
G01Y1183494D02*
Y1182707D01*
G01Y1189793D02*
Y1189006D01*
G01Y1196092D02*
Y1195305D01*
G01Y1192943D02*
Y1192155D01*
G01Y1199242D02*
Y1198455D01*
G01Y1205541D02*
Y1204754D01*
G01Y1202392D02*
Y1201604D01*
G01Y1208691D02*
Y1207903D01*
G01Y1211840D02*
Y1211053D01*
G01X1532391Y1142549D02*
Y1141762D01*
G01Y1148848D02*
Y1148061D01*
G01Y1145699D02*
Y1144911D01*
G01Y1151998D02*
Y1151211D01*
G01Y1158297D02*
Y1157510D01*
G01Y1155148D02*
Y1154360D01*
G01Y1161447D02*
Y1160659D01*
G01Y1167746D02*
Y1166959D01*
G01Y1164596D02*
Y1163809D01*
G01Y1170896D02*
Y1170108D01*
G01Y1177195D02*
Y1176407D01*
G01Y1174045D02*
Y1173258D01*
G01Y1180344D02*
Y1179557D01*
G01Y1186644D02*
Y1185856D01*
G01Y1183494D02*
Y1182707D01*
G01Y1189793D02*
Y1189006D01*
G01Y1196092D02*
Y1195305D01*
G01Y1192943D02*
Y1192155D01*
G01Y1199242D02*
Y1198455D01*
G01Y1205541D02*
Y1204754D01*
G01Y1202392D02*
Y1201604D01*
G01Y1208691D02*
Y1207903D01*
G01Y1211840D02*
Y1211053D01*
G01X1532024Y1182372D02*
Y1179222D01*
G01X1531945Y1217943D02*
Y1198651D01*
G01X1531630D02*
Y1217943D01*
G01X1526433Y1198553D02*
Y1218041D01*
G01Y1158592D02*
Y1142057D01*
G01Y1177490D02*
Y1160955D01*
G01Y1196191D02*
Y1179852D01*
G01X1503964Y1213708D02*
X1503838Y1213681D01*
X1503748Y1213608D01*
X1503717Y1213512D01*
G01X1509772Y1213708D02*
X1503964D01*
G01X1510035Y1213512D02*
X1503717D01*
G01Y1212527D02*
X1510035D01*
G01X1509772Y1212330D02*
X1503964D01*
G01X1503974Y1211840D02*
X1510058D01*
G01X1508945Y1213708D02*
X1508974Y1213705D01*
X1509001Y1213694D01*
X1509027Y1213675D01*
X1509049Y1213651D01*
X1509068Y1213621D01*
X1509081Y1213587D01*
X1509090Y1213550D01*
X1509093Y1213512D01*
G01X1507908Y1213708D02*
X1507914Y1213705D01*
X1507920Y1213694D01*
X1507926Y1213675D01*
X1507931Y1213651D01*
X1507935Y1213621D01*
X1507938Y1213587D01*
X1507940Y1213550D01*
X1507941Y1213512D01*
G01X1503717Y1212527D02*
X1503750Y1212428D01*
X1503838Y1212357D01*
X1503964Y1212330D01*
G01X1509093Y1212527D02*
X1509090Y1212489D01*
X1509081Y1212452D01*
X1509068Y1212418D01*
X1509049Y1212388D01*
X1509027Y1212364D01*
X1509002Y1212346D01*
X1508974Y1212334D01*
X1508945Y1212330D01*
G01X1507941Y1212527D02*
X1507940Y1212489D01*
X1507938Y1212452D01*
X1507935Y1212418D01*
X1507931Y1212388D01*
X1507926Y1212364D01*
X1507921Y1212346D01*
X1507915Y1212334D01*
X1507908Y1212330D01*
G01X1510035Y1213512D02*
Y1212527D01*
G01X1509093Y1213512D02*
Y1212527D01*
G01X1507941Y1213512D02*
Y1212527D01*
G01X1503717D02*
Y1213512D01*
G01X1509023Y1248848D02*
X1509050Y1248852D01*
X1509075Y1248863D01*
X1509099Y1248881D01*
X1509121Y1248906D01*
X1509138Y1248936D01*
X1509150Y1248970D01*
X1509158Y1249006D01*
X1509161Y1249045D01*
G01X1509023Y1245699D02*
X1509050Y1245702D01*
X1509075Y1245714D01*
X1509099Y1245732D01*
X1509121Y1245756D01*
X1509138Y1245786D01*
X1509150Y1245820D01*
X1509158Y1245857D01*
X1509161Y1245896D01*
G01X1509023Y1242549D02*
X1509050Y1242553D01*
X1509075Y1242564D01*
X1509099Y1242582D01*
X1509121Y1242607D01*
X1509138Y1242636D01*
X1509150Y1242670D01*
X1509158Y1242707D01*
X1509161Y1242746D01*
G01X1509023Y1239400D02*
X1509050Y1239403D01*
X1509075Y1239414D01*
X1509099Y1239432D01*
X1509121Y1239457D01*
X1509138Y1239487D01*
X1509150Y1239521D01*
X1509158Y1239557D01*
X1509161Y1239596D01*
G01X1509023Y1236250D02*
X1509050Y1236254D01*
X1509075Y1236265D01*
X1509099Y1236283D01*
X1509121Y1236308D01*
X1509138Y1236337D01*
X1509150Y1236371D01*
X1509158Y1236408D01*
X1509161Y1236447D01*
G01X1509023Y1233100D02*
X1509050Y1233104D01*
X1509075Y1233115D01*
X1509099Y1233133D01*
X1509121Y1233158D01*
X1509138Y1233188D01*
X1509150Y1233221D01*
X1509158Y1233258D01*
X1509161Y1233297D01*
G01X1509023Y1229951D02*
X1509050Y1229954D01*
X1509075Y1229966D01*
X1509099Y1229984D01*
X1509121Y1230008D01*
X1509138Y1230038D01*
X1509150Y1230072D01*
X1509158Y1230109D01*
X1509161Y1230148D01*
G01X1509023Y1226801D02*
X1509050Y1226805D01*
X1509075Y1226816D01*
X1509099Y1226834D01*
X1509121Y1226859D01*
X1509138Y1226888D01*
X1509150Y1226922D01*
X1509158Y1226959D01*
X1509161Y1226998D01*
G01X1509023Y1223651D02*
X1509050Y1223655D01*
X1509075Y1223666D01*
X1509099Y1223684D01*
X1509121Y1223709D01*
X1509138Y1223739D01*
X1509150Y1223773D01*
X1509158Y1223809D01*
X1509161Y1223848D01*
G01X1509023Y1220502D02*
X1509050Y1220506D01*
X1509075Y1220517D01*
X1509099Y1220535D01*
X1509121Y1220560D01*
X1509138Y1220589D01*
X1509150Y1220623D01*
X1509158Y1220660D01*
X1509161Y1220699D01*
G01X1509023Y1217352D02*
X1509050Y1217356D01*
X1509075Y1217367D01*
X1509099Y1217385D01*
X1509121Y1217410D01*
X1509138Y1217440D01*
X1509150Y1217473D01*
X1509158Y1217510D01*
X1509161Y1217549D01*
G01X1509023Y1214203D02*
X1509050Y1214206D01*
X1509075Y1214218D01*
X1509099Y1214236D01*
X1509121Y1214260D01*
X1509138Y1214290D01*
X1509150Y1214324D01*
X1509158Y1214361D01*
X1509161Y1214400D01*
G01X1503964Y1216858D02*
X1503838Y1216831D01*
X1503748Y1216758D01*
X1503717Y1216661D01*
G01X1503974Y1249636D02*
X1503846Y1249608D01*
X1503758Y1249535D01*
X1503727Y1249439D01*
G01X1503974Y1246486D02*
X1503846Y1246458D01*
X1503758Y1246385D01*
X1503727Y1246289D01*
G01X1503974Y1243337D02*
X1503846Y1243309D01*
X1503758Y1243236D01*
X1503727Y1243140D01*
G01X1503974Y1240187D02*
X1503846Y1240159D01*
X1503758Y1240086D01*
X1503727Y1239990D01*
G01X1503974Y1237037D02*
X1503846Y1237010D01*
X1503758Y1236937D01*
X1503727Y1236840D01*
G01X1503974Y1233888D02*
X1503846Y1233860D01*
X1503758Y1233787D01*
X1503727Y1233691D01*
G01X1503974Y1230738D02*
X1503846Y1230710D01*
X1503758Y1230637D01*
X1503727Y1230541D01*
G01X1503974Y1227588D02*
X1503846Y1227561D01*
X1503758Y1227488D01*
X1503727Y1227392D01*
G01X1503974Y1224439D02*
X1503846Y1224411D01*
X1503758Y1224338D01*
X1503727Y1224242D01*
G01X1503974Y1221289D02*
X1503846Y1221262D01*
X1503758Y1221189D01*
X1503727Y1221092D01*
G01X1503974Y1218140D02*
X1503846Y1218112D01*
X1503758Y1218039D01*
X1503727Y1217943D01*
G01X1503974Y1214990D02*
X1503846Y1214962D01*
X1503758Y1214889D01*
X1503727Y1214793D01*
G01X1497772Y1267884D02*
X1551709D01*
G01X1524149Y1266703D02*
X1497772D01*
G01X1501709Y1259537D02*
X1551709D01*
G01X1499740D02*
X1496457D01*
G01X1530449Y1255010D02*
X1499740D01*
G01X1520212Y1254616D02*
X1501709D01*
G01X1509749Y1251585D02*
X1504004D01*
G01X1510176Y1250994D02*
X1503590D01*
G01Y1250600D02*
X1510176D01*
G01X1504004Y1250010D02*
X1509749D01*
G01X1503974Y1249636D02*
X1510058D01*
G01X1503727Y1249439D02*
X1510338D01*
G01Y1249045D02*
X1503727D01*
G01X1503974Y1248848D02*
X1510058D01*
G01X1509749Y1246585D02*
X1504004D01*
G01X1503974Y1246486D02*
X1510058D01*
G01X1503727Y1246289D02*
X1510338D01*
G01X1510176Y1245994D02*
X1503590D01*
G01X1510338Y1245896D02*
X1503727D01*
G01X1503974Y1245699D02*
X1510058D01*
G01X1503590Y1245600D02*
X1510176D01*
G01X1504004Y1245010D02*
X1509749D01*
G01X1503974Y1243337D02*
X1510058D01*
G01X1503727Y1243140D02*
X1510338D01*
G01Y1242746D02*
X1503727D01*
G01X1503974Y1242549D02*
X1510058D01*
G01X1509749Y1241585D02*
X1504004D01*
G01X1510176Y1240994D02*
X1503590D01*
G01Y1240600D02*
X1510176D01*
G01X1503974Y1240187D02*
X1510058D01*
G01X1504004Y1240010D02*
X1509749D01*
G01X1503727Y1239990D02*
X1510338D01*
G01Y1239596D02*
X1503727D01*
G01X1503974Y1239400D02*
X1510058D01*
G01X1501709Y1238002D02*
X1528401D01*
G01X1503974Y1237037D02*
X1510058D01*
G01X1503727Y1236840D02*
X1510338D01*
G01X1509749Y1236585D02*
X1504004D01*
G01X1510338Y1236447D02*
X1503727D01*
G01X1503974Y1236250D02*
X1510058D01*
G01X1510176Y1235994D02*
X1503590D01*
G01X1528401Y1235640D02*
X1501709D01*
G01X1503590Y1235600D02*
X1510176D01*
G01X1504004Y1235010D02*
X1509749D01*
G01X1503974Y1233888D02*
X1510058D01*
G01X1503727Y1233691D02*
X1510338D01*
G01Y1233297D02*
X1503727D01*
G01X1503974Y1233100D02*
X1510058D01*
G01X1509749Y1231585D02*
X1504004D01*
G01X1510176Y1230994D02*
X1503590D01*
G01X1503974Y1230738D02*
X1510058D01*
G01X1503590Y1230600D02*
X1510176D01*
G01X1503727Y1230541D02*
X1510338D01*
G01Y1230148D02*
X1503727D01*
G01X1504004Y1230010D02*
X1509749D01*
G01X1503974Y1229951D02*
X1510058D01*
G01X1503974Y1227588D02*
X1510058D01*
G01X1503727Y1227392D02*
X1510338D01*
G01Y1226998D02*
X1503727D01*
G01X1503974Y1226801D02*
X1510058D01*
G01X1509749Y1226585D02*
X1504004D01*
G01X1510176Y1225994D02*
X1503590D01*
G01Y1225600D02*
X1510176D01*
G01X1504004Y1225010D02*
X1509749D01*
G01X1503974Y1224439D02*
X1510058D01*
G01X1520212Y1224400D02*
X1500751D01*
G01X1503727Y1224242D02*
X1510338D01*
G01Y1223848D02*
X1503727D01*
G01X1503974Y1223651D02*
X1510058D01*
G01X1509817Y1221585D02*
X1503904D01*
G01X1503974Y1221289D02*
X1510058D01*
G01X1503727Y1221092D02*
X1510338D01*
G01X1510241Y1220994D02*
X1503499D01*
G01X1510338Y1220699D02*
X1503727D01*
G01X1503499Y1220600D02*
X1510241D01*
G01X1503974Y1220502D02*
X1510058D01*
G01X1501709Y1220403D02*
X1528401D01*
G01X1509817Y1220010D02*
X1503904D01*
G01X1499740Y1219222D02*
X1506209D01*
G01X1503974Y1218140D02*
X1510058D01*
G01X1520212Y1218061D02*
X1501709D01*
G01X1528401Y1218041D02*
X1506209D01*
G01X1503727Y1217943D02*
X1510338D01*
G01Y1217549D02*
X1503727D01*
G01X1503974Y1217352D02*
X1510058D01*
G01X1509772Y1216858D02*
X1503964D01*
G01X1510035Y1216661D02*
X1503717D01*
G01Y1215677D02*
X1510035D01*
G01X1509772Y1215480D02*
X1503964D01*
G01X1503974Y1214990D02*
X1510058D01*
G01X1503727Y1214793D02*
X1510338D01*
G01Y1214400D02*
X1503727D01*
G01X1503974Y1214203D02*
X1510058D01*
G01X1508945Y1216858D02*
X1508974Y1216854D01*
X1509001Y1216843D01*
X1509027Y1216825D01*
X1509049Y1216800D01*
X1509068Y1216771D01*
X1509081Y1216737D01*
X1509090Y1216700D01*
X1509093Y1216661D01*
G01X1508572Y1249636D02*
X1508610Y1249609D01*
X1508638Y1249537D01*
X1508648Y1249439D01*
G01X1508572Y1246486D02*
X1508610Y1246460D01*
X1508638Y1246388D01*
X1508648Y1246289D01*
G01X1508572Y1243337D02*
X1508610Y1243310D01*
X1508638Y1243238D01*
X1508648Y1243140D01*
G01X1508572Y1240187D02*
X1508610Y1240161D01*
X1508638Y1240088D01*
X1508648Y1239990D01*
G01X1508572Y1237037D02*
X1508610Y1237011D01*
X1508638Y1236939D01*
X1508648Y1236840D01*
G01X1508572Y1233888D02*
X1508610Y1233861D01*
X1508638Y1233789D01*
X1508648Y1233691D01*
G01X1508572Y1230738D02*
X1508610Y1230712D01*
X1508638Y1230640D01*
X1508648Y1230541D01*
G01X1508572Y1227588D02*
X1508610Y1227562D01*
X1508638Y1227490D01*
X1508648Y1227392D01*
G01X1508572Y1224439D02*
X1508610Y1224412D01*
X1508638Y1224340D01*
X1508648Y1224242D01*
G01X1508572Y1221289D02*
X1508610Y1221263D01*
X1508638Y1221191D01*
X1508648Y1221092D01*
G01X1507908Y1216858D02*
X1507914Y1216854D01*
X1507920Y1216843D01*
X1507926Y1216825D01*
X1507931Y1216800D01*
X1507935Y1216771D01*
X1507938Y1216737D01*
X1507940Y1216700D01*
X1507941Y1216661D01*
G01X1508572Y1220502D02*
X1508610Y1220528D01*
X1508638Y1220600D01*
X1508648Y1220699D01*
G01X1508572Y1223651D02*
X1508610Y1223678D01*
X1508638Y1223750D01*
X1508648Y1223848D01*
G01X1508572Y1233100D02*
X1508610Y1233127D01*
X1508638Y1233199D01*
X1508648Y1233297D01*
G01X1508572Y1236250D02*
X1508610Y1236276D01*
X1508638Y1236348D01*
X1508648Y1236447D01*
G01X1508572Y1239400D02*
X1508610Y1239426D01*
X1508638Y1239498D01*
X1508648Y1239596D01*
G01X1508572Y1248848D02*
X1508610Y1248875D01*
X1508638Y1248947D01*
X1508648Y1249045D01*
G01X1499740Y1256585D02*
X1501709Y1254616D01*
G01Y1218061D02*
X1499740Y1220029D01*
G01X1508572Y1218140D02*
X1508610Y1218113D01*
X1508638Y1218041D01*
X1508648Y1217943D01*
G01X1508572Y1214990D02*
X1508610Y1214964D01*
X1508638Y1214892D01*
X1508648Y1214793D01*
G01X1501709Y1259537D02*
X1499740Y1257569D01*
G01X1509749Y1225010D02*
X1510176Y1225600D01*
G01X1509749Y1230010D02*
X1510176Y1230600D01*
G01X1509749Y1235010D02*
X1510176Y1235600D01*
G01X1509749Y1240010D02*
X1510176Y1240600D01*
G01X1509749Y1245010D02*
X1510176Y1245600D01*
G01X1509749Y1250010D02*
X1510176Y1250600D01*
G01X1509817Y1220010D02*
X1510241Y1220600D01*
G01X1504004Y1226585D02*
X1503865Y1226389D01*
X1503727Y1226192D01*
X1503590Y1225994D01*
G01X1504004Y1231585D02*
X1503865Y1231389D01*
X1503727Y1231192D01*
X1503590Y1230994D01*
G01X1504004Y1236585D02*
X1503865Y1236389D01*
X1503727Y1236192D01*
X1503590Y1235994D01*
G01X1504004Y1241585D02*
X1503865Y1241389D01*
X1503727Y1241192D01*
X1503590Y1240994D01*
G01X1504004Y1246585D02*
X1503865Y1246389D01*
X1503727Y1246192D01*
X1503590Y1245994D01*
G01X1504004Y1251585D02*
X1503865Y1251389D01*
X1503727Y1251192D01*
X1503590Y1250994D01*
G01X1503904Y1221585D02*
X1503768Y1221388D01*
X1503633Y1221192D01*
X1503499Y1220994D01*
G01X1503727Y1249045D02*
X1503758Y1248948D01*
X1503847Y1248876D01*
X1503974Y1248848D01*
G01X1503727Y1245896D02*
X1503758Y1245799D01*
X1503847Y1245726D01*
X1503974Y1245699D01*
G01X1503727Y1242746D02*
X1503758Y1242649D01*
X1503847Y1242577D01*
X1503974Y1242549D01*
G01X1503727Y1239596D02*
X1503758Y1239499D01*
X1503847Y1239427D01*
X1503974Y1239400D01*
G01X1503727Y1236447D02*
X1503758Y1236350D01*
X1503847Y1236278D01*
X1503974Y1236250D01*
G01X1503727Y1233297D02*
X1503758Y1233200D01*
X1503847Y1233128D01*
X1503974Y1233100D01*
G01X1509060Y1251585D02*
X1509332Y1250994D01*
G01X1509060Y1246585D02*
X1509332Y1245994D01*
G01X1509060Y1241585D02*
X1509332Y1240994D01*
G01X1509060Y1236585D02*
X1509332Y1235994D01*
G01X1509060Y1231585D02*
X1509332Y1230994D01*
G01X1509060Y1226585D02*
X1509332Y1225994D01*
G01X1509060Y1221585D02*
X1509332Y1220994D01*
G01X1503499Y1220600D02*
X1503633Y1220403D01*
X1503768Y1220206D01*
X1503904Y1220010D01*
G01X1503590Y1250600D02*
X1503727Y1250403D01*
X1503865Y1250206D01*
X1504004Y1250010D01*
G01X1503590Y1245600D02*
X1503727Y1245403D01*
X1503865Y1245206D01*
X1504004Y1245010D01*
G01X1503590Y1240600D02*
X1503727Y1240403D01*
X1503865Y1240206D01*
X1504004Y1240010D01*
G01X1503590Y1235600D02*
X1503727Y1235403D01*
X1503865Y1235206D01*
X1504004Y1235010D01*
G01X1503590Y1230600D02*
X1503727Y1230403D01*
X1503865Y1230206D01*
X1504004Y1230010D01*
G01X1503590Y1225600D02*
X1503727Y1225403D01*
X1503865Y1225206D01*
X1504004Y1225010D01*
G01X1509817Y1221585D02*
X1510241Y1220994D01*
G01X1509749Y1251585D02*
X1510176Y1250994D01*
G01X1509749Y1246585D02*
X1510176Y1245994D01*
G01X1509749Y1241585D02*
X1510176Y1240994D01*
G01X1509749Y1236585D02*
X1510176Y1235994D01*
G01X1509749Y1231585D02*
X1510176Y1230994D01*
G01X1509749Y1226585D02*
X1510176Y1225994D01*
G01X1509332Y1220600D02*
X1509060Y1220010D01*
G01X1509332Y1225600D02*
X1509060Y1225010D01*
G01X1509332Y1230600D02*
X1509060Y1230010D01*
G01X1509332Y1235600D02*
X1509060Y1235010D01*
G01X1509332Y1240600D02*
X1509060Y1240010D01*
G01X1509332Y1245600D02*
X1509060Y1245010D01*
G01X1509332Y1250600D02*
X1509060Y1250010D01*
G01X1497740Y1267853D02*
X1497683Y1267718D01*
X1497677Y1267483D01*
X1497714Y1267154D01*
G01X1497740Y1267853D02*
X1497682Y1267713D01*
X1497677Y1267473D01*
G01X1508208Y1220600D02*
X1508130Y1220010D01*
G01X1508208Y1225600D02*
X1508130Y1225010D01*
G01X1508208Y1230600D02*
X1508130Y1230010D01*
G01X1508208Y1250994D02*
X1508130Y1251585D01*
G01X1508208Y1245994D02*
X1508130Y1246585D01*
G01X1508208Y1240994D02*
X1508130Y1241585D01*
G01X1508208Y1235994D02*
X1508130Y1236585D01*
G01X1508208Y1230994D02*
X1508130Y1231585D01*
G01X1508208Y1225994D02*
X1508130Y1226585D01*
G01X1508208Y1220994D02*
X1508130Y1221585D01*
G01X1497712Y1267162D02*
X1497767Y1266776D01*
G01X1503727Y1230148D02*
X1503758Y1230051D01*
X1503847Y1229978D01*
X1503974Y1229951D01*
G01X1503727Y1226998D02*
X1503758Y1226901D01*
X1503847Y1226829D01*
X1503974Y1226801D01*
G01X1503727Y1223848D02*
X1503758Y1223751D01*
X1503847Y1223679D01*
X1503974Y1223651D01*
G01X1503727Y1220699D02*
X1503758Y1220602D01*
X1503847Y1220530D01*
X1503974Y1220502D01*
G01X1503727Y1217549D02*
X1503758Y1217452D01*
X1503847Y1217380D01*
X1503974Y1217352D01*
G01X1503727Y1214400D02*
X1503758Y1214303D01*
X1503847Y1214230D01*
X1503974Y1214203D01*
G01X1503717Y1215677D02*
X1503750Y1215578D01*
X1503838Y1215507D01*
X1503964Y1215480D01*
G01X1508208Y1235600D02*
X1508130Y1235010D01*
G01X1508208Y1240600D02*
X1508130Y1240010D01*
G01X1508208Y1245600D02*
X1508130Y1245010D01*
G01X1508208Y1250600D02*
X1508130Y1250010D01*
G01X1508648Y1214400D02*
X1508638Y1214301D01*
X1508610Y1214229D01*
X1508572Y1214203D01*
G01X1508648Y1217549D02*
X1508638Y1217451D01*
X1508610Y1217379D01*
X1508572Y1217352D01*
G01X1508648Y1226998D02*
X1508638Y1226900D01*
X1508610Y1226827D01*
X1508572Y1226801D01*
G01X1508648Y1230148D02*
X1508638Y1230049D01*
X1508610Y1229977D01*
X1508572Y1229951D01*
G01X1508648Y1242746D02*
X1508638Y1242648D01*
X1508610Y1242576D01*
X1508572Y1242549D01*
G01X1508648Y1245896D02*
X1508638Y1245797D01*
X1508610Y1245725D01*
X1508572Y1245699D01*
G01X1509093Y1215677D02*
X1509090Y1215639D01*
X1509081Y1215602D01*
X1509068Y1215568D01*
X1509049Y1215538D01*
X1509027Y1215513D01*
X1509002Y1215495D01*
X1508974Y1215484D01*
X1508945Y1215480D01*
G01X1507941Y1215677D02*
X1507940Y1215639D01*
X1507938Y1215602D01*
X1507935Y1215568D01*
X1507931Y1215538D01*
X1507926Y1215513D01*
X1507921Y1215495D01*
X1507915Y1215484D01*
X1507908Y1215480D01*
G01X1510338Y1249045D02*
Y1249439D01*
G01Y1245896D02*
Y1246289D01*
G01Y1239596D02*
Y1239990D01*
G01Y1242746D02*
Y1243140D01*
G01Y1236447D02*
Y1236840D01*
G01Y1230148D02*
Y1230541D01*
G01Y1233297D02*
Y1233691D01*
G01Y1226998D02*
Y1227392D01*
G01Y1220699D02*
Y1221092D01*
G01Y1223848D02*
Y1224242D01*
G01Y1217549D02*
Y1217943D01*
G01Y1214400D02*
Y1214793D01*
G01X1510241Y1220994D02*
Y1220600D01*
G01X1510176Y1225994D02*
Y1225600D01*
G01Y1230994D02*
Y1230600D01*
G01Y1235994D02*
Y1235600D01*
G01Y1240994D02*
Y1240600D01*
G01Y1245994D02*
Y1245600D01*
G01Y1250994D02*
Y1250600D01*
G01X1510035Y1216661D02*
Y1215677D01*
G01X1509332Y1220994D02*
Y1220600D01*
G01Y1225994D02*
Y1225600D01*
G01Y1230994D02*
Y1230600D01*
G01Y1235994D02*
Y1235600D01*
G01Y1240994D02*
Y1240600D01*
G01Y1245994D02*
Y1245600D01*
G01Y1250994D02*
Y1250600D01*
G01X1509161Y1249045D02*
Y1249439D01*
G01Y1245896D02*
Y1246289D01*
G01Y1239596D02*
Y1239990D01*
G01Y1242746D02*
Y1243140D01*
G01Y1236447D02*
Y1236840D01*
G01Y1230148D02*
Y1230541D01*
G01Y1233297D02*
Y1233691D01*
G01Y1226998D02*
Y1227392D01*
G01Y1220699D02*
Y1221092D01*
G01Y1223848D02*
Y1224242D01*
G01Y1217549D02*
Y1217943D01*
G01Y1214400D02*
Y1214793D01*
G01X1509093Y1216661D02*
Y1215677D01*
G01X1508648Y1214793D02*
Y1214400D01*
G01Y1217943D02*
Y1217549D01*
G01Y1221092D02*
Y1220699D01*
G01Y1224242D02*
Y1223848D01*
G01Y1227392D02*
Y1226998D01*
G01Y1230541D02*
Y1230148D01*
G01Y1233691D02*
Y1233297D01*
G01Y1236840D02*
Y1236447D01*
G01Y1239990D02*
Y1239596D01*
G01Y1243140D02*
Y1242746D01*
G01Y1246289D02*
Y1245896D01*
G01Y1249439D02*
Y1249045D01*
G01X1508208Y1250600D02*
Y1250994D01*
G01Y1245600D02*
Y1245994D01*
G01Y1240600D02*
Y1240994D01*
G01Y1235600D02*
Y1235994D01*
G01Y1230600D02*
Y1230994D01*
G01Y1225600D02*
Y1225994D01*
G01Y1220600D02*
Y1220994D01*
G01X1507941Y1216661D02*
Y1215677D01*
G01X1506209Y1218041D02*
Y1219222D01*
G01X1503727Y1214793D02*
Y1214400D01*
G01Y1217943D02*
Y1217549D01*
G01Y1221092D02*
Y1220699D01*
G01Y1224242D02*
Y1223848D01*
G01Y1227392D02*
Y1226998D01*
G01Y1230541D02*
Y1230148D01*
G01Y1233691D02*
Y1233297D01*
G01Y1236840D02*
Y1236447D01*
G01Y1239990D02*
Y1239596D01*
G01Y1243140D02*
Y1242746D01*
G01Y1246289D02*
Y1245896D01*
G01Y1249439D02*
Y1249045D01*
G01X1503717Y1215677D02*
Y1216661D01*
G01X1503590Y1250600D02*
Y1250994D01*
G01Y1245600D02*
Y1245994D01*
G01Y1240600D02*
Y1240994D01*
G01Y1235600D02*
Y1235994D01*
G01Y1230600D02*
Y1230994D01*
G01Y1225600D02*
Y1225994D01*
G01X1503499Y1220600D02*
Y1220994D01*
G01X1500921Y1224400D02*
Y1255403D01*
G01X1500751Y1219018D02*
Y1224400D01*
G01X1497772Y1266703D02*
Y1259537D01*
G01X1509161Y1249439D02*
X1509158Y1249477D01*
X1509151Y1249514D01*
X1509138Y1249548D01*
X1509121Y1249578D01*
X1509100Y1249602D01*
X1509076Y1249621D01*
X1509050Y1249632D01*
X1509023Y1249636D01*
G01X1509161Y1246289D02*
X1509158Y1246328D01*
X1509151Y1246364D01*
X1509138Y1246398D01*
X1509121Y1246428D01*
X1509100Y1246453D01*
X1509076Y1246471D01*
X1509050Y1246482D01*
X1509023Y1246486D01*
G01X1509161Y1243140D02*
X1509158Y1243178D01*
X1509151Y1243215D01*
X1509138Y1243249D01*
X1509121Y1243279D01*
X1509100Y1243303D01*
X1509076Y1243321D01*
X1509050Y1243333D01*
X1509023Y1243337D01*
G01X1509161Y1239990D02*
X1509158Y1240028D01*
X1509151Y1240065D01*
X1509138Y1240099D01*
X1509121Y1240129D01*
X1509100Y1240154D01*
X1509076Y1240172D01*
X1509050Y1240183D01*
X1509023Y1240187D01*
G01X1509161Y1236840D02*
X1509158Y1236879D01*
X1509151Y1236915D01*
X1509138Y1236949D01*
X1509121Y1236980D01*
X1509100Y1237004D01*
X1509076Y1237022D01*
X1509050Y1237033D01*
X1509023Y1237037D01*
G01X1509161Y1233691D02*
X1509158Y1233729D01*
X1509151Y1233766D01*
X1509138Y1233800D01*
X1509121Y1233830D01*
X1509100Y1233854D01*
X1509076Y1233873D01*
X1509050Y1233884D01*
X1509023Y1233888D01*
G01X1509161Y1230541D02*
X1509158Y1230579D01*
X1509151Y1230616D01*
X1509138Y1230650D01*
X1509121Y1230680D01*
X1509100Y1230705D01*
X1509076Y1230723D01*
X1509050Y1230734D01*
X1509023Y1230738D01*
G01X1509161Y1227392D02*
X1509158Y1227430D01*
X1509151Y1227467D01*
X1509138Y1227501D01*
X1509121Y1227531D01*
X1509100Y1227555D01*
X1509076Y1227573D01*
X1509050Y1227585D01*
X1509023Y1227588D01*
G01X1509161Y1224242D02*
X1509158Y1224280D01*
X1509151Y1224317D01*
X1509138Y1224351D01*
X1509121Y1224381D01*
X1509100Y1224406D01*
X1509076Y1224424D01*
X1509050Y1224435D01*
X1509023Y1224439D01*
G01X1509161Y1221092D02*
X1509158Y1221131D01*
X1509151Y1221167D01*
X1509138Y1221201D01*
X1509121Y1221232D01*
X1509100Y1221256D01*
X1509076Y1221274D01*
X1509050Y1221285D01*
X1509023Y1221289D01*
G01X1509161Y1217943D02*
X1509158Y1217981D01*
X1509151Y1218018D01*
X1509138Y1218052D01*
X1509121Y1218082D01*
X1509100Y1218106D01*
X1509076Y1218125D01*
X1509050Y1218136D01*
X1509023Y1218140D01*
G01X1509161Y1214793D02*
X1509158Y1214831D01*
X1509151Y1214868D01*
X1509138Y1214902D01*
X1509121Y1214932D01*
X1509100Y1214957D01*
X1509076Y1214975D01*
X1509050Y1214986D01*
X1509023Y1214990D01*
G01X1533442Y1214006D02*
X1532458D01*
G01X1533442Y1213809D02*
X1532458D01*
G01X1531551Y1213612D02*
X1537576D01*
G01X1531551Y1212431D02*
X1537576D01*
G01X1533442Y1212234D02*
X1532458D01*
G01X1533442Y1212037D02*
X1532458D01*
G01X1539440Y1211919D02*
X1537558D01*
G01X1542605Y1211840D02*
X1549937D01*
G01X1542457D02*
X1530449D01*
G01X1541519D02*
Y1214203D01*
G01X1539440Y1214124D02*
Y1211919D01*
G01X1537576Y1212431D02*
Y1213612D01*
G01X1537558Y1211919D02*
Y1214124D01*
G01X1534427Y1213612D02*
Y1212431D01*
G01X1532458Y1214203D02*
Y1211840D01*
G01X1532220Y1273337D02*
G03Y1276486I0J1574D01*
G01X1527890D02*
G03Y1273337I0J-1575D01*
G01X1541472Y1263100D02*
G03I-2165J0D01*
G01X1542653D02*
G03I-3346J0D01*
G01X1542811D02*
G03I-3504J0D01*
G01X1543835D02*
G03I-4528J0D01*
G01X1547119Y1261496D02*
G03X1549334Y1266663I-6937J6032D01*
G01X1546234Y1261422D02*
G03X1548448Y1266663I-7143J6105D01*
G01X1531945Y1250010D02*
G03X1531551Y1249616I0J-394D01*
G01Y1251978D02*
G03X1531945Y1251585I394J1D01*
G01X1531551Y1226978D02*
G03X1531945Y1226585I394J1D01*
G01Y1230010D02*
G03X1531551Y1229616I0J-394D01*
G01Y1231978D02*
G03X1531945Y1231585I394J1D01*
G01Y1240010D02*
G03X1531551Y1239616I0J-394D01*
G01Y1241978D02*
G03X1531945Y1241585I394J1D01*
G01Y1235010D02*
G03X1531551Y1234616I0J-394D01*
G01Y1236978D02*
G03X1531945Y1236585I394J1D01*
G01Y1245010D02*
G03X1531551Y1244616I0J-394D01*
G01Y1246978D02*
G03X1531945Y1246585I394J1D01*
G01X1533143Y1264941D02*
G03X1533685Y1265925I-1276J1344D01*
G01X1531945Y1220010D02*
G03X1531551Y1219616I0J-394D01*
G01Y1221978D02*
G03X1531945Y1221585I394J1D01*
G01Y1225010D02*
G03X1531551Y1224616I0J-394D01*
G01X1533648Y1264397D02*
G03X1534718Y1266220I-2809J2874D01*
G01X1526672Y1261496D02*
G03X1528886Y1266663I-6938J6031D01*
G01X1525786Y1261422D02*
G03X1528001Y1266663I-7142J6107D01*
G01X1526522Y1253297D02*
X1526174Y1253212D01*
G01X1528177Y1253041D02*
X1527829Y1252956D01*
G01X1538244Y1280817D02*
X1521866D01*
G01X1527890Y1276486D02*
X1532220D01*
G01X1527264Y1275699D02*
X1532846D01*
G01Y1274124D02*
X1527264D01*
G01X1532220Y1273337D02*
X1527890D01*
G01X1538244Y1270640D02*
X1521866D01*
G01X1528886Y1266663D02*
X1528000D01*
G01X1534718D02*
X1530806D01*
G01X1549334D02*
X1548448D01*
G01X1530806Y1265925D02*
X1533684D01*
G01X1551709Y1265915D02*
X1528087D01*
G01X1534423Y1262456D02*
X1533611D01*
G01X1528087Y1262136D02*
X1551709D01*
G01X1529624Y1261496D02*
X1526672D01*
G01X1550072D02*
X1547119D01*
G01X1546234Y1260758D02*
X1550072D01*
G01X1525786D02*
X1529624D01*
G01X1551709Y1260167D02*
X1528087D01*
G01Y1257726D02*
X1551709D01*
G01X1536549Y1257234D02*
X1530449D01*
G01X1536549Y1257175D02*
X1530449D01*
G01X1550916Y1256781D02*
X1530449D01*
G01X1531551Y1255600D02*
X1522181D01*
G01X1521866Y1254419D02*
X1528401D01*
G01X1531551Y1254203D02*
X1551709D01*
G01X1531551Y1253829D02*
X1522181D01*
G01X1528526Y1253041D02*
X1528177D01*
G01X1528265Y1252529D02*
X1528439D01*
G01X1534976Y1252372D02*
X1533992D01*
G01X1535567Y1252214D02*
X1544551D01*
G01X1534976Y1252175D02*
X1533992D01*
G01X1534976Y1251781D02*
X1533992D01*
G01X1540075Y1251762D02*
X1532004D01*
G01X1531945Y1251585D02*
X1539110D01*
G01X1526696Y1250653D02*
X1526435D01*
G01X1526348Y1250141D02*
X1526784D01*
G01X1531945Y1250010D02*
X1539110D01*
G01X1534976Y1249813D02*
X1533992D01*
G01X1532004Y1249793D02*
X1540075D01*
G01X1542605Y1249636D02*
X1549937D01*
G01X1542457D02*
X1530449D01*
G01X1528177Y1249459D02*
X1528874D01*
G01X1534976Y1249419D02*
X1533992D01*
G01X1534976Y1249222D02*
X1533992D01*
G01X1525390Y1248947D02*
X1528787D01*
G01X1542457Y1248848D02*
X1530449D01*
G01X1549937D02*
X1542605D01*
G01X1529484Y1248435D02*
X1525390D01*
G01X1534976Y1247372D02*
X1533992D01*
G01X1534976Y1247175D02*
X1533992D01*
G01X1534976Y1246781D02*
X1533992D01*
G01X1531945Y1246585D02*
X1539110D01*
G01X1542605Y1246486D02*
X1549937D01*
G01X1542457D02*
X1530449D01*
G01X1542457Y1245699D02*
X1530449D01*
G01X1549937D02*
X1542605D01*
G01X1531945Y1245010D02*
X1539110D01*
G01X1534976Y1244813D02*
X1533992D01*
G01X1534976Y1244419D02*
X1533992D01*
G01X1534976Y1244222D02*
X1533992D01*
G01X1542605Y1243337D02*
X1549937D01*
G01X1542457D02*
X1530449D01*
G01X1542457Y1242549D02*
X1530449D01*
G01X1549937D02*
X1542605D01*
G01X1534976Y1242372D02*
X1533992D01*
G01X1534976Y1242175D02*
X1533992D01*
G01X1534976Y1241781D02*
X1533992D01*
G01X1531945Y1241585D02*
X1539110D01*
G01X1542605Y1240187D02*
X1549937D01*
G01X1542457D02*
X1530449D01*
G01X1531945Y1240010D02*
X1539110D01*
G01X1534976Y1239813D02*
X1533992D01*
G01X1534976Y1239419D02*
X1533992D01*
G01X1542457Y1239400D02*
X1530449D01*
G01X1549937D02*
X1542605D01*
G01X1534976Y1239222D02*
X1533992D01*
G01X1534976Y1237372D02*
X1533992D01*
G01X1534976Y1237175D02*
X1533992D01*
G01X1542605Y1237037D02*
X1549937D01*
G01X1542457D02*
X1530449D01*
G01X1534976Y1236781D02*
X1533992D01*
G01X1531945Y1236585D02*
X1539110D01*
G01X1542457Y1236250D02*
X1530449D01*
G01X1549937D02*
X1542605D01*
G01X1531945Y1235010D02*
X1539110D01*
G01X1534976Y1234813D02*
X1533992D01*
G01X1534976Y1234419D02*
X1533992D01*
G01X1534976Y1234222D02*
X1533992D01*
G01X1542605Y1233888D02*
X1549937D01*
G01X1542457D02*
X1530449D01*
G01X1542457Y1233100D02*
X1530449D01*
G01X1549937D02*
X1542605D01*
G01X1534976Y1232372D02*
X1533992D01*
G01X1534976Y1232175D02*
X1533992D01*
G01X1534976Y1231781D02*
X1533992D01*
G01X1531945Y1231585D02*
X1539110D01*
G01X1542605Y1230738D02*
X1549937D01*
G01X1542457D02*
X1530449D01*
G01X1531945Y1230010D02*
X1539110D01*
G01X1542457Y1229951D02*
X1530449D01*
G01X1549937D02*
X1542605D01*
G01X1534976Y1229813D02*
X1533992D01*
G01X1534976Y1229419D02*
X1533992D01*
G01X1534976Y1229222D02*
X1533992D01*
G01X1542605Y1227588D02*
X1549937D01*
G01X1542457D02*
X1530449D01*
G01X1534976Y1227372D02*
X1533992D01*
G01X1534976Y1227175D02*
X1533992D01*
G01X1542457Y1226801D02*
X1530449D01*
G01X1549937D02*
X1542605D01*
G01X1534976Y1226781D02*
X1533992D01*
G01X1531945Y1226585D02*
X1539110D01*
G01X1531945Y1225010D02*
X1539110D01*
G01X1534976Y1224813D02*
X1533992D01*
G01X1542605Y1224439D02*
X1549937D01*
G01X1542457D02*
X1530449D01*
G01X1534976Y1224419D02*
X1533992D01*
G01X1534976Y1224222D02*
X1533992D01*
G01X1542457Y1223651D02*
X1530449D01*
G01X1549937D02*
X1542605D01*
G01X1534976Y1222372D02*
X1533992D01*
G01X1534976Y1222175D02*
X1533992D01*
G01X1534976Y1221781D02*
X1533992D01*
G01X1531945Y1221585D02*
X1539110D01*
G01X1542605Y1221289D02*
X1549937D01*
G01X1542457D02*
X1530449D01*
G01X1542457Y1220502D02*
X1530449D01*
G01X1549937D02*
X1542605D01*
G01X1531945Y1220010D02*
X1539110D01*
G01X1534976Y1219813D02*
X1533992D01*
G01X1534976Y1219419D02*
X1533992D01*
G01X1534976Y1219222D02*
X1533992D01*
G01X1542605Y1218140D02*
X1549937D01*
G01X1542457D02*
X1530449D01*
G01X1531551Y1218061D02*
X1530449D01*
G01Y1217943D02*
X1537984D01*
G01X1535567Y1217451D02*
X1533442D01*
G01X1542457Y1217352D02*
X1530449D01*
G01X1549937D02*
X1542605D01*
G01X1533442Y1217155D02*
X1532458D01*
G01X1533442Y1216959D02*
X1532458D01*
G01X1531551Y1216762D02*
X1537576D01*
G01X1531551Y1215581D02*
X1537576D01*
G01X1533442Y1215384D02*
X1532458D01*
G01X1533442Y1215187D02*
X1532458D01*
G01X1542605Y1214990D02*
X1549937D01*
G01X1542457D02*
X1530449D01*
G01X1542457Y1214203D02*
X1530449D01*
G01X1549937D02*
X1542605D01*
G01X1539440Y1214124D02*
X1537558D01*
G01X1528874Y1252956D02*
X1528526Y1253041D01*
G01X1532712Y1261496D02*
X1532365Y1261565D01*
G01X1528526Y1250397D02*
X1528787Y1250482D01*
G01X1528003Y1252444D02*
X1528265Y1252529D01*
G01X1526261Y1252700D02*
X1526522Y1252785D01*
G01X1525999Y1250312D02*
X1526348Y1250141D01*
G01X1528439Y1252529D02*
X1528700Y1252444D01*
G01Y1250994D02*
X1528526Y1250909D01*
G01X1526784Y1250141D02*
X1527132Y1250312D01*
G01X1526174Y1253212D02*
X1525738Y1252956D01*
G01X1528874Y1249459D02*
X1529484Y1248947D01*
G01X1528787D02*
X1528177Y1249459D01*
G01X1543482Y1265847D02*
X1543843Y1265611D01*
X1544081Y1265261D01*
X1544167Y1264857D01*
X1544084Y1264455D01*
X1543848Y1264103D01*
X1543484Y1263863D01*
X1543059Y1263778D01*
G01X1542636Y1263862D02*
X1542276Y1264098D01*
X1542038Y1264448D01*
X1541952Y1264852D01*
X1542035Y1265254D01*
X1542271Y1265606D01*
X1542635Y1265846D01*
X1543059Y1265931D01*
G01X1538315Y1265847D02*
X1538675Y1265611D01*
X1538914Y1265261D01*
X1538999Y1264857D01*
X1538917Y1264455D01*
X1538680Y1264103D01*
X1538317Y1263863D01*
X1537892Y1263778D01*
G01X1537469Y1263862D02*
X1537109Y1264098D01*
X1536870Y1264448D01*
X1536785Y1264852D01*
X1536867Y1265254D01*
X1537104Y1265606D01*
X1537467Y1265846D01*
X1537892Y1265931D01*
G01X1526435Y1250653D02*
X1526174Y1250823D01*
G01X1532366Y1261565D02*
X1532086Y1261746D01*
G01X1543408Y1263055D02*
X1543691Y1262877D01*
X1543878Y1262612D01*
X1543945Y1262310D01*
X1543881Y1262010D01*
X1543695Y1261743D01*
X1543410Y1261562D01*
X1543059Y1261496D01*
G01X1542711Y1261561D02*
X1542428Y1261739D01*
X1542241Y1262004D01*
X1542174Y1262306D01*
X1542238Y1262606D01*
X1542424Y1262873D01*
X1542709Y1263054D01*
X1543059Y1263120D01*
G01X1538241Y1263055D02*
X1538524Y1262877D01*
X1538711Y1262612D01*
X1538778Y1262310D01*
X1538713Y1262010D01*
X1538528Y1261743D01*
X1538243Y1261562D01*
X1537892Y1261496D01*
G01X1537543Y1261561D02*
X1537261Y1261739D01*
X1537073Y1262004D01*
X1537006Y1262306D01*
X1537071Y1262606D01*
X1537256Y1262873D01*
X1537542Y1263054D01*
X1537892Y1263120D01*
G01X1533354Y1261737D02*
X1533067Y1261558D01*
X1532713Y1261496D01*
G01X1543408Y1261561D02*
X1543691Y1261739D01*
X1543878Y1262004D01*
X1543945Y1262306D01*
X1543881Y1262606D01*
X1543695Y1262873D01*
X1543410Y1263054D01*
X1543059Y1263120D01*
G01X1542711Y1263055D02*
X1542428Y1262877D01*
X1542241Y1262612D01*
X1542174Y1262310D01*
X1542238Y1262010D01*
X1542424Y1261743D01*
X1542709Y1261562D01*
X1543059Y1261496D01*
G01X1538241Y1261561D02*
X1538524Y1261739D01*
X1538711Y1262004D01*
X1538778Y1262306D01*
X1538713Y1262606D01*
X1538528Y1262873D01*
X1538243Y1263054D01*
X1537892Y1263120D01*
G01X1537543Y1263055D02*
X1537261Y1262877D01*
X1537073Y1262612D01*
X1537006Y1262310D01*
X1537071Y1262010D01*
X1537256Y1261743D01*
X1537542Y1261562D01*
X1537892Y1261496D01*
G01X1526958Y1250823D02*
X1526696Y1250653D01*
G01X1543482Y1263862D02*
X1543843Y1264098D01*
X1544081Y1264448D01*
X1544167Y1264852D01*
X1544084Y1265254D01*
X1543848Y1265606D01*
X1543484Y1265846D01*
X1543059Y1265931D01*
G01X1542636Y1265847D02*
X1542276Y1265611D01*
X1542038Y1265261D01*
X1541952Y1264857D01*
X1542035Y1264455D01*
X1542271Y1264103D01*
X1542635Y1263863D01*
X1543059Y1263778D01*
G01X1538315Y1263862D02*
X1538675Y1264098D01*
X1538914Y1264448D01*
X1538999Y1264852D01*
X1538917Y1265254D01*
X1538680Y1265606D01*
X1538317Y1265846D01*
X1537892Y1265931D01*
G01X1537469Y1265847D02*
X1537109Y1265611D01*
X1536870Y1265261D01*
X1536785Y1264857D01*
X1536867Y1264455D01*
X1537104Y1264103D01*
X1537467Y1263863D01*
X1537892Y1263778D01*
G01X1528787Y1250482D02*
X1529136Y1250738D01*
G01X1544257Y1263407D02*
X1544709Y1263847D01*
X1544979Y1264383D01*
X1545049Y1264953D01*
X1544908Y1265517D01*
X1544561Y1266042D01*
X1544034Y1266435D01*
X1543391Y1266638D01*
X1542712Y1266636D01*
X1542072Y1266428D01*
X1541549Y1266032D01*
X1541207Y1265508D01*
X1541069Y1264947D01*
X1541141Y1264379D01*
X1541411Y1263845D01*
X1541862Y1263407D01*
G01X1536804Y1256781D02*
X1536549Y1257175D01*
G01X1528700Y1252444D02*
X1528874Y1252188D01*
G01X1526174Y1250823D02*
X1525999Y1251079D01*
G01X1532086Y1261746D02*
X1531903Y1262010D01*
X1531839Y1262309D01*
X1531904Y1262606D01*
G01X1544257Y1263407D02*
X1544580Y1262987D01*
X1544742Y1262504D01*
X1544721Y1261999D01*
X1544518Y1261522D01*
X1544151Y1261119D01*
X1543645Y1260852D01*
X1543054Y1260758D01*
X1542464Y1260855D01*
X1541962Y1261124D01*
X1541598Y1261528D01*
X1541397Y1262006D01*
X1541377Y1262510D01*
X1541541Y1262992D01*
X1541862Y1263407D01*
G01X1539090D02*
X1539413Y1262987D01*
X1539575Y1262504D01*
X1539553Y1261999D01*
X1539350Y1261522D01*
X1538984Y1261119D01*
X1538477Y1260852D01*
X1537886Y1260758D01*
X1537297Y1260855D01*
X1536795Y1261124D01*
X1536431Y1261528D01*
X1536229Y1262006D01*
X1536210Y1262510D01*
X1536374Y1262992D01*
X1536694Y1263407D01*
G01X1529223Y1252615D02*
X1528874Y1252956D01*
G01X1525651Y1250653D02*
X1525999Y1250312D01*
G01X1541862Y1263407D02*
X1541410Y1263847D01*
X1541140Y1264383D01*
X1541070Y1264953D01*
X1541211Y1265517D01*
X1541558Y1266042D01*
X1542085Y1266435D01*
X1542728Y1266638D01*
X1543407Y1266636D01*
X1544047Y1266428D01*
X1544570Y1266032D01*
X1544912Y1265508D01*
X1545050Y1264947D01*
X1544978Y1264379D01*
X1544708Y1263845D01*
G01X1536694Y1263407D02*
X1536243Y1263847D01*
X1535973Y1264383D01*
X1535902Y1264953D01*
X1536044Y1265517D01*
X1536391Y1266042D01*
X1536918Y1266435D01*
X1537561Y1266638D01*
X1538240Y1266636D01*
X1538880Y1266428D01*
X1539403Y1266032D01*
X1539744Y1265508D01*
X1539882Y1264947D01*
X1539811Y1264379D01*
X1539540Y1263845D01*
G01X1533143Y1264941D02*
X1531514Y1263395D01*
G01X1539090Y1263407D02*
X1539542Y1263847D01*
X1539812Y1264383D01*
X1539882Y1264953D01*
X1539740Y1265517D01*
X1539394Y1266042D01*
X1538866Y1266435D01*
X1538224Y1266638D01*
X1537544Y1266636D01*
X1536904Y1266428D01*
X1536381Y1266032D01*
X1536040Y1265508D01*
X1535902Y1264947D01*
X1535974Y1264379D01*
X1536244Y1263845D01*
G01X1533648Y1264397D02*
X1532086Y1262870D01*
G01X1528874Y1251165D02*
X1528700Y1250994D01*
G01X1527132Y1250312D02*
X1527480Y1250653D01*
G01X1527829Y1252956D02*
X1527480Y1252615D01*
G01X1525999Y1252444D02*
X1526261Y1252700D01*
G01X1541862Y1263407D02*
X1541539Y1262987D01*
X1541376Y1262504D01*
X1541398Y1261999D01*
X1541601Y1261522D01*
X1541968Y1261119D01*
X1542474Y1260852D01*
X1543065Y1260758D01*
X1543654Y1260855D01*
X1544157Y1261124D01*
X1544521Y1261528D01*
X1544722Y1262006D01*
X1544741Y1262510D01*
X1544578Y1262992D01*
X1544257Y1263407D01*
G01X1536694D02*
X1536372Y1262987D01*
X1536209Y1262504D01*
X1536231Y1261999D01*
X1536434Y1261522D01*
X1536801Y1261119D01*
X1537307Y1260852D01*
X1537898Y1260758D01*
X1538487Y1260855D01*
X1538989Y1261124D01*
X1539354Y1261528D01*
X1539555Y1262006D01*
X1539574Y1262510D01*
X1539410Y1262992D01*
X1539090Y1263407D01*
G01X1529136Y1250738D02*
X1529397Y1251079D01*
G01X1531514Y1263395D02*
X1531177Y1262933D01*
X1531031Y1262415D01*
X1531092Y1261897D01*
X1531343Y1261413D01*
X1531779Y1261018D01*
X1532352Y1260795D01*
X1532987Y1260776D01*
X1533571Y1260962D01*
X1534026Y1261315D01*
X1534319Y1261787D01*
X1534423Y1262308D01*
G01X1533354Y1261736D02*
X1533544Y1262004D01*
G01X1532086Y1262870D02*
X1531903Y1262604D01*
X1531839Y1262307D01*
X1531904Y1262009D01*
G01X1527132Y1251079D02*
X1526958Y1250823D01*
G01X1527829Y1252188D02*
X1528003Y1252444D01*
G01X1525738Y1252956D02*
X1525477Y1252529D01*
G01X1525390Y1251421D02*
X1525477Y1250994D01*
G01X1529484Y1251932D02*
X1529397Y1252274D01*
G01X1525999Y1251079D02*
X1525912Y1251421D01*
G01X1528874Y1252188D02*
X1528961Y1251932D01*
G01X1529397Y1252274D02*
X1529223Y1252615D01*
G01X1525477Y1250994D02*
X1525651Y1250653D01*
G01X1527480D02*
X1527655Y1250994D01*
G01X1527480Y1252615D02*
X1527306Y1252274D01*
G01X1528961Y1251421D02*
X1528874Y1251165D01*
G01X1527742Y1251932D02*
X1527829Y1252188D01*
G01X1527219Y1251421D02*
X1527132Y1251079D01*
G01X1527306Y1252274D02*
X1527219Y1251932D01*
G01X1525912Y1252103D02*
X1525999Y1252444D01*
G01X1533543Y1262003D02*
X1533611Y1262308D01*
G01X1529397Y1251079D02*
X1529484Y1251506D01*
G01X1527655Y1250994D02*
X1527742Y1251421D01*
G01X1525477Y1252529D02*
X1525390Y1252103D01*
G01X1534423Y1262308D02*
X1534336Y1261831D01*
X1534088Y1261389D01*
X1533700Y1261037D01*
X1533193Y1260817D01*
X1532616Y1260761D01*
X1532052Y1260883D01*
X1531576Y1261166D01*
X1531237Y1261570D01*
X1531057Y1262027D01*
X1531042Y1262507D01*
X1531199Y1262978D01*
X1531514Y1263395D01*
G01X1551709Y1254203D02*
Y1267884D01*
G01X1551391Y1254203D02*
Y1259537D01*
G01X1550916Y1254203D02*
Y1256781D01*
G01X1550072Y1260758D02*
Y1261496D01*
G01X1549937Y1214990D02*
Y1214203D01*
G01Y1218140D02*
Y1217352D01*
G01Y1224439D02*
Y1223651D01*
G01Y1221289D02*
Y1220502D01*
G01Y1227588D02*
Y1226801D01*
G01Y1233888D02*
Y1233100D01*
G01Y1230738D02*
Y1229951D01*
G01Y1237037D02*
Y1236250D01*
G01Y1243337D02*
Y1242549D01*
G01Y1240187D02*
Y1239400D01*
G01Y1246486D02*
Y1245699D01*
G01Y1249636D02*
Y1248848D01*
G01X1548163Y1214990D02*
Y1214203D01*
G01Y1218140D02*
Y1217352D01*
G01Y1224439D02*
Y1223651D01*
G01Y1221289D02*
Y1220502D01*
G01Y1227588D02*
Y1226801D01*
G01Y1233888D02*
Y1233100D01*
G01Y1230738D02*
Y1229951D01*
G01Y1237037D02*
Y1236250D01*
G01Y1243337D02*
Y1242549D01*
G01Y1240187D02*
Y1239400D01*
G01Y1246486D02*
Y1245699D01*
G01Y1249636D02*
Y1248848D01*
G01X1547975D02*
Y1249636D01*
G01Y1245699D02*
Y1246486D01*
G01Y1242549D02*
Y1243337D01*
G01Y1239400D02*
Y1240187D01*
G01Y1236250D02*
Y1237037D01*
G01Y1233100D02*
Y1233888D01*
G01Y1229951D02*
Y1230738D01*
G01Y1226801D02*
Y1227588D01*
G01Y1223651D02*
Y1224439D01*
G01Y1220502D02*
Y1221289D01*
G01Y1217352D02*
Y1218140D01*
G01Y1214203D02*
Y1214990D01*
G01X1546234Y1261422D02*
Y1260758D01*
G01X1545138Y1248848D02*
Y1249636D01*
G01Y1245699D02*
Y1246486D01*
G01Y1242549D02*
Y1243337D01*
G01Y1239400D02*
Y1240187D01*
G01Y1236250D02*
Y1237037D01*
G01Y1233100D02*
Y1233888D01*
G01Y1229951D02*
Y1230738D01*
G01Y1226801D02*
Y1227588D01*
G01Y1223651D02*
Y1224439D01*
G01Y1220502D02*
Y1221289D01*
G01Y1217352D02*
Y1218140D01*
G01Y1214203D02*
Y1214990D01*
G01X1545062Y1259537D02*
Y1256781D01*
G01X1544197Y1214990D02*
Y1214203D01*
G01Y1218140D02*
Y1217352D01*
G01Y1224439D02*
Y1223651D01*
G01Y1221289D02*
Y1220502D01*
G01Y1227588D02*
Y1226801D01*
G01Y1233888D02*
Y1233100D01*
G01Y1230738D02*
Y1229951D01*
G01Y1237037D02*
Y1236250D01*
G01Y1243337D02*
Y1242549D01*
G01Y1240187D02*
Y1239400D01*
G01Y1246486D02*
Y1245699D01*
G01Y1249636D02*
Y1248848D01*
G01X1542605Y1214990D02*
Y1214203D01*
G01Y1218140D02*
Y1217352D01*
G01Y1224439D02*
Y1223651D01*
G01Y1221289D02*
Y1220502D01*
G01Y1227588D02*
Y1226801D01*
G01Y1233888D02*
Y1233100D01*
G01Y1230738D02*
Y1229951D01*
G01Y1237037D02*
Y1236250D01*
G01Y1243337D02*
Y1242549D01*
G01Y1240187D02*
Y1239400D01*
G01Y1246486D02*
Y1245699D01*
G01Y1249636D02*
Y1248848D01*
G01X1542457Y1214990D02*
Y1214203D01*
G01Y1218140D02*
Y1217352D01*
G01Y1224439D02*
Y1223651D01*
G01Y1221289D02*
Y1220502D01*
G01Y1227588D02*
Y1226801D01*
G01Y1233888D02*
Y1233100D01*
G01Y1230738D02*
Y1229951D01*
G01Y1237037D02*
Y1236250D01*
G01Y1243337D02*
Y1242549D01*
G01Y1240187D02*
Y1239400D01*
G01Y1246486D02*
Y1245699D01*
G01Y1249636D02*
Y1248848D01*
G01X1541519Y1246486D02*
Y1248848D01*
G01Y1249636D02*
Y1252214D01*
G01Y1243337D02*
Y1245699D01*
G01Y1240187D02*
Y1242549D01*
G01Y1237037D02*
Y1239400D01*
G01Y1233888D02*
Y1236250D01*
G01Y1230738D02*
Y1233100D01*
G01Y1227588D02*
Y1229951D01*
G01Y1224439D02*
Y1226801D01*
G01Y1221289D02*
Y1223651D01*
G01Y1218140D02*
Y1220502D01*
G01Y1214990D02*
Y1217352D01*
G01X1540075Y1249793D02*
Y1251762D01*
G01X1539791Y1214990D02*
Y1214203D01*
G01Y1218140D02*
Y1217352D01*
G01Y1224439D02*
Y1223651D01*
G01Y1221289D02*
Y1220502D01*
G01Y1227588D02*
Y1226801D01*
G01Y1233888D02*
Y1233100D01*
G01Y1230738D02*
Y1229951D01*
G01Y1237037D02*
Y1236250D01*
G01Y1243337D02*
Y1242549D01*
G01Y1240187D02*
Y1239400D01*
G01Y1246486D02*
Y1245699D01*
G01Y1249636D02*
Y1248848D01*
G01X1539110Y1250010D02*
Y1251585D01*
G01Y1245010D02*
Y1246585D01*
G01Y1240010D02*
Y1241585D01*
G01Y1235010D02*
Y1236585D01*
G01Y1230010D02*
Y1231585D01*
G01Y1225010D02*
Y1226585D01*
G01Y1220010D02*
Y1221585D01*
G01X1538244Y1280817D02*
Y1267884D01*
G01X1538139Y1248848D02*
Y1249636D01*
G01Y1245699D02*
Y1246486D01*
G01Y1242549D02*
Y1243337D01*
G01Y1239400D02*
Y1240187D01*
G01Y1236250D02*
Y1237037D01*
G01Y1233100D02*
Y1233888D01*
G01Y1229951D02*
Y1230738D01*
G01Y1226801D02*
Y1227588D01*
G01Y1223651D02*
Y1224439D01*
G01Y1220502D02*
Y1221289D01*
G01Y1217352D02*
Y1218140D01*
G01Y1214203D02*
Y1214990D01*
G01X1537984Y1217943D02*
Y1214124D01*
G01X1537576Y1215581D02*
Y1216762D01*
G01X1537188Y1259537D02*
Y1256781D01*
G01X1536549Y1257175D02*
Y1257234D01*
G01X1536156Y1248848D02*
Y1249636D01*
G01Y1245699D02*
Y1246486D01*
G01Y1242549D02*
Y1243337D01*
G01Y1239400D02*
Y1240187D01*
G01Y1236250D02*
Y1237037D01*
G01Y1233100D02*
Y1233888D01*
G01Y1229951D02*
Y1230738D01*
G01Y1226801D02*
Y1227588D01*
G01Y1223651D02*
Y1224439D01*
G01Y1220502D02*
Y1221289D01*
G01Y1217352D02*
Y1218140D01*
G01Y1214203D02*
Y1214990D01*
G01X1535961Y1221585D02*
Y1220010D01*
G01Y1226585D02*
Y1225010D01*
G01Y1231585D02*
Y1230010D01*
G01Y1236585D02*
Y1235010D01*
G01Y1241585D02*
Y1240010D01*
G01Y1246585D02*
Y1245010D01*
G01Y1251585D02*
Y1250010D01*
G01X1534976Y1222372D02*
Y1219222D01*
G01Y1227372D02*
Y1224222D01*
G01Y1232372D02*
Y1229222D01*
G01Y1237372D02*
Y1234222D01*
G01Y1242372D02*
Y1239222D01*
G01Y1247372D02*
Y1244222D01*
G01Y1252372D02*
Y1249222D01*
G01X1534718Y1266220D02*
Y1266663D01*
G01X1534427Y1216762D02*
Y1215581D01*
G01X1534423Y1262308D02*
Y1262456D01*
G01X1533992Y1257234D02*
Y1259537D01*
G01Y1222372D02*
Y1219222D01*
G01Y1227372D02*
Y1224222D01*
G01Y1232372D02*
Y1229222D01*
G01Y1237372D02*
Y1234222D01*
G01Y1242372D02*
Y1239222D01*
G01Y1247372D02*
Y1244222D01*
G01Y1252372D02*
Y1249222D01*
G01X1533611Y1262456D02*
Y1262308D01*
G01X1533008Y1221585D02*
Y1220010D01*
G01Y1226585D02*
Y1225010D01*
G01Y1231585D02*
Y1230010D01*
G01Y1236585D02*
Y1235010D01*
G01Y1241585D02*
Y1240010D01*
G01Y1246585D02*
Y1245010D01*
G01Y1251585D02*
Y1250010D01*
G01X1532846Y1274124D02*
Y1275699D01*
G01X1532811D02*
Y1274124D01*
G01X1532793Y1214990D02*
Y1214203D01*
G01Y1218140D02*
Y1217352D01*
G01Y1224439D02*
Y1223651D01*
G01Y1221289D02*
Y1220502D01*
G01Y1227588D02*
Y1226801D01*
G01Y1233888D02*
Y1233100D01*
G01Y1230738D02*
Y1229951D01*
G01Y1237037D02*
Y1236250D01*
G01Y1243337D02*
Y1242549D01*
G01Y1240187D02*
Y1239400D01*
G01Y1246486D02*
Y1245699D01*
G01Y1249636D02*
Y1248848D01*
G01X1532787Y1275699D02*
Y1274124D01*
G01X1532458Y1217352D02*
Y1214990D01*
G01X1532417D02*
Y1214203D01*
G01Y1218140D02*
Y1217352D01*
G01Y1224439D02*
Y1223651D01*
G01Y1221289D02*
Y1220502D01*
G01Y1227588D02*
Y1226801D01*
G01Y1233888D02*
Y1233100D01*
G01Y1230738D02*
Y1229951D01*
G01Y1237037D02*
Y1236250D01*
G01Y1243337D02*
Y1242549D01*
G01Y1240187D02*
Y1239400D01*
G01Y1246486D02*
Y1245699D01*
G01Y1249636D02*
Y1248848D01*
G01X1532391Y1214990D02*
Y1214203D01*
G01Y1218140D02*
Y1217352D01*
G01Y1224439D02*
Y1223651D01*
G01Y1221289D02*
Y1220502D01*
G01Y1227588D02*
Y1226801D01*
G01Y1233888D02*
Y1233100D01*
G01Y1230738D02*
Y1229951D01*
G01Y1237037D02*
Y1236250D01*
G01Y1243337D02*
Y1242549D01*
G01Y1240187D02*
Y1239400D01*
G01Y1246486D02*
Y1245699D01*
G01Y1249636D02*
Y1248848D01*
G01X1532004Y1251762D02*
Y1249793D01*
G01X1531464Y1274124D02*
Y1275699D01*
G01X1531094D02*
Y1274124D01*
G01X1530806Y1266663D02*
Y1265925D01*
G01X1529624Y1260758D02*
Y1261496D01*
G01X1529484Y1251506D02*
Y1251932D01*
G01Y1248947D02*
Y1248435D01*
G01X1529016Y1274124D02*
Y1275699D01*
G01X1528961Y1251932D02*
Y1251421D01*
G01X1528646Y1275699D02*
Y1274124D01*
G01X1528526Y1250909D02*
Y1250397D01*
G01X1528087Y1257726D02*
Y1260167D01*
G01Y1265915D02*
Y1262136D01*
G01X1527742Y1251421D02*
Y1251932D01*
G01X1527324Y1274124D02*
Y1275699D01*
G01X1527299Y1274124D02*
Y1275699D01*
G01X1527264D02*
Y1274124D01*
G01X1527219Y1251932D02*
Y1251421D01*
G01X1526522Y1252785D02*
Y1253297D01*
G01X1526433Y1238002D02*
Y1254419D01*
G01Y1220403D02*
Y1235640D01*
G01X1525912Y1251421D02*
Y1252103D01*
G01X1525786Y1261422D02*
Y1260758D01*
G01X1525390Y1248435D02*
Y1248947D01*
G01Y1252103D02*
Y1251421D01*
G01X1524149Y1267884D02*
Y1259537D01*
G01X1522181Y1255600D02*
Y1253829D01*
G01X1521866Y1254419D02*
Y1280817D01*
G01X1494474Y1309012D02*
X1596694Y1467443D01*
G01X1498077Y1317045D02*
X1587449Y1485164D01*
G01X1533205Y1292116D02*
G03Y1290935I0J-591D01*
G01X1526905D02*
G03Y1292116I0J591D01*
G01Y1293691D02*
G03Y1294872I0J591D01*
G01X1533205D02*
G03Y1293691I0J-590D01*
G01Y1295463D02*
X1526905D01*
G01X1531630Y1295167D02*
X1534779D01*
G01X1528480D02*
X1525331D01*
G01Y1293199D02*
X1528480D01*
G01X1534779D02*
X1531630D01*
G01X1525331Y1292608D02*
X1528480D01*
G01X1534779D02*
X1531630D01*
G01X1526916Y1291864D02*
X1527010D01*
G01Y1291116D02*
X1526916D01*
G01X1531630Y1290640D02*
X1534779D01*
G01X1528480D02*
X1525331D01*
G01X1526905Y1290344D02*
X1533205D01*
G01X1526916Y1291737D02*
X1526823Y1291625D01*
G01Y1291753D02*
X1526916Y1291864D01*
G01X1534779Y1290640D02*
Y1292608D01*
G01Y1295167D02*
Y1293199D01*
G01X1533205Y1292116D02*
Y1293691D01*
G01Y1290344D02*
Y1290935D01*
G01Y1294872D02*
Y1295463D01*
G01X1532220Y1290344D02*
Y1295463D01*
G01X1532024D02*
Y1290344D01*
G01X1531630Y1293199D02*
Y1295167D01*
G01Y1292608D02*
Y1290640D01*
G01X1528480Y1293199D02*
Y1295167D01*
G01Y1292608D02*
Y1290640D01*
G01X1528087Y1295463D02*
Y1290344D01*
G01X1527890D02*
Y1295463D01*
G01X1527010Y1291864D02*
Y1291116D01*
G01X1526916D02*
Y1291737D01*
G01X1526905Y1290935D02*
Y1290344D01*
G01Y1293691D02*
Y1292116D01*
G01Y1295463D02*
Y1294872D01*
G01X1526823Y1291625D02*
Y1291753D01*
G01X1525331Y1290640D02*
Y1292608D01*
G01Y1295167D02*
Y1293199D01*
G01X1521866Y1501289D02*
X1538244D01*
G01Y1514222D02*
Y1501289D01*
G01X1521866Y1527687D02*
Y1501289D01*
G01X1503974Y1570108D02*
X1503846Y1570080D01*
X1503758Y1570008D01*
X1503727Y1569911D01*
G01X1509023Y1572470D02*
X1509050Y1572474D01*
X1509075Y1572485D01*
X1509099Y1572503D01*
X1509121Y1572528D01*
X1509138Y1572558D01*
X1509150Y1572592D01*
X1509158Y1572628D01*
X1509161Y1572667D01*
G01X1509023Y1569321D02*
X1509050Y1569325D01*
X1509075Y1569336D01*
X1509099Y1569354D01*
X1509121Y1569378D01*
X1509138Y1569408D01*
X1509150Y1569442D01*
X1509158Y1569479D01*
X1509161Y1569518D01*
G01X1509023Y1566171D02*
X1509050Y1566175D01*
X1509075Y1566186D01*
X1509099Y1566204D01*
X1509121Y1566229D01*
X1509138Y1566259D01*
X1509150Y1566292D01*
X1509158Y1566329D01*
X1509161Y1566368D01*
G01X1509023Y1563022D02*
X1509050Y1563025D01*
X1509075Y1563036D01*
X1509099Y1563054D01*
X1509121Y1563079D01*
X1509138Y1563109D01*
X1509150Y1563143D01*
X1509158Y1563179D01*
X1509161Y1563218D01*
G01X1509023Y1559872D02*
X1509050Y1559876D01*
X1509075Y1559887D01*
X1509099Y1559905D01*
X1509121Y1559930D01*
X1509138Y1559959D01*
X1509150Y1559993D01*
X1509158Y1560030D01*
X1509161Y1560069D01*
G01X1509023Y1556722D02*
X1509050Y1556726D01*
X1509075Y1556737D01*
X1509099Y1556755D01*
X1509121Y1556780D01*
X1509138Y1556810D01*
X1509150Y1556844D01*
X1509158Y1556880D01*
X1509161Y1556919D01*
G01X1509023Y1553573D02*
X1509050Y1553576D01*
X1509075Y1553588D01*
X1509099Y1553606D01*
X1509121Y1553630D01*
X1509138Y1553660D01*
X1509150Y1553694D01*
X1509158Y1553731D01*
X1509161Y1553770D01*
G01X1509023Y1550423D02*
X1509050Y1550427D01*
X1509075Y1550438D01*
X1509099Y1550456D01*
X1509121Y1550481D01*
X1509138Y1550510D01*
X1509150Y1550544D01*
X1509158Y1550581D01*
X1509161Y1550620D01*
G01X1509023Y1547274D02*
X1509050Y1547277D01*
X1509075Y1547288D01*
X1509099Y1547306D01*
X1509121Y1547331D01*
X1509138Y1547361D01*
X1509150Y1547395D01*
X1509158Y1547431D01*
X1509161Y1547470D01*
G01X1509023Y1544124D02*
X1509050Y1544128D01*
X1509075Y1544139D01*
X1509099Y1544157D01*
X1509121Y1544182D01*
X1509138Y1544211D01*
X1509150Y1544245D01*
X1509158Y1544282D01*
X1509161Y1544321D01*
G01X1509023Y1540974D02*
X1509050Y1540978D01*
X1509075Y1540989D01*
X1509099Y1541007D01*
X1509121Y1541032D01*
X1509138Y1541062D01*
X1509150Y1541096D01*
X1509158Y1541132D01*
X1509161Y1541171D01*
G01X1509023Y1537825D02*
X1509050Y1537828D01*
X1509075Y1537840D01*
X1509099Y1537858D01*
X1509121Y1537882D01*
X1509138Y1537912D01*
X1509150Y1537946D01*
X1509158Y1537983D01*
X1509161Y1538022D01*
G01X1509023Y1534675D02*
X1509050Y1534679D01*
X1509075Y1534690D01*
X1509099Y1534708D01*
X1509121Y1534733D01*
X1509138Y1534762D01*
X1509150Y1534796D01*
X1509158Y1534833D01*
X1509161Y1534872D01*
G01X1509023Y1531525D02*
X1509050Y1531529D01*
X1509075Y1531540D01*
X1509099Y1531558D01*
X1509121Y1531583D01*
X1509138Y1531613D01*
X1509150Y1531647D01*
X1509158Y1531683D01*
X1509161Y1531722D01*
G01X1503974Y1566959D02*
X1503846Y1566931D01*
X1503758Y1566858D01*
X1503727Y1566762D01*
G01X1503974Y1563809D02*
X1503846Y1563781D01*
X1503758Y1563708D01*
X1503727Y1563612D01*
G01X1503974Y1560659D02*
X1503846Y1560632D01*
X1503758Y1560559D01*
X1503727Y1560463D01*
G01X1503974Y1557510D02*
X1503846Y1557482D01*
X1503758Y1557409D01*
X1503727Y1557313D01*
G01X1503974Y1554360D02*
X1503846Y1554332D01*
X1503758Y1554260D01*
X1503727Y1554163D01*
G01X1503974Y1551211D02*
X1503846Y1551183D01*
X1503758Y1551110D01*
X1503727Y1551014D01*
G01X1503974Y1548061D02*
X1503846Y1548033D01*
X1503758Y1547960D01*
X1503727Y1547864D01*
G01X1503974Y1541762D02*
X1503846Y1541734D01*
X1503758Y1541661D01*
X1503727Y1541565D01*
G01X1503974Y1538612D02*
X1503846Y1538584D01*
X1503758Y1538511D01*
X1503727Y1538415D01*
G01X1503974Y1535463D02*
X1503846Y1535435D01*
X1503758Y1535362D01*
X1503727Y1535266D01*
G01X1503974Y1532313D02*
X1503846Y1532285D01*
X1503758Y1532212D01*
X1503727Y1532116D01*
G01X1503974Y1573258D02*
X1510058D01*
G01X1503727Y1573061D02*
X1510338D01*
G01Y1572667D02*
X1503727D01*
G01X1503974Y1572470D02*
X1510058D01*
G01X1509749Y1572096D02*
X1504004D01*
G01X1510176Y1571506D02*
X1503590D01*
G01Y1571112D02*
X1510176D01*
G01X1504004Y1570522D02*
X1509749D01*
G01X1503974Y1570108D02*
X1510058D01*
G01X1503727Y1569911D02*
X1510338D01*
G01Y1569518D02*
X1503727D01*
G01X1503974Y1569321D02*
X1510058D01*
G01X1509749Y1567096D02*
X1504004D01*
G01X1503974Y1566959D02*
X1510058D01*
G01X1503727Y1566762D02*
X1510338D01*
G01X1510176Y1566506D02*
X1503590D01*
G01X1501709Y1566466D02*
X1528401D01*
G01X1510338Y1566368D02*
X1503727D01*
G01X1503974Y1566171D02*
X1510058D01*
G01X1503590Y1566112D02*
X1510176D01*
G01X1504004Y1565522D02*
X1509749D01*
G01X1528401Y1564104D02*
X1501709D01*
G01X1503974Y1563809D02*
X1510058D01*
G01X1503727Y1563612D02*
X1510338D01*
G01Y1563218D02*
X1503727D01*
G01X1503974Y1563022D02*
X1510058D01*
G01X1509749Y1562096D02*
X1504004D01*
G01X1510176Y1561506D02*
X1503590D01*
G01Y1561112D02*
X1510176D01*
G01X1503974Y1560659D02*
X1510058D01*
G01X1504004Y1560522D02*
X1509749D01*
G01X1503727Y1560463D02*
X1510338D01*
G01Y1560069D02*
X1503727D01*
G01X1503974Y1559872D02*
X1510058D01*
G01X1503974Y1557510D02*
X1510058D01*
G01X1503727Y1557313D02*
X1510338D01*
G01X1509749Y1557096D02*
X1504004D01*
G01X1510338Y1556919D02*
X1503727D01*
G01X1503974Y1556722D02*
X1510058D01*
G01X1510176Y1556506D02*
X1503590D01*
G01Y1556112D02*
X1510176D01*
G01X1504004Y1555522D02*
X1509749D01*
G01X1503974Y1554360D02*
X1510058D01*
G01X1503727Y1554163D02*
X1510338D01*
G01Y1553770D02*
X1503727D01*
G01X1503974Y1553573D02*
X1510058D01*
G01X1509749Y1552096D02*
X1504004D01*
G01X1510176Y1551506D02*
X1503590D01*
G01X1503974Y1551211D02*
X1510058D01*
G01X1503590Y1551112D02*
X1510176D01*
G01X1503727Y1551014D02*
X1510338D01*
G01Y1550620D02*
X1503727D01*
G01X1504004Y1550522D02*
X1509749D01*
G01X1503974Y1550423D02*
X1510058D01*
G01X1503974Y1548061D02*
X1510058D01*
G01X1503727Y1547864D02*
X1510338D01*
G01X1501709Y1547569D02*
X1528401D01*
G01X1510338Y1547470D02*
X1503727D01*
G01X1503974Y1547274D02*
X1510058D01*
G01X1507781Y1547096D02*
X1502036D01*
G01X1508207Y1546506D02*
X1501621D01*
G01Y1546112D02*
X1508207D01*
G01X1502036Y1545522D02*
X1507781D01*
G01X1528401Y1545207D02*
X1501709D01*
G01X1503974Y1544911D02*
X1510058D01*
G01X1503727Y1544714D02*
X1510338D01*
G01Y1544321D02*
X1503727D01*
G01X1503974Y1544124D02*
X1510058D01*
G01X1509749Y1542096D02*
X1504004D01*
G01X1503974Y1541762D02*
X1510058D01*
G01X1503727Y1541565D02*
X1510338D01*
G01X1510176Y1541506D02*
X1503590D01*
G01X1510338Y1541171D02*
X1503727D01*
G01X1503590Y1541112D02*
X1510176D01*
G01X1503974Y1540974D02*
X1510058D01*
G01X1504004Y1540522D02*
X1509749D01*
G01X1503974Y1538612D02*
X1510058D01*
G01X1503727Y1538415D02*
X1510338D01*
G01Y1538022D02*
X1503727D01*
G01X1503974Y1537825D02*
X1510058D01*
G01X1509749Y1537096D02*
X1504004D01*
G01X1510176Y1536506D02*
X1503590D01*
G01Y1536112D02*
X1510176D01*
G01X1504004Y1535522D02*
X1509749D01*
G01X1503974Y1535463D02*
X1510058D01*
G01X1503727Y1535266D02*
X1510338D01*
G01Y1534872D02*
X1503727D01*
G01X1503974Y1534675D02*
X1510058D01*
G01X1503974Y1532313D02*
X1510058D01*
G01X1503727Y1532116D02*
X1510338D01*
G01X1509749Y1532096D02*
X1504004D01*
G01X1510338Y1531722D02*
X1503727D01*
G01X1503974Y1531525D02*
X1510058D01*
G01X1510176Y1531506D02*
X1503590D01*
G01Y1531112D02*
X1510176D01*
G01X1504004Y1530522D02*
X1509749D01*
G01X1501709Y1527490D02*
X1520212D01*
G01X1499740Y1527096D02*
X1530449D01*
G01X1501709Y1522569D02*
X1551709D01*
G01X1499740D02*
X1496457D01*
G01X1497772Y1515403D02*
X1524149D01*
G01X1551709Y1514222D02*
X1497772D01*
G01X1503974Y1572470D02*
X1503847Y1572498D01*
X1503758Y1572570D01*
X1503727Y1572667D01*
G01X1503974Y1544124D02*
X1503847Y1544151D01*
X1503758Y1544224D01*
X1503727Y1544321D01*
G01X1508572Y1573258D02*
X1508610Y1573231D01*
X1508638Y1573159D01*
X1508648Y1573061D01*
G01X1508572Y1570108D02*
X1508610Y1570082D01*
X1508638Y1570010D01*
X1508648Y1569911D01*
G01X1508572Y1566959D02*
X1508610Y1566932D01*
X1508638Y1566860D01*
X1508648Y1566762D01*
G01X1508572Y1563809D02*
X1508610Y1563783D01*
X1508638Y1563710D01*
X1508648Y1563612D01*
G01X1508572Y1560659D02*
X1508610Y1560633D01*
X1508638Y1560561D01*
X1508648Y1560463D01*
G01X1508572Y1557510D02*
X1508610Y1557483D01*
X1508638Y1557411D01*
X1508648Y1557313D01*
G01X1508572Y1554360D02*
X1508610Y1554334D01*
X1508638Y1554262D01*
X1508648Y1554163D01*
G01X1508572Y1551211D02*
X1508610Y1551184D01*
X1508638Y1551112D01*
X1508648Y1551014D01*
G01X1508572Y1548061D02*
X1508610Y1548035D01*
X1508638Y1547962D01*
X1508648Y1547864D01*
G01X1508572Y1544911D02*
X1508610Y1544885D01*
X1508638Y1544813D01*
X1508648Y1544714D01*
G01X1508572Y1541762D02*
X1508610Y1541735D01*
X1508638Y1541663D01*
X1508648Y1541565D01*
G01X1508572Y1538612D02*
X1508610Y1538586D01*
X1508638Y1538514D01*
X1508648Y1538415D01*
G01X1508572Y1535463D02*
X1508610Y1535436D01*
X1508638Y1535364D01*
X1508648Y1535266D01*
G01X1508572Y1532313D02*
X1508610Y1532286D01*
X1508638Y1532214D01*
X1508648Y1532116D01*
G01X1503590Y1576112D02*
X1503727Y1575914D01*
X1503865Y1575718D01*
X1504004Y1575522D01*
G01X1503590Y1571112D02*
X1503727Y1570914D01*
X1503865Y1570718D01*
X1504004Y1570522D01*
G01X1503590Y1566112D02*
X1503727Y1565914D01*
X1503865Y1565718D01*
X1504004Y1565522D01*
G01X1503590Y1561112D02*
X1503727Y1560914D01*
X1503865Y1560718D01*
X1504004Y1560522D01*
G01X1503590Y1556112D02*
X1503727Y1555914D01*
X1503865Y1555718D01*
X1504004Y1555522D01*
G01X1503590Y1551112D02*
X1503727Y1550914D01*
X1503865Y1550718D01*
X1504004Y1550522D01*
G01X1509749Y1572096D02*
X1510176Y1571506D01*
G01X1509749Y1567096D02*
X1510176Y1566506D01*
G01X1509749Y1562096D02*
X1510176Y1561506D01*
G01X1509749Y1557096D02*
X1510176Y1556506D01*
G01X1509749Y1552096D02*
X1510176Y1551506D01*
G01X1507781Y1547096D02*
X1508207Y1546506D01*
G01X1509749Y1542096D02*
X1510176Y1541506D01*
G01X1509749Y1537096D02*
X1510176Y1536506D01*
G01X1509749Y1532096D02*
X1510176Y1531506D01*
G01X1499740Y1524537D02*
X1501709Y1522569D01*
G01X1509060Y1572096D02*
X1509332Y1571506D01*
G01X1509060Y1567096D02*
X1509332Y1566506D01*
G01X1509060Y1562096D02*
X1509332Y1561506D01*
G01X1509060Y1557096D02*
X1509332Y1556506D01*
G01X1509060Y1552096D02*
X1509332Y1551506D01*
G01X1501621Y1546112D02*
X1501758Y1545914D01*
X1501896Y1545718D01*
X1502036Y1545522D01*
G01X1503590Y1541112D02*
X1503727Y1540914D01*
X1503865Y1540718D01*
X1504004Y1540522D01*
G01X1503590Y1536112D02*
X1503727Y1535914D01*
X1503865Y1535718D01*
X1504004Y1535522D01*
G01X1503590Y1531112D02*
X1503727Y1530914D01*
X1503865Y1530718D01*
X1504004Y1530522D01*
G01X1503727Y1569518D02*
X1503758Y1569421D01*
X1503847Y1569348D01*
X1503974Y1569321D01*
G01X1503727Y1566368D02*
X1503758Y1566271D01*
X1503847Y1566199D01*
X1503974Y1566171D01*
G01X1503727Y1563218D02*
X1503758Y1563121D01*
X1503847Y1563049D01*
X1503974Y1563022D01*
G01X1503727Y1560069D02*
X1503758Y1559972D01*
X1503847Y1559900D01*
X1503974Y1559872D01*
G01X1503727Y1556919D02*
X1503758Y1556822D01*
X1503847Y1556750D01*
X1503974Y1556722D01*
G01X1503727Y1553770D02*
X1503758Y1553673D01*
X1503847Y1553600D01*
X1503974Y1553573D01*
G01X1503727Y1550620D02*
X1503758Y1550523D01*
X1503847Y1550451D01*
X1503974Y1550423D01*
G01X1503727Y1547470D02*
X1503758Y1547373D01*
X1503847Y1547301D01*
X1503974Y1547274D01*
G01X1503727Y1541171D02*
X1503758Y1541074D01*
X1503847Y1541002D01*
X1503974Y1540974D01*
G01X1503727Y1538022D02*
X1503758Y1537925D01*
X1503847Y1537852D01*
X1503974Y1537825D01*
G01X1503727Y1534872D02*
X1503758Y1534775D01*
X1503847Y1534703D01*
X1503974Y1534675D01*
G01X1503727Y1531722D02*
X1503758Y1531625D01*
X1503847Y1531553D01*
X1503974Y1531525D01*
G01X1497740Y1514253D02*
X1497682Y1514393D01*
X1497677Y1514633D01*
G01X1507091Y1547096D02*
X1507364Y1546506D01*
G01X1509060Y1542096D02*
X1509332Y1541506D01*
G01X1509060Y1537096D02*
X1509332Y1536506D01*
G01X1509060Y1532096D02*
X1509332Y1531506D01*
G01X1508208Y1571506D02*
X1508130Y1572096D01*
G01X1508208Y1566506D02*
X1508130Y1567096D01*
G01X1508208Y1561506D02*
X1508130Y1562096D01*
G01X1508208Y1556506D02*
X1508130Y1557096D01*
G01X1508208Y1551506D02*
X1508130Y1552096D01*
G01X1508208Y1541506D02*
X1508130Y1542096D01*
G01Y1537096D02*
X1508208Y1536506D01*
G01X1506239Y1546506D02*
X1506161Y1547096D01*
G01X1508208Y1531506D02*
X1508130Y1532096D01*
G01X1509161Y1573061D02*
X1509158Y1573099D01*
X1509151Y1573136D01*
X1509138Y1573170D01*
X1509121Y1573200D01*
X1509100Y1573225D01*
X1509076Y1573243D01*
X1509050Y1573254D01*
X1509023Y1573258D01*
G01X1509161Y1569911D02*
X1509158Y1569950D01*
X1509151Y1569986D01*
X1509138Y1570020D01*
X1509121Y1570051D01*
X1509100Y1570075D01*
X1509076Y1570093D01*
X1509050Y1570104D01*
X1509023Y1570108D01*
G01X1509161Y1566762D02*
X1509158Y1566800D01*
X1509151Y1566837D01*
X1509138Y1566871D01*
X1509121Y1566901D01*
X1509100Y1566925D01*
X1509076Y1566943D01*
X1509050Y1566955D01*
X1509023Y1566959D01*
G01X1509161Y1563612D02*
X1509158Y1563650D01*
X1509151Y1563687D01*
X1509138Y1563721D01*
X1509121Y1563751D01*
X1509100Y1563776D01*
X1509076Y1563794D01*
X1509050Y1563805D01*
X1509023Y1563809D01*
G01X1509161Y1560463D02*
X1509158Y1560501D01*
X1509151Y1560538D01*
X1509138Y1560571D01*
X1509121Y1560602D01*
X1509100Y1560626D01*
X1509076Y1560644D01*
X1509050Y1560655D01*
X1509023Y1560659D01*
G01X1509161Y1557313D02*
X1509158Y1557351D01*
X1509151Y1557388D01*
X1509138Y1557422D01*
X1509121Y1557452D01*
X1509100Y1557476D01*
X1509076Y1557495D01*
X1509050Y1557506D01*
X1509023Y1557510D01*
G01X1509161Y1554163D02*
X1509158Y1554202D01*
X1509151Y1554238D01*
X1509138Y1554272D01*
X1509121Y1554302D01*
X1509100Y1554327D01*
X1509076Y1554345D01*
X1509050Y1554356D01*
X1509023Y1554360D01*
G01X1509161Y1551014D02*
X1509158Y1551052D01*
X1509151Y1551089D01*
X1509138Y1551123D01*
X1509121Y1551153D01*
X1509100Y1551177D01*
X1509076Y1551195D01*
X1509050Y1551207D01*
X1509023Y1551211D01*
G01X1509161Y1547864D02*
X1509158Y1547902D01*
X1509151Y1547939D01*
X1509138Y1547973D01*
X1509121Y1548003D01*
X1509100Y1548028D01*
X1509076Y1548046D01*
X1509050Y1548057D01*
X1509023Y1548061D01*
G01X1509161Y1544714D02*
X1509158Y1544753D01*
X1509151Y1544789D01*
X1509138Y1544823D01*
X1509121Y1544854D01*
X1509100Y1544878D01*
X1509076Y1544896D01*
X1509050Y1544907D01*
X1509023Y1544911D01*
G01X1509161Y1541565D02*
X1509158Y1541603D01*
X1509151Y1541640D01*
X1509138Y1541674D01*
X1509121Y1541704D01*
X1509100Y1541728D01*
X1509076Y1541747D01*
X1509050Y1541758D01*
X1509023Y1541762D01*
G01X1509161Y1538415D02*
X1509158Y1538453D01*
X1509151Y1538490D01*
X1509138Y1538524D01*
X1509121Y1538554D01*
X1509100Y1538579D01*
X1509076Y1538597D01*
X1509050Y1538608D01*
X1509023Y1538612D01*
G01X1509161Y1535266D02*
X1509158Y1535304D01*
X1509151Y1535341D01*
X1509138Y1535375D01*
X1509121Y1535405D01*
X1509100Y1535429D01*
X1509076Y1535447D01*
X1509050Y1535459D01*
X1509023Y1535463D01*
G01X1509161Y1532116D02*
X1509158Y1532154D01*
X1509151Y1532191D01*
X1509138Y1532225D01*
X1509121Y1532255D01*
X1509100Y1532280D01*
X1509076Y1532298D01*
X1509050Y1532309D01*
X1509023Y1532313D01*
G01X1501709Y1527490D02*
X1499740Y1525522D01*
G01X1509749Y1530522D02*
X1510176Y1531112D01*
G01X1509332D02*
X1509060Y1530522D01*
G01X1497714Y1514952D02*
X1497767Y1515330D01*
G01X1508208Y1531112D02*
X1508130Y1530522D01*
G01Y1535522D02*
X1508208Y1536112D01*
G01Y1541112D02*
X1508130Y1540522D01*
G01X1508208Y1551112D02*
X1508130Y1550522D01*
G01X1508208Y1556112D02*
X1508130Y1555522D01*
G01X1506239Y1546112D02*
X1506161Y1545522D01*
G01X1508208Y1561112D02*
X1508130Y1560522D01*
G01X1508208Y1566112D02*
X1508130Y1565522D01*
G01X1508208Y1571112D02*
X1508130Y1570522D01*
G01X1497714Y1514954D02*
X1497677Y1514630D01*
X1497683Y1514389D01*
X1497740Y1514253D01*
G01X1508648Y1531722D02*
X1508638Y1531624D01*
X1508610Y1531552D01*
X1508572Y1531525D01*
G01X1508648Y1534872D02*
X1508638Y1534774D01*
X1508610Y1534702D01*
X1508572Y1534675D01*
G01X1508648Y1538022D02*
X1508638Y1537923D01*
X1508610Y1537851D01*
X1508572Y1537825D01*
G01X1508648Y1541171D02*
X1508638Y1541073D01*
X1508610Y1541001D01*
X1508572Y1540974D01*
G01X1508648Y1544321D02*
X1508638Y1544222D01*
X1508610Y1544150D01*
X1508572Y1544124D01*
G01X1508648Y1547470D02*
X1508638Y1547372D01*
X1508610Y1547300D01*
X1508572Y1547274D01*
G01X1508648Y1550620D02*
X1508638Y1550522D01*
X1508610Y1550450D01*
X1508572Y1550423D01*
G01X1508648Y1553770D02*
X1508638Y1553671D01*
X1508610Y1553599D01*
X1508572Y1553573D01*
G01X1508648Y1556919D02*
X1508638Y1556821D01*
X1508610Y1556749D01*
X1508572Y1556722D01*
G01X1508648Y1560069D02*
X1508638Y1559970D01*
X1508610Y1559898D01*
X1508572Y1559872D01*
G01X1508648Y1563218D02*
X1508638Y1563120D01*
X1508610Y1563048D01*
X1508572Y1563022D01*
G01X1508648Y1566368D02*
X1508638Y1566270D01*
X1508610Y1566198D01*
X1508572Y1566171D01*
G01X1508648Y1569518D02*
X1508638Y1569419D01*
X1508610Y1569347D01*
X1508572Y1569321D01*
G01X1508648Y1572667D02*
X1508638Y1572569D01*
X1508610Y1572497D01*
X1508572Y1572470D01*
G01X1510338Y1572667D02*
Y1573061D01*
G01Y1569518D02*
Y1569911D01*
G01Y1563218D02*
Y1563612D01*
G01Y1566368D02*
Y1566762D01*
G01Y1560069D02*
Y1560463D01*
G01Y1553770D02*
Y1554163D01*
G01Y1556919D02*
Y1557313D01*
G01Y1550620D02*
Y1551014D01*
G01Y1547470D02*
Y1547864D01*
G01Y1544321D02*
Y1544714D01*
G01Y1541171D02*
Y1541565D01*
G01Y1534872D02*
Y1535266D01*
G01Y1538022D02*
Y1538415D01*
G01Y1531722D02*
Y1532116D01*
G01X1510176Y1531506D02*
Y1531112D01*
G01Y1536506D02*
Y1536112D01*
G01Y1541506D02*
Y1541112D01*
G01Y1551506D02*
Y1551112D01*
G01Y1556506D02*
Y1556112D01*
G01Y1561506D02*
Y1561112D01*
G01Y1566506D02*
Y1566112D01*
G01Y1571506D02*
Y1571112D01*
G01X1509332Y1531506D02*
Y1531112D01*
G01Y1536506D02*
Y1536112D01*
G01Y1541506D02*
Y1541112D01*
G01Y1551506D02*
Y1551112D01*
G01Y1556506D02*
Y1556112D01*
G01Y1561506D02*
Y1561112D01*
G01Y1566506D02*
Y1566112D01*
G01Y1571506D02*
Y1571112D01*
G01X1509161Y1572667D02*
Y1573061D01*
G01Y1569518D02*
Y1569911D01*
G01Y1563218D02*
Y1563612D01*
G01Y1566368D02*
Y1566762D01*
G01Y1560069D02*
Y1560463D01*
G01Y1553770D02*
Y1554163D01*
G01Y1556919D02*
Y1557313D01*
G01Y1550620D02*
Y1551014D01*
G01Y1547470D02*
Y1547864D01*
G01Y1544321D02*
Y1544714D01*
G01Y1541171D02*
Y1541565D01*
G01Y1534872D02*
Y1535266D01*
G01Y1538022D02*
Y1538415D01*
G01Y1531722D02*
Y1532116D01*
G01X1508648D02*
Y1531722D01*
G01Y1535266D02*
Y1534872D01*
G01Y1538415D02*
Y1538022D01*
G01Y1541565D02*
Y1541171D01*
G01Y1547864D02*
Y1547470D01*
G01Y1544714D02*
Y1544321D01*
G01Y1551014D02*
Y1550620D01*
G01Y1554163D02*
Y1553770D01*
G01Y1557313D02*
Y1556919D01*
G01Y1560463D02*
Y1560069D01*
G01Y1563612D02*
Y1563218D01*
G01Y1566762D02*
Y1566368D01*
G01Y1569911D02*
Y1569518D01*
G01Y1573061D02*
Y1572667D01*
G01X1508208Y1571112D02*
Y1571506D01*
G01Y1566112D02*
Y1566506D01*
G01Y1561112D02*
Y1561506D01*
G01Y1556112D02*
Y1556506D01*
G01Y1551112D02*
Y1551506D01*
G01Y1541112D02*
Y1541506D01*
G01Y1531112D02*
Y1531506D01*
G01Y1536506D02*
Y1536112D01*
G01X1508207Y1546506D02*
Y1546112D01*
G01X1507364Y1546506D02*
Y1546112D01*
G01X1506239D02*
Y1546506D01*
G01X1503727Y1532116D02*
Y1531722D01*
G01Y1535266D02*
Y1534872D01*
G01Y1538415D02*
Y1538022D01*
G01Y1541565D02*
Y1541171D01*
G01Y1547864D02*
Y1547470D01*
G01Y1544714D02*
Y1544321D01*
G01Y1551014D02*
Y1550620D01*
G01Y1554163D02*
Y1553770D01*
G01Y1557313D02*
Y1556919D01*
G01Y1560463D02*
Y1560069D01*
G01Y1563612D02*
Y1563218D01*
G01Y1566762D02*
Y1566368D01*
G01Y1569911D02*
Y1569518D01*
G01Y1573061D02*
Y1572667D01*
G01X1503590Y1571112D02*
Y1571506D01*
G01Y1566112D02*
Y1566506D01*
G01Y1561112D02*
Y1561506D01*
G01Y1556112D02*
Y1556506D01*
G01Y1551112D02*
Y1551506D01*
G01Y1541112D02*
Y1541506D01*
G01Y1536112D02*
Y1536506D01*
G01Y1531112D02*
Y1531506D01*
G01X1501709Y1660128D02*
Y1527490D01*
G01X1501621Y1546112D02*
Y1546506D01*
G01X1500921Y1526703D02*
Y1597608D01*
G01X1500862Y1527096D02*
Y1660522D01*
G01X1499740Y1665049D02*
Y1522569D01*
G01X1497772D02*
Y1515403D01*
G01X1509749Y1535522D02*
X1510176Y1536112D01*
G01X1509749Y1540522D02*
X1510176Y1541112D01*
G01X1507781Y1545522D02*
X1508207Y1546112D01*
G01X1509749Y1550522D02*
X1510176Y1551112D01*
G01X1509749Y1555522D02*
X1510176Y1556112D01*
G01X1509749Y1560522D02*
X1510176Y1561112D01*
G01X1509749Y1565522D02*
X1510176Y1566112D01*
G01X1509749Y1570522D02*
X1510176Y1571112D01*
G01X1509749Y1575522D02*
X1510176Y1576112D01*
G01X1504004Y1532096D02*
X1503865Y1531900D01*
X1503727Y1531703D01*
X1503590Y1531506D01*
G01X1504004Y1537096D02*
X1503865Y1536900D01*
X1503727Y1536703D01*
X1503590Y1536506D01*
G01X1504004Y1542096D02*
X1503865Y1541900D01*
X1503727Y1541703D01*
X1503590Y1541506D01*
G01X1502036Y1547096D02*
X1501896Y1546900D01*
X1501758Y1546703D01*
X1501621Y1546506D01*
G01X1504004Y1552096D02*
X1503865Y1551900D01*
X1503727Y1551703D01*
X1503590Y1551506D01*
G01X1504004Y1557096D02*
X1503865Y1556900D01*
X1503727Y1556703D01*
X1503590Y1556506D01*
G01X1504004Y1562096D02*
X1503865Y1561900D01*
X1503727Y1561703D01*
X1503590Y1561506D01*
G01X1504004Y1567096D02*
X1503865Y1566900D01*
X1503727Y1566703D01*
X1503590Y1566506D01*
G01X1504004Y1572096D02*
X1503865Y1571900D01*
X1503727Y1571703D01*
X1503590Y1571506D01*
G01X1509332Y1536112D02*
X1509060Y1535522D01*
G01X1509332Y1541112D02*
X1509060Y1540522D01*
G01X1507364Y1546112D02*
X1507091Y1545522D01*
G01X1509332Y1551112D02*
X1509060Y1550522D01*
G01X1509332Y1556112D02*
X1509060Y1555522D01*
G01X1509332Y1561112D02*
X1509060Y1560522D01*
G01X1509332Y1566112D02*
X1509060Y1565522D01*
G01X1509332Y1571112D02*
X1509060Y1570522D01*
G01X1509332Y1576112D02*
X1509060Y1575522D01*
G01X1503727Y1544714D02*
X1503760Y1544813D01*
X1503848Y1544884D01*
X1503974Y1544911D01*
G01X1503727Y1573061D02*
X1503760Y1573160D01*
X1503848Y1573231D01*
X1503974Y1573258D01*
G01X1543875Y1518049D02*
G03X1542450I-713J83D01*
G01X1542889Y1515424D02*
G03X1544475Y1515711I263J3073D01*
G01X1543223Y1516415D02*
G03X1543814Y1516780I9J646D01*
G01X1542450Y1517223D02*
G03X1543223Y1516415I792J-16D01*
G01X1544475Y1515711D02*
G03X1545318Y1516780I-704J1422D01*
G01X1545109Y1518666D02*
G03X1543875Y1519640I-1735J-930D01*
G01X1542232Y1519596D02*
G03X1541068Y1518458I730J-1911D01*
G01X1541154Y1516442D02*
G03X1542893Y1515424I1807J1093D01*
G01X1543875Y1519639D02*
G03X1542232Y1519596I-757J-2475D01*
G01X1540894Y1517302D02*
G03X1541156Y1516439I2971J431D01*
G01X1545448Y1517223D02*
G03X1545109Y1518666I-3015J53D01*
G01X1540894Y1517797D02*
G03Y1517300I3524J-249D01*
G01X1541068Y1518458D02*
G03X1540894Y1517797I4018J-1411D01*
G01X1541472Y1519006D02*
G03I-2165J0D01*
G01X1541261Y1516289D02*
G03Y1521722I-1954J2717D01*
G01X1537353D02*
G03Y1516289I1954J-2716D01*
G01X1542811Y1519006D02*
G03I-3504J0D01*
G01X1537003Y1522903D02*
G03Y1515108I2304J-3898D01*
G01X1541611D02*
G03Y1522903I-2304J3898D01*
G01X1531945Y1570522D02*
G03X1531551Y1570128I0J-394D01*
G01Y1572490D02*
G03X1531945Y1572096I394J0D01*
G01Y1565522D02*
G03X1531551Y1565128I0J-394D01*
G01Y1567490D02*
G03X1531945Y1567096I394J0D01*
G01Y1560522D02*
G03X1531551Y1560128I0J-394D01*
G01Y1562490D02*
G03X1531945Y1562096I394J0D01*
G01Y1575522D02*
G03X1531551Y1575128I0J-394D01*
G01X1535250Y1516733D02*
G03X1536723I736J277D01*
G01Y1518418D02*
G03X1535250I-737J-278D01*
G01X1533978Y1516398D02*
G03X1534499Y1515833I1351J723D01*
G01X1537545Y1515835D02*
G03X1538065Y1516400I-832J1287D01*
G01Y1518712D02*
G03X1537544Y1519277I-1351J-723D01*
G01X1534498D02*
G03X1533977Y1518712I830J-1288D01*
G01X1535250Y1518418D02*
G03Y1516733I2236J-843D01*
G01X1533977Y1518712D02*
G03X1533978Y1516398I2163J-1156D01*
G01X1538065Y1516400D02*
G03Y1518712I-2163J1156D01*
G01X1534499Y1515833D02*
G03X1537545Y1515834I1522J2362D01*
G01X1537544Y1519278D02*
G03X1534498Y1519277I-1522J-2362D01*
G01X1531945Y1550522D02*
G03X1531551Y1550128I0J-394D01*
G01Y1552490D02*
G03X1531945Y1552096I394J0D01*
G01Y1555522D02*
G03X1531551Y1555128I0J-394D01*
G01Y1557490D02*
G03X1531945Y1557096I394J0D01*
G01Y1540522D02*
G03X1531551Y1540128I0J-394D01*
G01Y1542490D02*
G03X1531945Y1542096I394J0D01*
G01X1531551Y1537490D02*
G03X1531945Y1537096I394J0D01*
G01Y1530522D02*
G03X1531551Y1530128I0J-394D01*
G01Y1532490D02*
G03X1531945Y1532096I394J0D01*
G01Y1535522D02*
G03X1531551Y1535128I0J-394D01*
G01X1533043Y1518553D02*
G03X1532749Y1519224I-913J0D01*
G01X1536723Y1516733D02*
G03Y1518418I-2237J842D01*
G01X1528761Y1518149D02*
G03X1527330I-716J0D01*
G01X1531651D02*
G03X1530220I-716J0D01*
G01X1532749Y1519224D02*
G03X1530114Y1519080I-1248J-1351D01*
G01D02*
G03X1527333Y1519074I-1388J-1207D01*
G01X1532220Y1505620D02*
G03Y1508770I0J1575D01*
G01X1527890D02*
G03Y1505620I0J-1575D01*
G01X1534976Y1575325D02*
X1533992D01*
G01X1534976Y1574931D02*
X1533992D01*
G01X1534976Y1574734D02*
X1533992D01*
G01X1542605Y1573258D02*
X1549937D01*
G01X1542457D02*
X1530449D01*
G01X1534976Y1572884D02*
X1533992D01*
G01X1534976Y1572687D02*
X1533992D01*
G01X1542457Y1572470D02*
X1530449D01*
G01X1549937D02*
X1542605D01*
G01X1534976Y1572293D02*
X1533992D01*
G01X1531945Y1572096D02*
X1539110D01*
G01X1531945Y1570522D02*
X1539110D01*
G01X1534976Y1570325D02*
X1533992D01*
G01X1542605Y1570108D02*
X1549937D01*
G01X1542457D02*
X1530449D01*
G01X1534976Y1569931D02*
X1533992D01*
G01X1534976Y1569734D02*
X1533992D01*
G01X1542457Y1569321D02*
X1530449D01*
G01X1549937D02*
X1542605D01*
G01X1534976Y1567884D02*
X1533992D01*
G01X1534976Y1567687D02*
X1533992D01*
G01X1534976Y1567293D02*
X1533992D01*
G01X1531945Y1567096D02*
X1539110D01*
G01X1542605Y1566959D02*
X1549937D01*
G01X1542457D02*
X1530449D01*
G01X1542457Y1566171D02*
X1530449D01*
G01X1549937D02*
X1542605D01*
G01X1531945Y1565522D02*
X1539110D01*
G01X1534976Y1565325D02*
X1533992D01*
G01X1534976Y1564931D02*
X1533992D01*
G01X1534976Y1564734D02*
X1533992D01*
G01X1542605Y1563809D02*
X1549937D01*
G01X1542457D02*
X1530449D01*
G01X1542457Y1563022D02*
X1530449D01*
G01X1549937D02*
X1542605D01*
G01X1534976Y1562884D02*
X1533992D01*
G01X1534976Y1562687D02*
X1533992D01*
G01X1534976Y1562293D02*
X1533992D01*
G01X1531945Y1562096D02*
X1539110D01*
G01X1542605Y1560659D02*
X1549937D01*
G01X1542457D02*
X1530449D01*
G01X1531945Y1560522D02*
X1539110D01*
G01X1534976Y1560325D02*
X1533992D01*
G01X1534976Y1559931D02*
X1533992D01*
G01X1542457Y1559872D02*
X1530449D01*
G01X1549937D02*
X1542605D01*
G01X1534976Y1559734D02*
X1533992D01*
G01X1534976Y1557884D02*
X1533992D01*
G01X1534976Y1557687D02*
X1533992D01*
G01X1542605Y1557510D02*
X1549937D01*
G01X1542457D02*
X1530449D01*
G01X1534976Y1557293D02*
X1533992D01*
G01X1531945Y1557096D02*
X1539110D01*
G01X1542457Y1556722D02*
X1530449D01*
G01X1549937D02*
X1542605D01*
G01X1531945Y1555522D02*
X1539110D01*
G01X1534976Y1555325D02*
X1533992D01*
G01X1534976Y1554931D02*
X1533992D01*
G01X1534976Y1554734D02*
X1533992D01*
G01X1542605Y1554360D02*
X1549937D01*
G01X1542457D02*
X1530449D01*
G01X1542457Y1553573D02*
X1530449D01*
G01X1549937D02*
X1542605D01*
G01X1534976Y1552884D02*
X1533992D01*
G01X1534976Y1552687D02*
X1533992D01*
G01X1534976Y1552293D02*
X1533992D01*
G01X1531945Y1552096D02*
X1539110D01*
G01X1542605Y1551211D02*
X1549937D01*
G01X1542457D02*
X1530449D01*
G01X1531945Y1550522D02*
X1539110D01*
G01X1542457Y1550423D02*
X1530449D01*
G01X1549937D02*
X1542605D01*
G01X1534976Y1550325D02*
X1533992D01*
G01X1534976Y1549931D02*
X1533992D01*
G01X1534976Y1549734D02*
X1533992D01*
G01X1530449Y1548514D02*
X1531551D01*
G01X1542605Y1548061D02*
X1549937D01*
G01X1542457D02*
X1530449D01*
G01X1533008Y1547884D02*
X1532024D01*
G01X1533008Y1547687D02*
X1532024D01*
G01X1533008Y1547293D02*
X1532024D01*
G01X1542457Y1547274D02*
X1530449D01*
G01X1549937D02*
X1542605D01*
G01X1531551Y1547096D02*
X1537142D01*
G01X1531551Y1545522D02*
X1537142D01*
G01X1533008Y1545325D02*
X1532024D01*
G01X1533008Y1544931D02*
X1532024D01*
G01X1542605Y1544911D02*
X1549937D01*
G01X1542457D02*
X1530449D01*
G01X1533008Y1544734D02*
X1532024D01*
G01X1542457Y1544124D02*
X1530449D01*
G01X1549937D02*
X1542605D01*
G01X1530449Y1544104D02*
X1531551D01*
G01X1534976Y1542884D02*
X1533992D01*
G01X1534976Y1542687D02*
X1533992D01*
G01X1534976Y1542293D02*
X1533992D01*
G01X1531945Y1542096D02*
X1539110D01*
G01X1542605Y1541762D02*
X1549937D01*
G01X1542457D02*
X1530449D01*
G01X1542457Y1540974D02*
X1530449D01*
G01X1549937D02*
X1542605D01*
G01X1531945Y1540522D02*
X1539110D01*
G01X1534976Y1540325D02*
X1533992D01*
G01X1534976Y1539931D02*
X1533992D01*
G01X1534976Y1539734D02*
X1533992D01*
G01X1542605Y1538612D02*
X1549937D01*
G01X1542457D02*
X1530449D01*
G01X1534976Y1537884D02*
X1533992D01*
G01X1542457Y1537825D02*
X1530449D01*
G01X1549937D02*
X1542605D01*
G01X1534976Y1537687D02*
X1533992D01*
G01X1534976Y1537293D02*
X1533992D01*
G01X1539110Y1537096D02*
X1531945D01*
G01X1539110Y1535522D02*
X1531945D01*
G01X1542605Y1535463D02*
X1549937D01*
G01X1542457D02*
X1530449D01*
G01X1534976Y1535325D02*
X1533992D01*
G01X1534976Y1534931D02*
X1533992D01*
G01X1534976Y1534734D02*
X1533992D01*
G01X1542457Y1534675D02*
X1530449D01*
G01X1549937D02*
X1542605D01*
G01X1534976Y1532884D02*
X1533992D01*
G01X1534976Y1532687D02*
X1533992D01*
G01X1542605Y1532313D02*
X1549937D01*
G01X1542457D02*
X1530449D01*
G01X1534976Y1532293D02*
X1533992D01*
G01X1531945Y1532096D02*
X1539110D01*
G01X1542457Y1531525D02*
X1530449D01*
G01X1549937D02*
X1542605D01*
G01X1531945Y1530522D02*
X1539110D01*
G01X1534976Y1530325D02*
X1533992D01*
G01X1534976Y1529931D02*
X1533992D01*
G01X1544551Y1529852D02*
X1535567D01*
G01X1534976Y1529734D02*
X1533992D01*
G01X1531551Y1528277D02*
X1522181D01*
G01X1551709Y1528100D02*
X1531551D01*
G01X1521866Y1527687D02*
X1528401D01*
G01X1531551Y1526506D02*
X1522181D01*
G01X1550916Y1525325D02*
X1530449D01*
G01X1536549Y1524931D02*
X1530449D01*
G01X1536549Y1524872D02*
X1530449D01*
G01X1551709Y1524340D02*
X1528087D01*
G01X1541611Y1522903D02*
X1537003D01*
G01X1551709Y1521939D02*
X1528087D01*
G01X1537353Y1521722D02*
X1541261D01*
G01X1540303Y1521378D02*
X1538843D01*
G01X1551709Y1519970D02*
X1528087D01*
G01X1527333Y1519631D02*
X1525890D01*
G01X1549942D02*
X1548560D01*
G01X1547265D02*
X1545648D01*
G01X1543875Y1518049D02*
X1542450D01*
G01X1545448Y1517223D02*
X1542449D01*
G01X1545318Y1516780D02*
X1543814D01*
G01X1541261Y1516289D02*
X1537353D01*
G01X1551709Y1516191D02*
X1528087D01*
G01X1527330Y1515624D02*
X1525890D01*
G01X1530220D02*
X1528761D01*
G01X1533043D02*
X1531651D01*
G01X1540303D02*
X1538843D01*
G01X1549968D02*
X1548419D01*
G01X1546882D02*
X1545474D01*
G01X1537003Y1515108D02*
X1541611D01*
G01X1538244Y1511466D02*
X1521866D01*
G01X1527890Y1508770D02*
X1532220D01*
G01X1527264Y1507982D02*
X1532846D01*
G01Y1506407D02*
X1527264D01*
G01X1532220Y1505620D02*
X1527890D01*
G01X1545648Y1519631D02*
X1546917Y1517771D01*
G01X1547673Y1516902D02*
X1548419Y1515624D01*
G01X1548647Y1517780D02*
X1549968Y1515624D01*
G01X1547265Y1519631D02*
X1547870Y1518645D01*
G01X1541261Y1516289D02*
X1541279Y1516233D01*
X1541331Y1516068D01*
X1541410Y1515809D01*
X1541506Y1515482D01*
X1541611Y1515108D01*
G01X1537353Y1521722D02*
X1537335Y1521778D01*
X1537283Y1521944D01*
X1537204Y1522202D01*
X1537108Y1522530D01*
X1537003Y1522903D01*
G01X1551709Y1514222D02*
Y1528100D01*
G01X1551391Y1522569D02*
Y1528100D01*
G01X1550916Y1525325D02*
Y1528100D01*
G01X1549937Y1532313D02*
Y1531525D01*
G01Y1538612D02*
Y1537825D01*
G01Y1535463D02*
Y1534675D01*
G01Y1541762D02*
Y1540974D01*
G01Y1548061D02*
Y1547274D01*
G01Y1544911D02*
Y1544124D01*
G01Y1551211D02*
Y1550423D01*
G01Y1557510D02*
Y1556722D01*
G01Y1554360D02*
Y1553573D01*
G01Y1560659D02*
Y1559872D01*
G01Y1566959D02*
Y1566171D01*
G01Y1563809D02*
Y1563022D01*
G01Y1570108D02*
Y1569321D01*
G01Y1573258D02*
Y1572470D01*
G01X1548163Y1532313D02*
Y1531525D01*
G01Y1538612D02*
Y1537825D01*
G01Y1535463D02*
Y1534675D01*
G01Y1541762D02*
Y1540974D01*
G01Y1548061D02*
Y1547274D01*
G01Y1544911D02*
Y1544124D01*
G01Y1551211D02*
Y1550423D01*
G01Y1557510D02*
Y1556722D01*
G01Y1554360D02*
Y1553573D01*
G01Y1560659D02*
Y1559872D01*
G01Y1566959D02*
Y1566171D01*
G01Y1563809D02*
Y1563022D01*
G01Y1570108D02*
Y1569321D01*
G01Y1573258D02*
Y1572470D01*
G01X1547975D02*
Y1573258D01*
G01Y1569321D02*
Y1570108D01*
G01Y1566171D02*
Y1566959D01*
G01Y1563022D02*
Y1563809D01*
G01Y1559872D02*
Y1560659D01*
G01Y1556722D02*
Y1557510D01*
G01Y1553573D02*
Y1554360D01*
G01Y1550423D02*
Y1551211D01*
G01Y1547274D02*
Y1548061D01*
G01Y1544124D02*
Y1544911D01*
G01Y1540974D02*
Y1541762D01*
G01Y1537825D02*
Y1538612D01*
G01Y1534675D02*
Y1535463D01*
G01Y1531525D02*
Y1532313D01*
G01X1545138Y1572470D02*
Y1573258D01*
G01Y1569321D02*
Y1570108D01*
G01Y1566171D02*
Y1566959D01*
G01Y1563022D02*
Y1563809D01*
G01Y1559872D02*
Y1560659D01*
G01Y1556722D02*
Y1557510D01*
G01Y1553573D02*
Y1554360D01*
G01Y1550423D02*
Y1551211D01*
G01Y1547274D02*
Y1548061D01*
G01Y1544124D02*
Y1544911D01*
G01Y1540974D02*
Y1541762D01*
G01Y1537825D02*
Y1538612D01*
G01Y1534675D02*
Y1535463D01*
G01Y1531525D02*
Y1532313D01*
G01X1545062Y1525325D02*
Y1522569D01*
G01X1544551Y1525325D02*
Y1662293D01*
G01X1544197Y1532313D02*
Y1531525D01*
G01Y1538612D02*
Y1537825D01*
G01Y1535463D02*
Y1534675D01*
G01Y1541762D02*
Y1540974D01*
G01Y1548061D02*
Y1547274D01*
G01Y1544911D02*
Y1544124D01*
G01Y1551211D02*
Y1550423D01*
G01Y1557510D02*
Y1556722D01*
G01Y1554360D02*
Y1553573D01*
G01Y1560659D02*
Y1559872D01*
G01Y1566959D02*
Y1566171D01*
G01Y1563809D02*
Y1563022D01*
G01Y1570108D02*
Y1569321D01*
G01Y1573258D02*
Y1572470D01*
G01X1542605Y1532313D02*
Y1531525D01*
G01Y1538612D02*
Y1537825D01*
G01Y1535463D02*
Y1534675D01*
G01Y1541762D02*
Y1540974D01*
G01Y1548061D02*
Y1547274D01*
G01Y1544911D02*
Y1544124D01*
G01Y1551211D02*
Y1550423D01*
G01Y1557510D02*
Y1556722D01*
G01Y1554360D02*
Y1553573D01*
G01Y1560659D02*
Y1559872D01*
G01Y1566959D02*
Y1566171D01*
G01Y1563809D02*
Y1563022D01*
G01Y1570108D02*
Y1569321D01*
G01Y1573258D02*
Y1572470D01*
G01X1542457Y1532313D02*
Y1531525D01*
G01Y1538612D02*
Y1537825D01*
G01Y1535463D02*
Y1534675D01*
G01Y1541762D02*
Y1540974D01*
G01Y1548061D02*
Y1547274D01*
G01Y1544911D02*
Y1544124D01*
G01Y1551211D02*
Y1550423D01*
G01Y1557510D02*
Y1556722D01*
G01Y1554360D02*
Y1553573D01*
G01Y1560659D02*
Y1559872D01*
G01Y1566959D02*
Y1566171D01*
G01Y1563809D02*
Y1563022D01*
G01Y1570108D02*
Y1569321D01*
G01Y1573258D02*
Y1572470D01*
G01X1541519Y1573258D02*
Y1575620D01*
G01Y1570108D02*
Y1572470D01*
G01Y1566959D02*
Y1569321D01*
G01Y1563809D02*
Y1566171D01*
G01Y1560659D02*
Y1563022D01*
G01Y1557510D02*
Y1559872D01*
G01Y1554360D02*
Y1556722D01*
G01Y1551211D02*
Y1553573D01*
G01Y1548061D02*
Y1550423D01*
G01Y1544911D02*
Y1547274D01*
G01Y1541762D02*
Y1544124D01*
G01Y1538612D02*
Y1540974D01*
G01Y1535463D02*
Y1537825D01*
G01Y1532313D02*
Y1534675D01*
G01Y1529852D02*
Y1531525D01*
G01X1540303Y1521378D02*
Y1515624D01*
G01X1539791Y1532313D02*
Y1531525D01*
G01Y1538612D02*
Y1537825D01*
G01Y1535463D02*
Y1534675D01*
G01Y1541762D02*
Y1540974D01*
G01Y1548061D02*
Y1547274D01*
G01Y1544911D02*
Y1544124D01*
G01Y1551211D02*
Y1550423D01*
G01Y1557510D02*
Y1556722D01*
G01Y1554360D02*
Y1553573D01*
G01Y1560659D02*
Y1559872D01*
G01Y1566959D02*
Y1566171D01*
G01Y1563809D02*
Y1563022D01*
G01Y1570108D02*
Y1569321D01*
G01Y1573258D02*
Y1572470D01*
G01X1539110Y1570522D02*
Y1572096D01*
G01Y1565522D02*
Y1567096D01*
G01Y1560522D02*
Y1562096D01*
G01Y1555522D02*
Y1557096D01*
G01Y1550522D02*
Y1552096D01*
G01Y1540522D02*
Y1542096D01*
G01Y1535522D02*
Y1537096D01*
G01Y1530522D02*
Y1532096D01*
G01X1538843Y1515624D02*
Y1521378D01*
G01X1538139Y1572470D02*
Y1573258D01*
G01Y1569321D02*
Y1570108D01*
G01Y1566171D02*
Y1566959D01*
G01Y1563022D02*
Y1563809D01*
G01Y1559872D02*
Y1560659D01*
G01Y1556722D02*
Y1557510D01*
G01Y1553573D02*
Y1554360D01*
G01Y1550423D02*
Y1551211D01*
G01Y1547274D02*
Y1548061D01*
G01Y1544124D02*
Y1544911D01*
G01Y1540974D02*
Y1541762D01*
G01Y1537825D02*
Y1538612D01*
G01Y1534675D02*
Y1535463D01*
G01Y1531525D02*
Y1532313D01*
G01X1537188Y1525325D02*
Y1522569D01*
G01X1537142Y1545522D02*
Y1547096D01*
G01X1536549Y1524872D02*
Y1524931D01*
G01X1536156Y1572470D02*
Y1573258D01*
G01Y1569321D02*
Y1570108D01*
G01Y1566171D02*
Y1566959D01*
G01Y1563022D02*
Y1563809D01*
G01Y1559872D02*
Y1560659D01*
G01Y1556722D02*
Y1557510D01*
G01Y1553573D02*
Y1554360D01*
G01Y1550423D02*
Y1551211D01*
G01Y1547274D02*
Y1548061D01*
G01Y1544124D02*
Y1544911D01*
G01Y1540974D02*
Y1541762D01*
G01Y1537825D02*
Y1538612D01*
G01Y1534675D02*
Y1535463D01*
G01Y1531525D02*
Y1532313D01*
G01X1536021Y1659714D02*
Y1528100D01*
G01X1535961Y1532096D02*
Y1530522D01*
G01Y1537096D02*
Y1535522D01*
G01Y1542096D02*
Y1540522D01*
G01Y1552096D02*
Y1550522D01*
G01Y1557096D02*
Y1555522D01*
G01Y1562096D02*
Y1560522D01*
G01Y1567096D02*
Y1565522D01*
G01Y1572096D02*
Y1570522D01*
G01X1535567Y1662293D02*
Y1525325D01*
G01X1534976Y1532884D02*
Y1529734D01*
G01Y1537884D02*
Y1534734D01*
G01Y1542884D02*
Y1539734D01*
G01Y1552884D02*
Y1549734D01*
G01Y1557884D02*
Y1554734D01*
G01Y1562884D02*
Y1559734D01*
G01Y1567884D02*
Y1564734D01*
G01Y1572884D02*
Y1569734D01*
G01Y1577884D02*
Y1574734D01*
G01X1533992Y1522569D02*
Y1524872D01*
G01Y1532884D02*
Y1529734D01*
G01Y1537884D02*
Y1534734D01*
G01Y1542884D02*
Y1539734D01*
G01Y1547096D02*
Y1545522D01*
G01Y1552884D02*
Y1549734D01*
G01Y1557884D02*
Y1554734D01*
G01Y1562884D02*
Y1559734D01*
G01Y1567884D02*
Y1564734D01*
G01Y1572884D02*
Y1569734D01*
G01Y1577884D02*
Y1574734D01*
G01X1533043Y1518553D02*
Y1515624D01*
G01X1533008Y1532096D02*
Y1530522D01*
G01Y1537096D02*
Y1535522D01*
G01Y1542096D02*
Y1540522D01*
G01Y1547884D02*
Y1544734D01*
G01Y1552096D02*
Y1550522D01*
G01Y1557096D02*
Y1555522D01*
G01Y1562096D02*
Y1560522D01*
G01Y1567096D02*
Y1565522D01*
G01Y1572096D02*
Y1570522D01*
G01X1532846Y1506407D02*
Y1507982D01*
G01X1532811D02*
Y1506407D01*
G01X1532793Y1532313D02*
Y1531525D01*
G01Y1538612D02*
Y1537825D01*
G01Y1535463D02*
Y1534675D01*
G01Y1541762D02*
Y1540974D01*
G01Y1548061D02*
Y1547274D01*
G01Y1544911D02*
Y1544124D01*
G01Y1551211D02*
Y1550423D01*
G01Y1557510D02*
Y1556722D01*
G01Y1554360D02*
Y1553573D01*
G01Y1560659D02*
Y1559872D01*
G01Y1566959D02*
Y1566171D01*
G01Y1563809D02*
Y1563022D01*
G01Y1570108D02*
Y1569321D01*
G01Y1573258D02*
Y1572470D01*
G01X1532787Y1507982D02*
Y1506407D01*
G01X1532417Y1532313D02*
Y1531525D01*
G01Y1538612D02*
Y1537825D01*
G01Y1535463D02*
Y1534675D01*
G01Y1541762D02*
Y1540974D01*
G01Y1548061D02*
Y1547274D01*
G01Y1544911D02*
Y1544124D01*
G01Y1551211D02*
Y1550423D01*
G01Y1557510D02*
Y1556722D01*
G01Y1554360D02*
Y1553573D01*
G01Y1560659D02*
Y1559872D01*
G01Y1566959D02*
Y1566171D01*
G01Y1563809D02*
Y1563022D01*
G01Y1570108D02*
Y1569321D01*
G01Y1573258D02*
Y1572470D01*
G01X1532391Y1532313D02*
Y1531525D01*
G01Y1538612D02*
Y1537825D01*
G01Y1535463D02*
Y1534675D01*
G01Y1541762D02*
Y1540974D01*
G01Y1548061D02*
Y1547274D01*
G01Y1544911D02*
Y1544124D01*
G01Y1551211D02*
Y1550423D01*
G01Y1557510D02*
Y1556722D01*
G01Y1554360D02*
Y1553573D01*
G01Y1560659D02*
Y1559872D01*
G01Y1566959D02*
Y1566171D01*
G01Y1563809D02*
Y1563022D01*
G01Y1570108D02*
Y1569321D01*
G01Y1573258D02*
Y1572470D01*
G01X1532024Y1547884D02*
Y1544734D01*
G01X1531651Y1515624D02*
Y1518149D01*
G01X1531551Y1662293D02*
Y1525325D01*
G01X1531464Y1506407D02*
Y1507982D01*
G01X1531094D02*
Y1506407D01*
G01X1530449Y1524872D02*
Y1662746D01*
G01X1530220Y1518149D02*
Y1515624D01*
G01X1529016Y1506407D02*
Y1507982D01*
G01X1528761Y1515624D02*
Y1518149D01*
G01X1528646Y1507982D02*
Y1506407D01*
G01X1528401Y1659931D02*
Y1527687D01*
G01X1528087Y1519970D02*
Y1516191D01*
G01Y1524340D02*
Y1521939D01*
G01X1527333Y1519631D02*
Y1519074D01*
G01X1527330Y1518149D02*
Y1515624D01*
G01X1527324Y1506407D02*
Y1507982D01*
G01X1527299Y1506407D02*
Y1507982D01*
G01X1527264D02*
Y1506407D01*
G01X1526433Y1545207D02*
Y1527687D01*
G01Y1564104D02*
Y1547569D01*
G01Y1583002D02*
Y1566466D01*
G01X1525890Y1519631D02*
Y1515624D01*
G01X1524149Y1514222D02*
Y1522569D01*
G01X1522181Y1528277D02*
Y1526506D01*
G01X1520212Y1527490D02*
Y1660128D01*
G01X1549942Y1519631D02*
X1548647Y1517780D01*
G01X1548560Y1519631D02*
X1547870Y1518645D01*
G01X1546917Y1517771D02*
X1545474Y1515624D01*
G01X1536549Y1524931D02*
X1536804Y1525325D01*
G01X1547673Y1516902D02*
X1546882Y1515624D01*
G01X1541261Y1521722D02*
X1541279Y1521778D01*
X1541331Y1521943D01*
X1541410Y1522202D01*
X1541506Y1522529D01*
X1541611Y1522903D01*
G01X1537003Y1515108D02*
X1537106Y1515477D01*
X1537203Y1515807D01*
X1537283Y1516069D01*
X1537335Y1516235D01*
X1537353Y1516289D01*
G01X1503974Y1576407D02*
X1503846Y1576380D01*
X1503758Y1576307D01*
X1503727Y1576211D01*
G01X1509023Y1575620D02*
X1509050Y1575624D01*
X1509075Y1575635D01*
X1509099Y1575653D01*
X1509121Y1575678D01*
X1509138Y1575707D01*
X1509150Y1575741D01*
X1509158Y1575778D01*
X1509161Y1575817D01*
G01X1509749Y1577096D02*
X1504004D01*
G01X1510176Y1576506D02*
X1503590D01*
G01X1503974Y1576407D02*
X1510058D01*
G01X1503727Y1576211D02*
X1510338D01*
G01X1503590Y1576112D02*
X1510176D01*
G01X1510338Y1575817D02*
X1503727D01*
G01X1503974Y1575620D02*
X1510058D01*
G01X1504004Y1575522D02*
X1509749D01*
G01X1508572Y1576407D02*
X1508610Y1576381D01*
X1508638Y1576309D01*
X1508648Y1576211D01*
G01X1509749Y1577096D02*
X1510176Y1576506D01*
G01X1509060Y1577096D02*
X1509332Y1576506D01*
G01X1503727Y1575817D02*
X1503758Y1575720D01*
X1503847Y1575648D01*
X1503974Y1575620D01*
G01X1508208Y1576506D02*
X1508130Y1577096D01*
G01X1509161Y1576211D02*
X1509158Y1576249D01*
X1509151Y1576286D01*
X1509138Y1576319D01*
X1509121Y1576350D01*
X1509100Y1576374D01*
X1509076Y1576392D01*
X1509050Y1576403D01*
X1509023Y1576407D01*
G01X1508208Y1576112D02*
X1508130Y1575522D01*
G01X1508648Y1575817D02*
X1508638Y1575718D01*
X1508610Y1575646D01*
X1508572Y1575620D01*
G01X1510338Y1575817D02*
Y1576211D01*
G01X1510176Y1576506D02*
Y1576112D01*
G01X1509332Y1576506D02*
Y1576112D01*
G01X1509161Y1575817D02*
Y1576211D01*
G01X1508648D02*
Y1575817D01*
G01X1508208Y1576112D02*
Y1576506D01*
G01X1503727Y1576211D02*
Y1575817D01*
G01X1503590Y1576112D02*
Y1576506D01*
G01X1504004Y1577096D02*
X1503865Y1576900D01*
X1503727Y1576703D01*
X1503590Y1576506D01*
G01X1509023Y1648061D02*
X1509050Y1648065D01*
X1509075Y1648076D01*
X1509099Y1648094D01*
X1509121Y1648119D01*
X1509138Y1648148D01*
X1509150Y1648182D01*
X1509158Y1648219D01*
X1509161Y1648258D01*
G01X1509023Y1644911D02*
X1509050Y1644915D01*
X1509075Y1644926D01*
X1509099Y1644944D01*
X1509121Y1644969D01*
X1509138Y1644999D01*
X1509150Y1645033D01*
X1509158Y1645069D01*
X1509161Y1645108D01*
G01X1509023Y1641762D02*
X1509050Y1641765D01*
X1509075Y1641777D01*
X1509099Y1641795D01*
X1509121Y1641819D01*
X1509138Y1641849D01*
X1509150Y1641883D01*
X1509158Y1641920D01*
X1509161Y1641959D01*
G01X1509023Y1638612D02*
X1509050Y1638616D01*
X1509075Y1638627D01*
X1509099Y1638645D01*
X1509121Y1638670D01*
X1509138Y1638699D01*
X1509150Y1638733D01*
X1509158Y1638770D01*
X1509161Y1638809D01*
G01X1509023Y1635463D02*
X1509050Y1635466D01*
X1509075Y1635477D01*
X1509099Y1635495D01*
X1509121Y1635520D01*
X1509138Y1635550D01*
X1509150Y1635584D01*
X1509158Y1635620D01*
X1509161Y1635659D01*
G01X1509023Y1632313D02*
X1509050Y1632317D01*
X1509075Y1632328D01*
X1509099Y1632346D01*
X1509121Y1632371D01*
X1509138Y1632400D01*
X1509150Y1632434D01*
X1509158Y1632471D01*
X1509161Y1632510D01*
G01X1509023Y1629163D02*
X1509050Y1629167D01*
X1509075Y1629178D01*
X1509099Y1629196D01*
X1509121Y1629221D01*
X1509138Y1629251D01*
X1509150Y1629284D01*
X1509158Y1629321D01*
X1509161Y1629360D01*
G01X1509023Y1626014D02*
X1509050Y1626017D01*
X1509075Y1626029D01*
X1509099Y1626047D01*
X1509121Y1626071D01*
X1509138Y1626101D01*
X1509150Y1626135D01*
X1509158Y1626172D01*
X1509161Y1626211D01*
G01X1509023Y1622864D02*
X1509050Y1622868D01*
X1509075Y1622879D01*
X1509099Y1622897D01*
X1509121Y1622922D01*
X1509138Y1622951D01*
X1509150Y1622985D01*
X1509158Y1623022D01*
X1509161Y1623061D01*
G01X1509023Y1619714D02*
X1509050Y1619718D01*
X1509075Y1619729D01*
X1509099Y1619747D01*
X1509121Y1619772D01*
X1509138Y1619802D01*
X1509150Y1619836D01*
X1509158Y1619872D01*
X1509161Y1619911D01*
G01X1509023Y1616565D02*
X1509050Y1616569D01*
X1509075Y1616580D01*
X1509099Y1616598D01*
X1509121Y1616623D01*
X1509138Y1616652D01*
X1509150Y1616686D01*
X1509158Y1616723D01*
X1509161Y1616762D01*
G01X1509023Y1613415D02*
X1509050Y1613419D01*
X1509075Y1613430D01*
X1509099Y1613448D01*
X1509121Y1613473D01*
X1509138Y1613503D01*
X1509150Y1613536D01*
X1509158Y1613573D01*
X1509161Y1613612D01*
G01X1509023Y1610266D02*
X1509050Y1610269D01*
X1509075Y1610281D01*
X1509099Y1610299D01*
X1509121Y1610323D01*
X1509138Y1610353D01*
X1509150Y1610387D01*
X1509158Y1610424D01*
X1509161Y1610463D01*
G01X1509023Y1607116D02*
X1509050Y1607120D01*
X1509075Y1607131D01*
X1509099Y1607149D01*
X1509121Y1607174D01*
X1509138Y1607203D01*
X1509150Y1607237D01*
X1509158Y1607274D01*
X1509161Y1607313D01*
G01X1509023Y1603966D02*
X1509050Y1603970D01*
X1509075Y1603981D01*
X1509099Y1603999D01*
X1509121Y1604024D01*
X1509138Y1604054D01*
X1509150Y1604088D01*
X1509158Y1604124D01*
X1509161Y1604163D01*
G01X1509023Y1600817D02*
X1509050Y1600821D01*
X1509075Y1600832D01*
X1509099Y1600850D01*
X1509121Y1600874D01*
X1509138Y1600904D01*
X1509150Y1600938D01*
X1509158Y1600975D01*
X1509161Y1601014D01*
G01X1503964Y1622370D02*
X1503838Y1622342D01*
X1503748Y1622270D01*
X1503717Y1622173D01*
G01X1503964Y1619220D02*
X1503838Y1619193D01*
X1503748Y1619120D01*
X1503717Y1619023D01*
G01X1503964Y1616071D02*
X1503838Y1616043D01*
X1503748Y1615971D01*
X1503717Y1615874D01*
G01X1503964Y1612921D02*
X1503838Y1612894D01*
X1503748Y1612821D01*
X1503717Y1612724D01*
G01X1503964Y1609771D02*
X1503838Y1609744D01*
X1503748Y1609671D01*
X1503717Y1609575D01*
G01X1503964Y1606622D02*
X1503838Y1606594D01*
X1503748Y1606522D01*
X1503717Y1606425D01*
G01X1503974Y1645699D02*
X1503846Y1645671D01*
X1503758Y1645598D01*
X1503727Y1645502D01*
G01X1503974Y1642549D02*
X1503846Y1642521D01*
X1503758Y1642448D01*
X1503727Y1642352D01*
G01X1503974Y1639400D02*
X1503846Y1639372D01*
X1503758Y1639299D01*
X1503727Y1639203D01*
G01X1503974Y1636250D02*
X1503846Y1636222D01*
X1503758Y1636149D01*
X1503727Y1636053D01*
G01X1503974Y1633100D02*
X1503846Y1633073D01*
X1503758Y1633000D01*
X1503727Y1632903D01*
G01X1503974Y1629951D02*
X1503846Y1629923D01*
X1503758Y1629850D01*
X1503727Y1629754D01*
G01X1503974Y1626801D02*
X1503846Y1626773D01*
X1503758Y1626700D01*
X1503727Y1626604D01*
G01X1503974Y1623651D02*
X1503846Y1623624D01*
X1503758Y1623551D01*
X1503727Y1623455D01*
G01X1503974Y1620502D02*
X1503846Y1620474D01*
X1503758Y1620401D01*
X1503727Y1620305D01*
G01X1503974Y1617352D02*
X1503846Y1617325D01*
X1503758Y1617252D01*
X1503727Y1617155D01*
G01X1503974Y1614203D02*
X1503846Y1614175D01*
X1503758Y1614102D01*
X1503727Y1614006D01*
G01X1503974Y1611053D02*
X1503846Y1611025D01*
X1503758Y1610952D01*
X1503727Y1610856D01*
G01X1503974Y1607903D02*
X1503846Y1607876D01*
X1503758Y1607803D01*
X1503727Y1607707D01*
G01X1503974Y1604754D02*
X1503846Y1604726D01*
X1503758Y1604653D01*
X1503727Y1604557D01*
G01X1503974Y1601604D02*
X1503846Y1601576D01*
X1503758Y1601504D01*
X1503727Y1601407D01*
G01X1503974Y1598455D02*
X1503846Y1598427D01*
X1503758Y1598354D01*
X1503727Y1598258D01*
G01X1503974Y1595305D02*
X1503846Y1595277D01*
X1503758Y1595204D01*
X1503727Y1595108D01*
G01X1503974Y1592155D02*
X1503846Y1592128D01*
X1503758Y1592055D01*
X1503727Y1591959D01*
G01X1503974Y1589006D02*
X1503846Y1588978D01*
X1503758Y1588905D01*
X1503727Y1588809D01*
G01X1503974Y1585856D02*
X1503846Y1585828D01*
X1503758Y1585756D01*
X1503727Y1585659D01*
G01X1503974Y1582707D02*
X1503846Y1582679D01*
X1503758Y1582606D01*
X1503727Y1582510D01*
G01X1503974Y1579557D02*
X1503846Y1579529D01*
X1503758Y1579456D01*
X1503727Y1579360D01*
G01X1503974Y1648061D02*
X1510058D01*
G01X1509749Y1647096D02*
X1504004D01*
G01X1510176Y1646506D02*
X1503590D01*
G01Y1646112D02*
X1510176D01*
G01X1503974Y1645699D02*
X1510058D01*
G01X1504004Y1645522D02*
X1509749D01*
G01X1503727Y1645502D02*
X1510338D01*
G01Y1645108D02*
X1503727D01*
G01X1503974Y1644911D02*
X1510058D01*
G01X1501709Y1643514D02*
X1528401D01*
G01X1503974Y1642549D02*
X1510058D01*
G01X1503727Y1642352D02*
X1510338D01*
G01X1509749Y1642096D02*
X1504004D01*
G01X1510338Y1641959D02*
X1503727D01*
G01X1503974Y1641762D02*
X1510058D01*
G01X1510176Y1641506D02*
X1503590D01*
G01X1528401Y1641151D02*
X1501709D01*
G01X1503590Y1641112D02*
X1510176D01*
G01X1504004Y1640522D02*
X1509749D01*
G01X1503974Y1639400D02*
X1510058D01*
G01X1503727Y1639203D02*
X1510338D01*
G01Y1638809D02*
X1503727D01*
G01X1503974Y1638612D02*
X1510058D01*
G01X1509749Y1637096D02*
X1504004D01*
G01X1510176Y1636506D02*
X1503590D01*
G01X1503974Y1636250D02*
X1510058D01*
G01X1503590Y1636112D02*
X1510176D01*
G01X1503727Y1636053D02*
X1510338D01*
G01Y1635659D02*
X1503727D01*
G01X1504004Y1635522D02*
X1509749D01*
G01X1503974Y1635463D02*
X1510058D01*
G01X1503974Y1633100D02*
X1510058D01*
G01X1503727Y1632903D02*
X1510338D01*
G01Y1632510D02*
X1503727D01*
G01X1503974Y1632313D02*
X1510058D01*
G01X1509749Y1632096D02*
X1504004D01*
G01X1510176Y1631506D02*
X1503590D01*
G01Y1631112D02*
X1510176D01*
G01X1504004Y1630522D02*
X1509749D01*
G01X1503974Y1629951D02*
X1510058D01*
G01X1520212Y1629911D02*
X1500751D01*
G01X1503727Y1629754D02*
X1510338D01*
G01Y1629360D02*
X1503727D01*
G01X1503974Y1629163D02*
X1510058D01*
G01X1509817Y1627096D02*
X1503904D01*
G01X1503974Y1626801D02*
X1510058D01*
G01X1503727Y1626604D02*
X1510338D01*
G01X1510241Y1626506D02*
X1503499D01*
G01X1510338Y1626211D02*
X1503727D01*
G01X1503499Y1626112D02*
X1510241D01*
G01X1503974Y1626014D02*
X1510058D01*
G01X1501709Y1625915D02*
X1528401D01*
G01X1509817Y1625522D02*
X1503904D01*
G01X1499740Y1624734D02*
X1506209D01*
G01X1503974Y1623651D02*
X1510058D01*
G01X1520212Y1623573D02*
X1501709D01*
G01X1528401Y1623553D02*
X1506209D01*
G01X1503727Y1623455D02*
X1510338D01*
G01Y1623061D02*
X1503727D01*
G01X1503974Y1622864D02*
X1510058D01*
G01X1509772Y1622370D02*
X1503964D01*
G01X1510035Y1622173D02*
X1503717D01*
G01Y1621189D02*
X1510035D01*
G01X1509772Y1620992D02*
X1503964D01*
G01X1503974Y1620502D02*
X1510058D01*
G01X1503727Y1620305D02*
X1510338D01*
G01Y1619911D02*
X1503727D01*
G01X1503974Y1619714D02*
X1510058D01*
G01X1509772Y1619220D02*
X1503964D01*
G01X1510035Y1619023D02*
X1503717D01*
G01Y1618039D02*
X1510035D01*
G01X1509772Y1617842D02*
X1503964D01*
G01X1503974Y1617352D02*
X1510058D01*
G01X1503727Y1617155D02*
X1510338D01*
G01Y1616762D02*
X1503727D01*
G01X1503974Y1616565D02*
X1510058D01*
G01X1509772Y1616071D02*
X1503964D01*
G01X1510035Y1615874D02*
X1503717D01*
G01Y1614889D02*
X1510035D01*
G01X1509772Y1614693D02*
X1503964D01*
G01X1503974Y1614203D02*
X1510058D01*
G01X1503727Y1614006D02*
X1510338D01*
G01Y1613612D02*
X1503727D01*
G01X1503974Y1613415D02*
X1510058D01*
G01X1509772Y1612921D02*
X1503964D01*
G01X1510035Y1612724D02*
X1503717D01*
G01Y1611740D02*
X1510035D01*
G01X1509772Y1611543D02*
X1503964D01*
G01X1503974Y1611053D02*
X1510058D01*
G01X1503727Y1610856D02*
X1510338D01*
G01Y1610463D02*
X1503727D01*
G01X1503974Y1610266D02*
X1510058D01*
G01X1509772Y1609771D02*
X1503964D01*
G01X1510035Y1609575D02*
X1503717D01*
G01Y1608590D02*
X1510035D01*
G01X1509772Y1608393D02*
X1503964D01*
G01X1503974Y1607903D02*
X1510058D01*
G01X1503727Y1607707D02*
X1510338D01*
G01Y1607313D02*
X1503727D01*
G01X1503974Y1607116D02*
X1510058D01*
G01X1509772Y1606622D02*
X1503964D01*
G01X1510035Y1606425D02*
X1503717D01*
G01Y1605441D02*
X1510035D01*
G01X1509772Y1605244D02*
X1503964D01*
G01X1503974Y1604754D02*
X1510058D01*
G01X1503727Y1604557D02*
X1510338D01*
G01Y1604163D02*
X1503727D01*
G01X1506209Y1604065D02*
X1528401D01*
G01X1520212Y1604045D02*
X1501709D01*
G01X1503974Y1603966D02*
X1510058D01*
G01X1506209Y1602884D02*
X1499740D01*
G01X1509817Y1602096D02*
X1503904D01*
G01X1528401Y1601703D02*
X1501709D01*
G01X1503974Y1601604D02*
X1510058D01*
G01X1510241Y1601506D02*
X1503499D01*
G01X1503727Y1601407D02*
X1510338D01*
G01X1503499Y1601112D02*
X1510241D01*
G01X1510338Y1601014D02*
X1503727D01*
G01X1503974Y1600817D02*
X1510058D01*
G01X1509817Y1600522D02*
X1503904D01*
G01X1503974Y1598455D02*
X1510058D01*
G01X1503727Y1598258D02*
X1510338D01*
G01Y1597864D02*
X1503727D01*
G01X1503974Y1597667D02*
X1510058D01*
G01X1500751Y1597608D02*
X1520212D01*
G01X1509749Y1597096D02*
X1504004D01*
G01X1510176Y1596506D02*
X1503590D01*
G01Y1596112D02*
X1510176D01*
G01X1504004Y1595522D02*
X1509749D01*
G01X1503974Y1595305D02*
X1510058D01*
G01X1503727Y1595108D02*
X1510338D01*
G01Y1594714D02*
X1503727D01*
G01X1503974Y1594518D02*
X1510058D01*
G01X1503974Y1592155D02*
X1510058D01*
G01X1509749Y1592096D02*
X1504004D01*
G01X1503727Y1591959D02*
X1510338D01*
G01Y1591565D02*
X1503727D01*
G01X1510176Y1591506D02*
X1503590D01*
G01X1503974Y1591368D02*
X1510058D01*
G01X1503590Y1591112D02*
X1510176D01*
G01X1504004Y1590522D02*
X1509749D01*
G01X1503974Y1589006D02*
X1510058D01*
G01X1503727Y1588809D02*
X1510338D01*
G01Y1588415D02*
X1503727D01*
G01X1503974Y1588218D02*
X1510058D01*
G01X1507781Y1587096D02*
X1502036D01*
G01X1508207Y1586506D02*
X1501621D01*
G01Y1586112D02*
X1508207D01*
G01X1503974Y1585856D02*
X1510058D01*
G01X1503727Y1585659D02*
X1510338D01*
G01X1502036Y1585522D02*
X1507781D01*
G01X1501709Y1585364D02*
X1528401D01*
G01X1510338Y1585266D02*
X1503727D01*
G01X1503974Y1585069D02*
X1510058D01*
G01X1528401Y1583002D02*
X1501709D01*
G01X1503974Y1582707D02*
X1510058D01*
G01X1503727Y1582510D02*
X1510338D01*
G01Y1582116D02*
X1503727D01*
G01X1509749Y1582096D02*
X1504004D01*
G01X1503974Y1581919D02*
X1510058D01*
G01X1509023Y1597667D02*
X1509050Y1597671D01*
X1509075Y1597682D01*
X1509099Y1597700D01*
X1509121Y1597725D01*
X1509138Y1597755D01*
X1509150Y1597788D01*
X1509158Y1597825D01*
X1509161Y1597864D01*
G01X1509023Y1594518D02*
X1509050Y1594521D01*
X1509075Y1594532D01*
X1509099Y1594551D01*
X1509121Y1594575D01*
X1509138Y1594605D01*
X1509150Y1594639D01*
X1509158Y1594676D01*
X1509161Y1594714D01*
G01X1509023Y1591368D02*
X1509050Y1591372D01*
X1509075Y1591383D01*
X1509099Y1591401D01*
X1509121Y1591426D01*
X1509138Y1591455D01*
X1509150Y1591489D01*
X1509158Y1591526D01*
X1509161Y1591565D01*
G01X1509023Y1588218D02*
X1509050Y1588222D01*
X1509075Y1588233D01*
X1509099Y1588251D01*
X1509121Y1588276D01*
X1509138Y1588306D01*
X1509150Y1588340D01*
X1509158Y1588376D01*
X1509161Y1588415D01*
G01X1509023Y1585069D02*
X1509050Y1585073D01*
X1509075Y1585084D01*
X1509099Y1585102D01*
X1509121Y1585126D01*
X1509138Y1585156D01*
X1509150Y1585190D01*
X1509158Y1585227D01*
X1509161Y1585266D01*
G01X1509023Y1581919D02*
X1509050Y1581923D01*
X1509075Y1581934D01*
X1509099Y1581952D01*
X1509121Y1581977D01*
X1509138Y1582007D01*
X1509150Y1582040D01*
X1509158Y1582077D01*
X1509161Y1582116D01*
G01X1509023Y1578770D02*
X1509050Y1578773D01*
X1509075Y1578784D01*
X1509099Y1578802D01*
X1509121Y1578827D01*
X1509138Y1578857D01*
X1509150Y1578891D01*
X1509158Y1578928D01*
X1509161Y1578966D01*
G01X1508945Y1622370D02*
X1508974Y1622366D01*
X1509001Y1622355D01*
X1509027Y1622337D01*
X1509049Y1622312D01*
X1509068Y1622282D01*
X1509081Y1622249D01*
X1509090Y1622212D01*
X1509093Y1622173D01*
G01X1508945Y1619220D02*
X1508974Y1619216D01*
X1509001Y1619205D01*
X1509027Y1619187D01*
X1509049Y1619163D01*
X1509068Y1619133D01*
X1509081Y1619099D01*
X1509090Y1619062D01*
X1509093Y1619023D01*
G01X1508945Y1616071D02*
X1508974Y1616067D01*
X1509001Y1616056D01*
X1509027Y1616038D01*
X1509049Y1616013D01*
X1509068Y1615983D01*
X1509081Y1615949D01*
X1509090Y1615913D01*
X1509093Y1615874D01*
G01X1508945Y1612921D02*
X1508974Y1612917D01*
X1509001Y1612906D01*
X1509027Y1612888D01*
X1509049Y1612863D01*
X1509068Y1612834D01*
X1509081Y1612800D01*
X1509090Y1612763D01*
X1509093Y1612724D01*
G01X1508945Y1609771D02*
X1508974Y1609768D01*
X1509001Y1609757D01*
X1509027Y1609738D01*
X1509049Y1609714D01*
X1509068Y1609684D01*
X1509081Y1609650D01*
X1509090Y1609613D01*
X1509093Y1609575D01*
G01X1508945Y1606622D02*
X1508974Y1606618D01*
X1509001Y1606607D01*
X1509027Y1606589D01*
X1509049Y1606564D01*
X1509068Y1606534D01*
X1509081Y1606501D01*
X1509090Y1606464D01*
X1509093Y1606425D01*
G01X1510176Y1581506D02*
X1503590D01*
G01Y1581112D02*
X1510176D01*
G01X1504004Y1580522D02*
X1509749D01*
G01X1503974Y1579557D02*
X1510058D01*
G01X1503727Y1579360D02*
X1510338D01*
G01Y1578966D02*
X1503727D01*
G01X1503974Y1578770D02*
X1510058D01*
G01X1508572Y1645699D02*
X1508610Y1645672D01*
X1508638Y1645600D01*
X1508648Y1645502D01*
G01X1508572Y1642549D02*
X1508610Y1642523D01*
X1508638Y1642451D01*
X1508648Y1642352D01*
G01X1508572Y1639400D02*
X1508610Y1639373D01*
X1508638Y1639301D01*
X1508648Y1639203D01*
G01X1508572Y1636250D02*
X1508610Y1636223D01*
X1508638Y1636151D01*
X1508648Y1636053D01*
G01X1508572Y1633100D02*
X1508610Y1633074D01*
X1508638Y1633002D01*
X1508648Y1632903D01*
G01X1508572Y1629951D02*
X1508610Y1629924D01*
X1508638Y1629852D01*
X1508648Y1629754D01*
G01X1508572Y1626801D02*
X1508610Y1626775D01*
X1508638Y1626703D01*
X1508648Y1626604D01*
G01X1508572Y1623651D02*
X1508610Y1623625D01*
X1508638Y1623553D01*
X1508648Y1623455D01*
G01X1508572Y1620502D02*
X1508610Y1620475D01*
X1508638Y1620403D01*
X1508648Y1620305D01*
G01X1508572Y1617352D02*
X1508610Y1617326D01*
X1508638Y1617254D01*
X1508648Y1617155D01*
G01X1508572Y1614203D02*
X1508610Y1614176D01*
X1508638Y1614104D01*
X1508648Y1614006D01*
G01X1508572Y1611053D02*
X1508610Y1611027D01*
X1508638Y1610955D01*
X1508648Y1610856D01*
G01X1508572Y1607903D02*
X1508610Y1607877D01*
X1508638Y1607805D01*
X1508648Y1607707D01*
G01X1508572Y1604754D02*
X1508610Y1604727D01*
X1508638Y1604655D01*
X1508648Y1604557D01*
G01X1508572Y1601604D02*
X1508610Y1601578D01*
X1508638Y1601506D01*
X1508648Y1601407D01*
G01X1508572Y1598455D02*
X1508610Y1598428D01*
X1508638Y1598356D01*
X1508648Y1598258D01*
G01X1508572Y1595305D02*
X1508610Y1595279D01*
X1508638Y1595207D01*
X1508648Y1595108D01*
G01X1507908Y1622370D02*
X1507914Y1622366D01*
X1507920Y1622355D01*
X1507926Y1622337D01*
X1507931Y1622312D01*
X1507935Y1622282D01*
X1507938Y1622249D01*
X1507940Y1622212D01*
X1507941Y1622173D01*
G01X1507908Y1619220D02*
X1507914Y1619216D01*
X1507920Y1619205D01*
X1507926Y1619187D01*
X1507931Y1619163D01*
X1507935Y1619133D01*
X1507938Y1619099D01*
X1507940Y1619062D01*
X1507941Y1619023D01*
G01X1507908Y1616071D02*
X1507914Y1616067D01*
X1507920Y1616056D01*
X1507926Y1616038D01*
X1507931Y1616013D01*
X1507935Y1615983D01*
X1507938Y1615949D01*
X1507940Y1615913D01*
X1507941Y1615874D01*
G01X1507908Y1612921D02*
X1507914Y1612917D01*
X1507920Y1612906D01*
X1507926Y1612888D01*
X1507931Y1612863D01*
X1507935Y1612834D01*
X1507938Y1612800D01*
X1507940Y1612763D01*
X1507941Y1612724D01*
G01X1507908Y1609771D02*
X1507914Y1609768D01*
X1507920Y1609757D01*
X1507926Y1609738D01*
X1507931Y1609714D01*
X1507935Y1609684D01*
X1507938Y1609650D01*
X1507940Y1609613D01*
X1507941Y1609575D01*
G01X1507908Y1606622D02*
X1507914Y1606618D01*
X1507920Y1606607D01*
X1507926Y1606589D01*
X1507931Y1606564D01*
X1507935Y1606534D01*
X1507938Y1606501D01*
X1507940Y1606464D01*
X1507941Y1606425D01*
G01X1508572Y1592155D02*
X1508610Y1592129D01*
X1508638Y1592057D01*
X1508648Y1591959D01*
G01X1508572Y1589006D02*
X1508610Y1588979D01*
X1508638Y1588907D01*
X1508648Y1588809D01*
G01X1508572Y1585856D02*
X1508610Y1585830D01*
X1508638Y1585758D01*
X1508648Y1585659D01*
G01X1508572Y1582707D02*
X1508610Y1582680D01*
X1508638Y1582608D01*
X1508648Y1582510D01*
G01X1508572Y1579557D02*
X1508610Y1579531D01*
X1508638Y1579458D01*
X1508648Y1579360D01*
G01X1501709Y1623573D02*
X1499740Y1625541D01*
G01X1503499Y1626112D02*
X1503633Y1625915D01*
X1503768Y1625718D01*
X1503904Y1625522D01*
G01X1503499Y1601112D02*
X1503633Y1600915D01*
X1503768Y1600718D01*
X1503904Y1600522D01*
G01X1503590Y1646112D02*
X1503727Y1645914D01*
X1503865Y1645718D01*
X1504004Y1645522D01*
G01X1503590Y1641112D02*
X1503727Y1640914D01*
X1503865Y1640718D01*
X1504004Y1640522D01*
G01X1503590Y1636112D02*
X1503727Y1635914D01*
X1503865Y1635718D01*
X1504004Y1635522D01*
G01X1503590Y1631112D02*
X1503727Y1630914D01*
X1503865Y1630718D01*
X1504004Y1630522D01*
G01X1503590Y1596112D02*
X1503727Y1595914D01*
X1503865Y1595718D01*
X1504004Y1595522D01*
G01X1503590Y1591112D02*
X1503727Y1590914D01*
X1503865Y1590718D01*
X1504004Y1590522D01*
G01X1501621Y1586112D02*
X1501758Y1585914D01*
X1501896Y1585718D01*
X1502036Y1585522D01*
G01X1503590Y1581112D02*
X1503727Y1580914D01*
X1503865Y1580718D01*
X1504004Y1580522D01*
G01X1509817Y1627096D02*
X1510241Y1626506D01*
G01X1509817Y1602096D02*
X1510241Y1601506D01*
G01X1509749Y1647096D02*
X1510176Y1646506D01*
G01X1509749Y1642096D02*
X1510176Y1641506D01*
G01X1509749Y1637096D02*
X1510176Y1636506D01*
G01X1509749Y1632096D02*
X1510176Y1631506D01*
G01X1509749Y1597096D02*
X1510176Y1596506D01*
G01X1509749Y1592096D02*
X1510176Y1591506D01*
G01X1507781Y1587096D02*
X1508207Y1586506D01*
G01X1509749Y1582096D02*
X1510176Y1581506D01*
G01X1509060Y1647096D02*
X1509332Y1646506D01*
G01X1509060Y1642096D02*
X1509332Y1641506D01*
G01X1509060Y1637096D02*
X1509332Y1636506D01*
G01X1509060Y1632096D02*
X1509332Y1631506D01*
G01X1509060Y1627096D02*
X1509332Y1626506D01*
G01X1509060Y1602096D02*
X1509332Y1601506D01*
G01X1509060Y1597096D02*
X1509332Y1596506D01*
G01X1509060Y1592096D02*
X1509332Y1591506D01*
G01X1507091Y1587096D02*
X1507364Y1586506D01*
G01X1509060Y1582096D02*
X1509332Y1581506D01*
G01X1503727Y1648258D02*
X1503758Y1648161D01*
X1503847Y1648089D01*
X1503974Y1648061D01*
G01X1503727Y1645108D02*
X1503758Y1645011D01*
X1503847Y1644939D01*
X1503974Y1644911D01*
G01X1503727Y1641959D02*
X1503758Y1641862D01*
X1503847Y1641789D01*
X1503974Y1641762D01*
G01X1503727Y1638809D02*
X1503758Y1638712D01*
X1503847Y1638640D01*
X1503974Y1638612D01*
G01X1503727Y1635659D02*
X1503758Y1635562D01*
X1503847Y1635490D01*
X1503974Y1635463D01*
G01X1503727Y1632510D02*
X1503758Y1632413D01*
X1503847Y1632341D01*
X1503974Y1632313D01*
G01X1503727Y1629360D02*
X1503758Y1629263D01*
X1503847Y1629191D01*
X1503974Y1629163D01*
G01X1503727Y1626211D02*
X1503758Y1626114D01*
X1503847Y1626041D01*
X1503974Y1626014D01*
G01X1503727Y1623061D02*
X1503758Y1622964D01*
X1503847Y1622892D01*
X1503974Y1622864D01*
G01X1503727Y1619911D02*
X1503758Y1619814D01*
X1503847Y1619742D01*
X1503974Y1619714D01*
G01X1503727Y1616762D02*
X1503758Y1616665D01*
X1503847Y1616593D01*
X1503974Y1616565D01*
G01X1503727Y1613612D02*
X1503758Y1613515D01*
X1503847Y1613443D01*
X1503974Y1613415D01*
G01X1503727Y1610463D02*
X1503758Y1610365D01*
X1503847Y1610293D01*
X1503974Y1610266D01*
G01X1503727Y1607313D02*
X1503758Y1607216D01*
X1503847Y1607144D01*
X1503974Y1607116D01*
G01X1503727Y1604163D02*
X1503758Y1604066D01*
X1503847Y1603994D01*
X1503974Y1603966D01*
G01X1503727Y1601014D02*
X1503758Y1600917D01*
X1503847Y1600844D01*
X1503974Y1600817D01*
G01X1503727Y1597864D02*
X1503758Y1597767D01*
X1503847Y1597695D01*
X1503974Y1597667D01*
G01X1503727Y1594714D02*
X1503758Y1594617D01*
X1503847Y1594545D01*
X1503974Y1594518D01*
G01X1503727Y1591565D02*
X1503758Y1591468D01*
X1503847Y1591396D01*
X1503974Y1591368D01*
G01X1503727Y1588415D02*
X1503758Y1588318D01*
X1503847Y1588246D01*
X1503974Y1588218D01*
G01X1503727Y1585266D02*
X1503758Y1585169D01*
X1503847Y1585096D01*
X1503974Y1585069D01*
G01X1503727Y1582116D02*
X1503758Y1582019D01*
X1503847Y1581947D01*
X1503974Y1581919D01*
G01X1503727Y1578966D02*
X1503758Y1578869D01*
X1503847Y1578797D01*
X1503974Y1578770D01*
G01X1503717Y1621189D02*
X1503750Y1621090D01*
X1503838Y1621019D01*
X1503964Y1620992D01*
G01X1503717Y1618039D02*
X1503750Y1617940D01*
X1503838Y1617869D01*
X1503964Y1617842D01*
G01X1503717Y1614889D02*
X1503750Y1614790D01*
X1503838Y1614720D01*
X1503964Y1614693D01*
G01X1503717Y1611740D02*
X1503750Y1611641D01*
X1503838Y1611570D01*
X1503964Y1611543D01*
G01X1503717Y1608590D02*
X1503750Y1608491D01*
X1503838Y1608420D01*
X1503964Y1608393D01*
G01X1503717Y1605441D02*
X1503750Y1605342D01*
X1503838Y1605271D01*
X1503964Y1605244D01*
G01X1508208Y1646506D02*
X1508130Y1647096D01*
G01X1508208Y1641506D02*
X1508130Y1642096D01*
G01X1508208Y1636506D02*
X1508130Y1637096D01*
G01X1508208Y1631506D02*
X1508130Y1632096D01*
G01X1508208Y1626506D02*
X1508130Y1627096D01*
G01X1508208Y1601506D02*
X1508130Y1602096D01*
G01X1508208Y1596506D02*
X1508130Y1597096D01*
G01X1508208Y1591506D02*
X1508130Y1592096D01*
G01X1508208Y1581506D02*
X1508130Y1582096D01*
G01X1506239Y1586506D02*
X1506161Y1587096D01*
G01X1509161Y1645502D02*
X1509158Y1645540D01*
X1509151Y1645577D01*
X1509138Y1645611D01*
X1509121Y1645641D01*
X1509100Y1645665D01*
X1509076Y1645684D01*
X1509050Y1645695D01*
X1509023Y1645699D01*
G01X1509161Y1642352D02*
X1509158Y1642391D01*
X1509151Y1642427D01*
X1509138Y1642461D01*
X1509121Y1642491D01*
X1509100Y1642516D01*
X1509076Y1642534D01*
X1509050Y1642545D01*
X1509023Y1642549D01*
G01X1509161Y1639203D02*
X1509158Y1639241D01*
X1509151Y1639278D01*
X1509138Y1639312D01*
X1509121Y1639342D01*
X1509100Y1639366D01*
X1509076Y1639384D01*
X1509050Y1639396D01*
X1509023Y1639400D01*
G01X1509161Y1636053D02*
X1509158Y1636091D01*
X1509151Y1636128D01*
X1509138Y1636162D01*
X1509121Y1636192D01*
X1509100Y1636217D01*
X1509076Y1636235D01*
X1509050Y1636246D01*
X1509023Y1636250D01*
G01X1509161Y1632903D02*
X1509158Y1632942D01*
X1509151Y1632978D01*
X1509138Y1633012D01*
X1509121Y1633043D01*
X1509100Y1633067D01*
X1509076Y1633085D01*
X1509050Y1633096D01*
X1509023Y1633100D01*
G01X1509161Y1629754D02*
X1509158Y1629792D01*
X1509151Y1629829D01*
X1509138Y1629863D01*
X1509121Y1629893D01*
X1509100Y1629917D01*
X1509076Y1629936D01*
X1509050Y1629947D01*
X1509023Y1629951D01*
G01X1509161Y1626604D02*
X1509158Y1626642D01*
X1509151Y1626679D01*
X1509138Y1626713D01*
X1509121Y1626743D01*
X1509100Y1626768D01*
X1509076Y1626786D01*
X1509050Y1626797D01*
X1509023Y1626801D01*
G01X1509161Y1623455D02*
X1509158Y1623493D01*
X1509151Y1623530D01*
X1509138Y1623564D01*
X1509121Y1623594D01*
X1509100Y1623618D01*
X1509076Y1623636D01*
X1509050Y1623648D01*
X1509023Y1623651D01*
G01X1509161Y1620305D02*
X1509158Y1620343D01*
X1509151Y1620380D01*
X1509138Y1620414D01*
X1509121Y1620444D01*
X1509100Y1620469D01*
X1509076Y1620487D01*
X1509050Y1620498D01*
X1509023Y1620502D01*
G01X1509161Y1617155D02*
X1509158Y1617194D01*
X1509151Y1617230D01*
X1509138Y1617264D01*
X1509121Y1617295D01*
X1509100Y1617319D01*
X1509076Y1617337D01*
X1509050Y1617348D01*
X1509023Y1617352D01*
G01X1509161Y1614006D02*
X1509158Y1614044D01*
X1509151Y1614081D01*
X1509138Y1614115D01*
X1509121Y1614145D01*
X1509100Y1614169D01*
X1509076Y1614188D01*
X1509050Y1614199D01*
X1509023Y1614203D01*
G01X1509161Y1610856D02*
X1509158Y1610894D01*
X1509151Y1610931D01*
X1509138Y1610965D01*
X1509121Y1610995D01*
X1509100Y1611020D01*
X1509076Y1611038D01*
X1509050Y1611049D01*
X1509023Y1611053D01*
G01X1509161Y1607707D02*
X1509158Y1607745D01*
X1509151Y1607782D01*
X1509138Y1607816D01*
X1509121Y1607846D01*
X1509100Y1607870D01*
X1509076Y1607888D01*
X1509050Y1607900D01*
X1509023Y1607903D01*
G01X1509161Y1604557D02*
X1509158Y1604595D01*
X1509151Y1604632D01*
X1509138Y1604666D01*
X1509121Y1604696D01*
X1509100Y1604721D01*
X1509076Y1604739D01*
X1509050Y1604750D01*
X1509023Y1604754D01*
G01X1509161Y1601407D02*
X1509158Y1601446D01*
X1509151Y1601482D01*
X1509138Y1601516D01*
X1509121Y1601547D01*
X1509100Y1601571D01*
X1509076Y1601589D01*
X1509050Y1601600D01*
X1509023Y1601604D01*
G01X1509161Y1598258D02*
X1509158Y1598296D01*
X1509151Y1598333D01*
X1509138Y1598367D01*
X1509121Y1598397D01*
X1509100Y1598421D01*
X1509076Y1598440D01*
X1509050Y1598451D01*
X1509023Y1598455D01*
G01X1509161Y1595108D02*
X1509158Y1595146D01*
X1509151Y1595183D01*
X1509138Y1595217D01*
X1509121Y1595247D01*
X1509100Y1595272D01*
X1509076Y1595290D01*
X1509050Y1595301D01*
X1509023Y1595305D01*
G01X1509161Y1591959D02*
X1509158Y1591997D01*
X1509151Y1592034D01*
X1509138Y1592067D01*
X1509121Y1592098D01*
X1509100Y1592122D01*
X1509076Y1592140D01*
X1509050Y1592152D01*
X1509023Y1592155D01*
G01X1509161Y1588809D02*
X1509158Y1588847D01*
X1509151Y1588884D01*
X1509138Y1588918D01*
X1509121Y1588948D01*
X1509100Y1588973D01*
X1509076Y1588991D01*
X1509050Y1589002D01*
X1509023Y1589006D01*
G01X1509161Y1585659D02*
X1509158Y1585698D01*
X1509151Y1585734D01*
X1509138Y1585768D01*
X1509121Y1585799D01*
X1509100Y1585823D01*
X1509076Y1585841D01*
X1509050Y1585852D01*
X1509023Y1585856D01*
G01X1509161Y1582510D02*
X1509158Y1582548D01*
X1509151Y1582585D01*
X1509138Y1582619D01*
X1509121Y1582649D01*
X1509100Y1582673D01*
X1509076Y1582691D01*
X1509050Y1582703D01*
X1509023Y1582707D01*
G01X1509161Y1579360D02*
X1509158Y1579398D01*
X1509151Y1579435D01*
X1509138Y1579469D01*
X1509121Y1579499D01*
X1509100Y1579524D01*
X1509076Y1579542D01*
X1509050Y1579553D01*
X1509023Y1579557D01*
G01X1508208Y1581112D02*
X1508130Y1580522D01*
G01X1508208Y1591112D02*
X1508130Y1590522D01*
G01X1508208Y1596112D02*
X1508130Y1595522D01*
G01X1506239Y1586112D02*
X1506161Y1585522D01*
G01X1508208Y1601112D02*
X1508130Y1600522D01*
G01X1508208Y1626112D02*
X1508130Y1625522D01*
G01X1508208Y1631112D02*
X1508130Y1630522D01*
G01X1508208Y1636112D02*
X1508130Y1635522D01*
G01X1508208Y1641112D02*
X1508130Y1640522D01*
G01X1508208Y1646112D02*
X1508130Y1645522D01*
G01X1508648Y1578966D02*
X1508638Y1578868D01*
X1508610Y1578796D01*
X1508572Y1578770D01*
G01X1508648Y1582116D02*
X1508638Y1582018D01*
X1508610Y1581946D01*
X1508572Y1581919D01*
G01X1508648Y1585266D02*
X1508638Y1585167D01*
X1508610Y1585095D01*
X1508572Y1585069D01*
G01X1508648Y1588415D02*
X1508638Y1588317D01*
X1508610Y1588245D01*
X1508572Y1588218D01*
G01X1508648Y1591565D02*
X1508638Y1591467D01*
X1508610Y1591394D01*
X1508572Y1591368D01*
G01X1508648Y1594714D02*
X1508638Y1594616D01*
X1508610Y1594544D01*
X1508572Y1594518D01*
G01X1508648Y1597864D02*
X1508638Y1597766D01*
X1508610Y1597694D01*
X1508572Y1597667D01*
G01X1508648Y1601014D02*
X1508638Y1600915D01*
X1508610Y1600843D01*
X1508572Y1600817D01*
G01X1508648Y1604163D02*
X1508638Y1604065D01*
X1508610Y1603993D01*
X1508572Y1603966D01*
G01X1508648Y1607313D02*
X1508638Y1607215D01*
X1508610Y1607142D01*
X1508572Y1607116D01*
G01X1508648Y1613612D02*
X1508638Y1613514D01*
X1508610Y1613442D01*
X1508572Y1613415D01*
G01X1508648Y1616762D02*
X1508638Y1616663D01*
X1508610Y1616591D01*
X1508572Y1616565D01*
G01X1508648Y1619911D02*
X1508638Y1619813D01*
X1508610Y1619741D01*
X1508572Y1619714D01*
G01X1508648Y1623061D02*
X1508638Y1622963D01*
X1508610Y1622891D01*
X1508572Y1622864D01*
G01X1508648Y1632510D02*
X1508638Y1632411D01*
X1508610Y1632339D01*
X1508572Y1632313D01*
G01X1508648Y1635659D02*
X1508638Y1635561D01*
X1508610Y1635489D01*
X1508572Y1635463D01*
G01X1508648Y1648258D02*
X1508638Y1648159D01*
X1508610Y1648087D01*
X1508572Y1648061D01*
G01X1509093Y1605441D02*
X1509090Y1605402D01*
X1509081Y1605366D01*
X1509068Y1605332D01*
X1509049Y1605301D01*
X1509027Y1605277D01*
X1509002Y1605259D01*
X1508974Y1605248D01*
X1508945Y1605244D01*
G01X1509093Y1608590D02*
X1509090Y1608552D01*
X1509081Y1608515D01*
X1509068Y1608481D01*
X1509049Y1608451D01*
X1509027Y1608427D01*
X1509002Y1608409D01*
X1508974Y1608397D01*
X1508945Y1608393D01*
G01X1509093Y1611740D02*
X1509090Y1611702D01*
X1509081Y1611665D01*
X1509068Y1611631D01*
X1509049Y1611601D01*
X1509027Y1611576D01*
X1509002Y1611558D01*
X1508974Y1611547D01*
X1508945Y1611543D01*
G01X1509093Y1614889D02*
X1509090Y1614851D01*
X1509081Y1614814D01*
X1509068Y1614781D01*
X1509049Y1614750D01*
X1509027Y1614726D01*
X1509002Y1614708D01*
X1508974Y1614697D01*
X1508945Y1614693D01*
G01X1509093Y1618039D02*
X1509090Y1618001D01*
X1509081Y1617964D01*
X1509068Y1617930D01*
X1509049Y1617900D01*
X1509027Y1617876D01*
X1509002Y1617857D01*
X1508974Y1617846D01*
X1508945Y1617842D01*
G01X1509093Y1621189D02*
X1509090Y1621150D01*
X1509081Y1621114D01*
X1509068Y1621080D01*
X1509049Y1621049D01*
X1509027Y1621025D01*
X1509002Y1621007D01*
X1508974Y1620996D01*
X1508945Y1620992D01*
G01X1507941Y1605441D02*
X1507940Y1605402D01*
X1507938Y1605366D01*
X1507935Y1605332D01*
X1507931Y1605301D01*
X1507926Y1605277D01*
X1507921Y1605259D01*
X1507915Y1605248D01*
X1507908Y1605244D01*
G01X1507941Y1608590D02*
X1507940Y1608552D01*
X1507938Y1608515D01*
X1507935Y1608481D01*
X1507931Y1608451D01*
X1507926Y1608427D01*
X1507921Y1608409D01*
X1507915Y1608397D01*
X1507908Y1608393D01*
G01X1507941Y1611740D02*
X1507940Y1611702D01*
X1507938Y1611665D01*
X1507935Y1611631D01*
X1507931Y1611601D01*
X1507926Y1611576D01*
X1507921Y1611558D01*
X1507915Y1611547D01*
X1507908Y1611543D01*
G01X1507941Y1614889D02*
X1507940Y1614851D01*
X1507938Y1614814D01*
X1507935Y1614781D01*
X1507931Y1614750D01*
X1507926Y1614726D01*
X1507921Y1614708D01*
X1507915Y1614697D01*
X1507908Y1614693D01*
G01X1507941Y1618039D02*
X1507940Y1618001D01*
X1507938Y1617964D01*
X1507935Y1617930D01*
X1507931Y1617900D01*
X1507926Y1617876D01*
X1507921Y1617857D01*
X1507915Y1617846D01*
X1507908Y1617842D01*
G01X1507941Y1621189D02*
X1507940Y1621150D01*
X1507938Y1621114D01*
X1507935Y1621080D01*
X1507931Y1621049D01*
X1507926Y1621025D01*
X1507921Y1621007D01*
X1507915Y1620996D01*
X1507908Y1620992D01*
G01X1510338Y1641959D02*
Y1642352D01*
G01Y1645108D02*
Y1645502D01*
G01Y1638809D02*
Y1639203D01*
G01Y1632510D02*
Y1632903D01*
G01Y1635659D02*
Y1636053D01*
G01Y1629360D02*
Y1629754D01*
G01Y1626211D02*
Y1626604D01*
G01Y1623061D02*
Y1623455D01*
G01Y1619911D02*
Y1620305D01*
G01Y1613612D02*
Y1614006D01*
G01Y1616762D02*
Y1617155D01*
G01Y1610463D02*
Y1610856D01*
G01Y1604163D02*
Y1604557D01*
G01Y1607313D02*
Y1607707D01*
G01Y1601014D02*
Y1601407D01*
G01Y1594714D02*
Y1595108D01*
G01Y1597864D02*
Y1598258D01*
G01Y1591565D02*
Y1591959D01*
G01Y1588415D02*
Y1588809D01*
G01Y1582116D02*
Y1582510D01*
G01Y1585266D02*
Y1585659D01*
G01Y1578966D02*
Y1579360D01*
G01X1510241Y1601506D02*
Y1601112D01*
G01Y1626506D02*
Y1626112D01*
G01X1510176Y1581506D02*
Y1581112D01*
G01Y1591506D02*
Y1591112D01*
G01Y1596506D02*
Y1596112D01*
G01Y1631506D02*
Y1631112D01*
G01Y1636506D02*
Y1636112D01*
G01Y1641506D02*
Y1641112D01*
G01Y1646506D02*
Y1646112D01*
G01X1510035Y1606425D02*
Y1605441D01*
G01Y1612724D02*
Y1611740D01*
G01Y1609575D02*
Y1608590D01*
G01Y1615874D02*
Y1614889D01*
G01Y1622173D02*
Y1621189D01*
G01Y1619023D02*
Y1618039D01*
G01X1509332Y1581506D02*
Y1581112D01*
G01Y1591506D02*
Y1591112D01*
G01Y1596506D02*
Y1596112D01*
G01Y1601506D02*
Y1601112D01*
G01Y1626506D02*
Y1626112D01*
G01Y1631506D02*
Y1631112D01*
G01Y1636506D02*
Y1636112D01*
G01Y1641506D02*
Y1641112D01*
G01Y1646506D02*
Y1646112D01*
G01X1509161Y1641959D02*
Y1642352D01*
G01Y1645108D02*
Y1645502D01*
G01Y1638809D02*
Y1639203D01*
G01Y1632510D02*
Y1632903D01*
G01Y1635659D02*
Y1636053D01*
G01Y1629360D02*
Y1629754D01*
G01Y1626211D02*
Y1626604D01*
G01Y1623061D02*
Y1623455D01*
G01Y1619911D02*
Y1620305D01*
G01Y1613612D02*
Y1614006D01*
G01Y1616762D02*
Y1617155D01*
G01Y1610463D02*
Y1610856D01*
G01Y1604163D02*
Y1604557D01*
G01Y1607313D02*
Y1607707D01*
G01Y1601014D02*
Y1601407D01*
G01Y1594714D02*
Y1595108D01*
G01Y1597864D02*
Y1598258D01*
G01Y1591565D02*
Y1591959D01*
G01Y1588415D02*
Y1588809D01*
G01Y1582116D02*
Y1582510D01*
G01Y1585266D02*
Y1585659D01*
G01Y1578966D02*
Y1579360D01*
G01X1509093Y1606425D02*
Y1605441D01*
G01Y1612724D02*
Y1611740D01*
G01Y1609575D02*
Y1608590D01*
G01Y1615874D02*
Y1614889D01*
G01Y1622173D02*
Y1621189D01*
G01Y1619023D02*
Y1618039D01*
G01X1508648Y1579360D02*
Y1578966D01*
G01Y1582510D02*
Y1582116D01*
G01Y1585659D02*
Y1585266D01*
G01Y1588809D02*
Y1588415D01*
G01Y1591959D02*
Y1591565D01*
G01Y1595108D02*
Y1594714D01*
G01Y1598258D02*
Y1597864D01*
G01Y1601407D02*
Y1601014D01*
G01Y1604557D02*
Y1604163D01*
G01Y1607707D02*
Y1607313D01*
G01Y1610856D02*
Y1610463D01*
G01Y1614006D02*
Y1613612D01*
G01Y1617155D02*
Y1616762D01*
G01Y1620305D02*
Y1619911D01*
G01Y1626604D02*
Y1626211D01*
G01Y1623455D02*
Y1623061D01*
G01Y1629754D02*
Y1629360D01*
G01Y1632903D02*
Y1632510D01*
G01Y1636053D02*
Y1635659D01*
G01Y1639203D02*
Y1638809D01*
G01Y1642352D02*
Y1641959D01*
G01Y1645502D02*
Y1645108D01*
G01X1508208Y1646112D02*
Y1646506D01*
G01Y1641112D02*
Y1641506D01*
G01Y1636112D02*
Y1636506D01*
G01Y1631112D02*
Y1631506D01*
G01Y1626112D02*
Y1626506D01*
G01Y1601112D02*
Y1601506D01*
G01Y1596112D02*
Y1596506D01*
G01Y1591112D02*
Y1591506D01*
G01Y1581112D02*
Y1581506D01*
G01X1508207Y1586506D02*
Y1586112D01*
G01X1507941Y1606425D02*
Y1605441D01*
G01Y1612724D02*
Y1611740D01*
G01Y1609575D02*
Y1608590D01*
G01Y1615874D02*
Y1614889D01*
G01Y1622173D02*
Y1621189D01*
G01Y1619023D02*
Y1618039D01*
G01X1507364Y1586506D02*
Y1586112D01*
G01X1506239D02*
Y1586506D01*
G01X1506209Y1623553D02*
Y1624734D01*
G01Y1602884D02*
Y1604065D01*
G01X1503727Y1579360D02*
Y1578966D01*
G01Y1582510D02*
Y1582116D01*
G01Y1585659D02*
Y1585266D01*
G01Y1588809D02*
Y1588415D01*
G01Y1591959D02*
Y1591565D01*
G01Y1595108D02*
Y1594714D01*
G01Y1598258D02*
Y1597864D01*
G01Y1601407D02*
Y1601014D01*
G01Y1604557D02*
Y1604163D01*
G01Y1607707D02*
Y1607313D01*
G01Y1610856D02*
Y1610463D01*
G01Y1614006D02*
Y1613612D01*
G01Y1617155D02*
Y1616762D01*
G01Y1620305D02*
Y1619911D01*
G01Y1626604D02*
Y1626211D01*
G01Y1623455D02*
Y1623061D01*
G01Y1629754D02*
Y1629360D01*
G01Y1632903D02*
Y1632510D01*
G01Y1636053D02*
Y1635659D01*
G01Y1639203D02*
Y1638809D01*
G01Y1642352D02*
Y1641959D01*
G01Y1645502D02*
Y1645108D01*
G01X1503717Y1621189D02*
Y1622173D01*
G01Y1618039D02*
Y1619023D01*
G01Y1614889D02*
Y1615874D01*
G01Y1611740D02*
Y1612724D01*
G01Y1608590D02*
Y1609575D01*
G01Y1605441D02*
Y1606425D01*
G01X1503590Y1646112D02*
Y1646506D01*
G01Y1641112D02*
Y1641506D01*
G01Y1636112D02*
Y1636506D01*
G01Y1631112D02*
Y1631506D01*
G01Y1596112D02*
Y1596506D01*
G01Y1591112D02*
Y1591506D01*
G01Y1581112D02*
Y1581506D01*
G01X1503499Y1626112D02*
Y1626506D01*
G01Y1601112D02*
Y1601506D01*
G01X1501621Y1586112D02*
Y1586506D01*
G01X1500921Y1629911D02*
Y1660915D01*
G01Y1624734D02*
Y1602884D01*
G01X1500751Y1624530D02*
Y1629911D01*
G01Y1597608D02*
Y1603088D01*
G01X1508572Y1610266D02*
X1508610Y1610292D01*
X1508638Y1610364D01*
X1508648Y1610463D01*
G01X1508572Y1626014D02*
X1508610Y1626040D01*
X1508638Y1626112D01*
X1508648Y1626211D01*
G01X1508572Y1629163D02*
X1508610Y1629190D01*
X1508638Y1629262D01*
X1508648Y1629360D01*
G01X1508572Y1638612D02*
X1508610Y1638639D01*
X1508638Y1638711D01*
X1508648Y1638809D01*
G01X1508572Y1641762D02*
X1508610Y1641788D01*
X1508638Y1641860D01*
X1508648Y1641959D01*
G01X1508572Y1644911D02*
X1508610Y1644938D01*
X1508638Y1645010D01*
X1508648Y1645108D01*
G01X1499740Y1602077D02*
X1501709Y1604045D01*
G01X1509749Y1580522D02*
X1510176Y1581112D01*
G01X1507781Y1585522D02*
X1508207Y1586112D01*
G01X1509749Y1590522D02*
X1510176Y1591112D01*
G01X1509749Y1595522D02*
X1510176Y1596112D01*
G01X1509749Y1630522D02*
X1510176Y1631112D01*
G01X1509749Y1635522D02*
X1510176Y1636112D01*
G01X1509749Y1640522D02*
X1510176Y1641112D01*
G01X1509749Y1645522D02*
X1510176Y1646112D01*
G01X1509817Y1600522D02*
X1510241Y1601112D01*
G01X1509817Y1625522D02*
X1510241Y1626112D01*
G01X1504004Y1582096D02*
X1503865Y1581900D01*
X1503727Y1581703D01*
X1503590Y1581506D01*
G01X1502036Y1587096D02*
X1501896Y1586900D01*
X1501758Y1586703D01*
X1501621Y1586506D01*
G01X1504004Y1592096D02*
X1503865Y1591900D01*
X1503727Y1591703D01*
X1503590Y1591506D01*
G01X1504004Y1597096D02*
X1503865Y1596900D01*
X1503727Y1596703D01*
X1503590Y1596506D01*
G01X1504004Y1632096D02*
X1503865Y1631900D01*
X1503727Y1631703D01*
X1503590Y1631506D01*
G01X1504004Y1637096D02*
X1503865Y1636900D01*
X1503727Y1636703D01*
X1503590Y1636506D01*
G01X1504004Y1642096D02*
X1503865Y1641900D01*
X1503727Y1641703D01*
X1503590Y1641506D01*
G01X1504004Y1647096D02*
X1503865Y1646900D01*
X1503727Y1646703D01*
X1503590Y1646506D01*
G01X1503904Y1602096D02*
X1503768Y1601900D01*
X1503633Y1601703D01*
X1503499Y1601506D01*
G01X1503904Y1627096D02*
X1503768Y1626900D01*
X1503633Y1626703D01*
X1503499Y1626506D01*
G01X1509332Y1581112D02*
X1509060Y1580522D01*
G01X1507364Y1586112D02*
X1507091Y1585522D01*
G01X1509332Y1591112D02*
X1509060Y1590522D01*
G01X1509332Y1596112D02*
X1509060Y1595522D01*
G01X1509332Y1601112D02*
X1509060Y1600522D01*
G01X1509332Y1626112D02*
X1509060Y1625522D01*
G01X1509332Y1631112D02*
X1509060Y1630522D01*
G01X1509332Y1636112D02*
X1509060Y1635522D01*
G01X1509332Y1641112D02*
X1509060Y1640522D01*
G01X1509332Y1646112D02*
X1509060Y1645522D01*
G01X1531551Y1577490D02*
G03X1531945Y1577096I394J0D01*
G01X1534976Y1577884D02*
X1533992D01*
G01X1534976Y1577687D02*
X1533992D01*
G01X1534976Y1577293D02*
X1533992D01*
G01X1531945Y1577096D02*
X1539110D01*
G01X1542605Y1576407D02*
X1549937D01*
G01X1542457D02*
X1530449D01*
G01X1542457Y1575620D02*
X1530449D01*
G01X1549937D02*
X1542605D01*
G01X1531945Y1575522D02*
X1539110D01*
G01X1549937Y1576407D02*
Y1575620D01*
G01X1548163Y1576407D02*
Y1575620D01*
G01X1547975D02*
Y1576407D01*
G01X1545138Y1575620D02*
Y1576407D01*
G01X1544197D02*
Y1575620D01*
G01X1542605Y1576407D02*
Y1575620D01*
G01X1542457Y1576407D02*
Y1575620D01*
G01X1541519Y1576407D02*
Y1578770D01*
G01X1539791Y1576407D02*
Y1575620D01*
G01X1539110Y1575522D02*
Y1577096D01*
G01X1538139Y1575620D02*
Y1576407D01*
G01X1536156Y1575620D02*
Y1576407D01*
G01X1535961Y1577096D02*
Y1575522D01*
G01X1533008Y1577096D02*
Y1575522D01*
G01X1532793Y1576407D02*
Y1575620D01*
G01X1532417Y1576407D02*
Y1575620D01*
G01X1532391Y1576407D02*
Y1575620D01*
G01X1531945Y1625522D02*
G03X1531551Y1625128I0J-394D01*
G01Y1627490D02*
G03X1531945Y1627096I394J0D01*
G01Y1630522D02*
G03X1531551Y1630128I0J-394D01*
G01Y1632490D02*
G03X1531945Y1632096I394J0D01*
G01Y1635522D02*
G03X1531551Y1635128I0J-394D01*
G01Y1637490D02*
G03X1531945Y1637096I394J0D01*
G01Y1645522D02*
G03X1531551Y1645128I0J-394D01*
G01Y1647490D02*
G03X1531945Y1647096I394J0D01*
G01Y1640522D02*
G03X1531551Y1640128I0J-394D01*
G01Y1642490D02*
G03X1531945Y1642096I394J0D01*
G01Y1580522D02*
G03X1531551Y1580128I0J-394D01*
G01Y1582490D02*
G03X1531945Y1582096I394J0D01*
G01Y1595522D02*
G03X1531551Y1595128I0J-394D01*
G01Y1597490D02*
G03X1531945Y1597096I394J0D01*
G01Y1590522D02*
G03X1531551Y1590128I0J-394D01*
G01Y1592490D02*
G03X1531945Y1592096I394J0D01*
G01Y1600522D02*
G03X1531551Y1600128I0J-394D01*
G01Y1602490D02*
G03X1531945Y1602096I394J0D01*
G01X1542457Y1648061D02*
X1530449D01*
G01X1549937D02*
X1542605D01*
G01X1534976Y1647884D02*
X1533992D01*
G01X1534976Y1647687D02*
X1533992D01*
G01X1534976Y1647293D02*
X1533992D01*
G01X1531945Y1647096D02*
X1539110D01*
G01X1542605Y1645699D02*
X1549937D01*
G01X1542457D02*
X1530449D01*
G01X1531945Y1645522D02*
X1539110D01*
G01X1534976Y1645325D02*
X1533992D01*
G01X1534976Y1644931D02*
X1533992D01*
G01X1542457Y1644911D02*
X1530449D01*
G01X1549937D02*
X1542605D01*
G01X1534976Y1644734D02*
X1533992D01*
G01X1534976Y1642884D02*
X1533992D01*
G01X1534976Y1642687D02*
X1533992D01*
G01X1542605Y1642549D02*
X1549937D01*
G01X1542457D02*
X1530449D01*
G01X1534976Y1642293D02*
X1533992D01*
G01X1531945Y1642096D02*
X1539110D01*
G01X1542457Y1641762D02*
X1530449D01*
G01X1549937D02*
X1542605D01*
G01X1531945Y1640522D02*
X1539110D01*
G01X1534976Y1640325D02*
X1533992D01*
G01X1534976Y1639931D02*
X1533992D01*
G01X1534976Y1639734D02*
X1533992D01*
G01X1542605Y1639400D02*
X1549937D01*
G01X1542457D02*
X1530449D01*
G01X1542457Y1638612D02*
X1530449D01*
G01X1549937D02*
X1542605D01*
G01X1534976Y1637884D02*
X1533992D01*
G01X1534976Y1637687D02*
X1533992D01*
G01X1534976Y1637293D02*
X1533992D01*
G01X1531945Y1637096D02*
X1539110D01*
G01X1542605Y1636250D02*
X1549937D01*
G01X1542457D02*
X1530449D01*
G01X1531945Y1635522D02*
X1539110D01*
G01X1542457Y1635463D02*
X1530449D01*
G01X1549937D02*
X1542605D01*
G01X1534976Y1635325D02*
X1533992D01*
G01X1534976Y1634931D02*
X1533992D01*
G01X1534976Y1634734D02*
X1533992D01*
G01X1542605Y1633100D02*
X1549937D01*
G01X1542457D02*
X1530449D01*
G01X1534976Y1632884D02*
X1533992D01*
G01X1534976Y1632687D02*
X1533992D01*
G01X1542457Y1632313D02*
X1530449D01*
G01X1549937D02*
X1542605D01*
G01X1534976Y1632293D02*
X1533992D01*
G01X1531945Y1632096D02*
X1539110D01*
G01X1531945Y1630522D02*
X1539110D01*
G01X1534976Y1630325D02*
X1533992D01*
G01X1542605Y1629951D02*
X1549937D01*
G01X1542457D02*
X1530449D01*
G01X1534976Y1629931D02*
X1533992D01*
G01X1534976Y1629734D02*
X1533992D01*
G01X1542457Y1629163D02*
X1530449D01*
G01X1549937D02*
X1542605D01*
G01X1534976Y1627884D02*
X1533992D01*
G01X1534976Y1627687D02*
X1533992D01*
G01X1534976Y1627293D02*
X1533992D01*
G01X1531945Y1627096D02*
X1539110D01*
G01X1542605Y1626801D02*
X1549937D01*
G01X1542457D02*
X1530449D01*
G01X1542457Y1626014D02*
X1530449D01*
G01X1549937D02*
X1542605D01*
G01X1531945Y1625522D02*
X1539110D01*
G01X1534976Y1625325D02*
X1533992D01*
G01X1534976Y1624931D02*
X1533992D01*
G01X1534976Y1624734D02*
X1533992D01*
G01X1542605Y1623651D02*
X1549937D01*
G01X1542457D02*
X1530449D01*
G01X1531551Y1623573D02*
X1530449D01*
G01Y1623455D02*
X1537984D01*
G01X1535567Y1622963D02*
X1533442D01*
G01X1542457Y1622864D02*
X1530449D01*
G01X1549937D02*
X1542605D01*
G01X1533442Y1622667D02*
X1532458D01*
G01X1533442Y1622470D02*
X1532458D01*
G01X1531551Y1622274D02*
X1537576D01*
G01X1531551Y1621092D02*
X1537576D01*
G01X1533442Y1620896D02*
X1532458D01*
G01X1533442Y1620699D02*
X1532458D01*
G01X1542605Y1620502D02*
X1549937D01*
G01X1542457D02*
X1530449D01*
G01X1542457Y1619714D02*
X1530449D01*
G01X1549937D02*
X1542605D01*
G01X1539440Y1619636D02*
X1537558D01*
G01X1533442Y1619518D02*
X1532458D01*
G01X1533442Y1619321D02*
X1532458D01*
G01X1531551Y1619124D02*
X1537576D01*
G01X1531551Y1617943D02*
X1537576D01*
G01X1533442Y1617746D02*
X1532458D01*
G01X1533442Y1617549D02*
X1532458D01*
G01X1539440Y1617431D02*
X1537558D01*
G01X1542605Y1617352D02*
X1549937D01*
G01X1542457D02*
X1530449D01*
G01X1542457Y1616565D02*
X1530449D01*
G01X1549937D02*
X1542605D01*
G01X1533442Y1616368D02*
X1532458D01*
G01X1533442Y1616171D02*
X1532458D01*
G01X1531551Y1615974D02*
X1537576D01*
G01X1531551Y1614793D02*
X1537576D01*
G01X1533442Y1614596D02*
X1532458D01*
G01X1533442Y1614400D02*
X1532458D01*
G01X1542605Y1614203D02*
X1549937D01*
G01X1542457D02*
X1530449D01*
G01X1542457Y1613415D02*
X1530449D01*
G01X1549937D02*
X1542605D01*
G01X1533442Y1613218D02*
X1532458D01*
G01X1533442Y1613022D02*
X1532458D01*
G01X1531551Y1612825D02*
X1537576D01*
G01X1531551Y1611644D02*
X1537576D01*
G01X1533442Y1611447D02*
X1532458D01*
G01X1533442Y1611250D02*
X1532458D01*
G01X1542605Y1611053D02*
X1549937D01*
G01X1542457D02*
X1530449D01*
G01X1542457Y1610266D02*
X1530449D01*
G01X1549937D02*
X1542605D01*
G01X1539440Y1610187D02*
X1537558D01*
G01X1533442Y1610069D02*
X1532458D01*
G01X1533442Y1609872D02*
X1532458D01*
G01X1531551Y1609675D02*
X1537576D01*
G01X1531551Y1608494D02*
X1537576D01*
G01X1533442Y1608297D02*
X1532458D01*
G01X1533442Y1608100D02*
X1532458D01*
G01X1539440Y1607982D02*
X1537558D01*
G01X1542605Y1607903D02*
X1549937D01*
G01X1542457D02*
X1530449D01*
G01X1542457Y1607116D02*
X1530449D01*
G01X1549937D02*
X1542605D01*
G01X1533442Y1606919D02*
X1532458D01*
G01X1533442Y1606722D02*
X1532458D01*
G01X1531551Y1606525D02*
X1537576D01*
G01X1531551Y1605344D02*
X1537576D01*
G01X1533442Y1605148D02*
X1532458D01*
G01X1533442Y1604951D02*
X1532458D01*
G01X1542605Y1604754D02*
X1549937D01*
G01X1542457D02*
X1530449D01*
G01X1533442Y1604655D02*
X1535567D01*
G01X1530449Y1604163D02*
X1537984D01*
G01X1531551Y1604045D02*
X1530449D01*
G01X1542457Y1603966D02*
X1530449D01*
G01X1549937D02*
X1542605D01*
G01X1534976Y1602884D02*
X1533992D01*
G01X1534976Y1602687D02*
X1533992D01*
G01X1534976Y1602293D02*
X1533992D01*
G01X1531945Y1602096D02*
X1539110D01*
G01X1542605Y1601604D02*
X1549937D01*
G01X1542457D02*
X1530449D01*
G01X1542457Y1600817D02*
X1530449D01*
G01X1549937D02*
X1542605D01*
G01X1531945Y1600522D02*
X1539110D01*
G01X1534976Y1600325D02*
X1533992D01*
G01X1534976Y1599931D02*
X1533992D01*
G01X1534976Y1599734D02*
X1533992D01*
G01X1542605Y1598455D02*
X1549937D01*
G01X1542457D02*
X1530449D01*
G01X1534976Y1597884D02*
X1533992D01*
G01X1534976Y1597687D02*
X1533992D01*
G01X1542457Y1597667D02*
X1530449D01*
G01X1549937D02*
X1542605D01*
G01X1534976Y1597293D02*
X1533992D01*
G01X1531945Y1597096D02*
X1539110D01*
G01X1531945Y1595522D02*
X1539110D01*
G01X1534976Y1595325D02*
X1533992D01*
G01X1542605Y1595305D02*
X1549937D01*
G01X1542457D02*
X1530449D01*
G01X1534976Y1594931D02*
X1533992D01*
G01X1534976Y1594734D02*
X1533992D01*
G01X1542457Y1594518D02*
X1530449D01*
G01X1549937D02*
X1542605D01*
G01X1534976Y1592884D02*
X1533992D01*
G01X1534976Y1592687D02*
X1533992D01*
G01X1534976Y1592293D02*
X1533992D01*
G01X1542605Y1592155D02*
X1549937D01*
G01X1542457D02*
X1530449D01*
G01X1531945Y1592096D02*
X1539110D01*
G01X1542457Y1591368D02*
X1530449D01*
G01X1549937D02*
X1542605D01*
G01X1531945Y1590522D02*
X1539110D01*
G01X1534976Y1590325D02*
X1533992D01*
G01X1534976Y1589931D02*
X1533992D01*
G01X1534976Y1589734D02*
X1533992D01*
G01X1542605Y1589006D02*
X1549937D01*
G01X1542457D02*
X1530449D01*
G01Y1588514D02*
X1531551D01*
G01X1542457Y1588218D02*
X1530449D01*
G01X1549937D02*
X1542605D01*
G01X1533008Y1587884D02*
X1532024D01*
G01X1533008Y1587687D02*
X1532024D01*
G01X1533008Y1587293D02*
X1532024D01*
G01X1531551Y1587096D02*
X1537142D01*
G01X1542605Y1585856D02*
X1549937D01*
G01X1542457D02*
X1530449D01*
G01X1531551Y1585522D02*
X1537142D01*
G01X1533008Y1585325D02*
X1532024D01*
G01X1542457Y1585069D02*
X1530449D01*
G01X1549937D02*
X1542605D01*
G01X1533008Y1584931D02*
X1532024D01*
G01X1533008Y1584734D02*
X1532024D01*
G01X1531551Y1584104D02*
X1530449D01*
G01X1534976Y1582884D02*
X1533992D01*
G01X1542605Y1582707D02*
X1549937D01*
G01X1542457D02*
X1530449D01*
G01X1534976Y1582687D02*
X1533992D01*
G01X1534976Y1582293D02*
X1533992D01*
G01X1531945Y1582096D02*
X1539110D01*
G01X1542457Y1581919D02*
X1530449D01*
G01X1549937D02*
X1542605D01*
G01X1531945Y1580522D02*
X1539110D01*
G01X1534976Y1580325D02*
X1533992D01*
G01X1534976Y1579931D02*
X1533992D01*
G01X1534976Y1579734D02*
X1533992D01*
G01X1542605Y1579557D02*
X1549937D01*
G01X1542457D02*
X1530449D01*
G01X1542457Y1578770D02*
X1530449D01*
G01X1549937D02*
X1542605D01*
G01X1549937Y1579557D02*
Y1578770D01*
G01Y1582707D02*
Y1581919D01*
G01Y1589006D02*
Y1588218D01*
G01Y1585856D02*
Y1585069D01*
G01Y1592155D02*
Y1591368D01*
G01Y1598455D02*
Y1597667D01*
G01Y1595305D02*
Y1594518D01*
G01Y1601604D02*
Y1600817D01*
G01Y1607903D02*
Y1607116D01*
G01Y1604754D02*
Y1603966D01*
G01Y1611053D02*
Y1610266D01*
G01Y1617352D02*
Y1616565D01*
G01Y1614203D02*
Y1613415D01*
G01Y1620502D02*
Y1619714D01*
G01Y1626801D02*
Y1626014D01*
G01Y1623651D02*
Y1622864D01*
G01Y1629951D02*
Y1629163D01*
G01Y1636250D02*
Y1635463D01*
G01Y1633100D02*
Y1632313D01*
G01Y1639400D02*
Y1638612D01*
G01Y1645699D02*
Y1644911D01*
G01Y1642549D02*
Y1641762D01*
G01Y1648848D02*
Y1648061D01*
G01X1548163Y1579557D02*
Y1578770D01*
G01Y1582707D02*
Y1581919D01*
G01Y1589006D02*
Y1588218D01*
G01Y1585856D02*
Y1585069D01*
G01Y1592155D02*
Y1591368D01*
G01Y1598455D02*
Y1597667D01*
G01Y1595305D02*
Y1594518D01*
G01Y1601604D02*
Y1600817D01*
G01Y1607903D02*
Y1607116D01*
G01Y1604754D02*
Y1603966D01*
G01Y1611053D02*
Y1610266D01*
G01Y1617352D02*
Y1616565D01*
G01Y1614203D02*
Y1613415D01*
G01Y1620502D02*
Y1619714D01*
G01Y1626801D02*
Y1626014D01*
G01Y1623651D02*
Y1622864D01*
G01Y1629951D02*
Y1629163D01*
G01Y1636250D02*
Y1635463D01*
G01Y1633100D02*
Y1632313D01*
G01Y1639400D02*
Y1638612D01*
G01Y1645699D02*
Y1644911D01*
G01Y1642549D02*
Y1641762D01*
G01Y1648848D02*
Y1648061D01*
G01X1547975D02*
Y1648848D01*
G01Y1644911D02*
Y1645699D01*
G01Y1641762D02*
Y1642549D01*
G01Y1638612D02*
Y1639400D01*
G01Y1635463D02*
Y1636250D01*
G01Y1632313D02*
Y1633100D01*
G01Y1629163D02*
Y1629951D01*
G01Y1626014D02*
Y1626801D01*
G01Y1622864D02*
Y1623651D01*
G01Y1619714D02*
Y1620502D01*
G01Y1616565D02*
Y1617352D01*
G01Y1613415D02*
Y1614203D01*
G01Y1610266D02*
Y1611053D01*
G01Y1607116D02*
Y1607903D01*
G01Y1603966D02*
Y1604754D01*
G01Y1600817D02*
Y1601604D01*
G01Y1597667D02*
Y1598455D01*
G01Y1594518D02*
Y1595305D01*
G01Y1591368D02*
Y1592155D01*
G01Y1588218D02*
Y1589006D01*
G01Y1585069D02*
Y1585856D01*
G01Y1581919D02*
Y1582707D01*
G01Y1578770D02*
Y1579557D01*
G01X1545138Y1648061D02*
Y1648848D01*
G01Y1644911D02*
Y1645699D01*
G01Y1641762D02*
Y1642549D01*
G01Y1638612D02*
Y1639400D01*
G01Y1635463D02*
Y1636250D01*
G01Y1632313D02*
Y1633100D01*
G01Y1629163D02*
Y1629951D01*
G01Y1626014D02*
Y1626801D01*
G01Y1622864D02*
Y1623651D01*
G01Y1619714D02*
Y1620502D01*
G01Y1616565D02*
Y1617352D01*
G01Y1613415D02*
Y1614203D01*
G01Y1610266D02*
Y1611053D01*
G01Y1607116D02*
Y1607903D01*
G01Y1603966D02*
Y1604754D01*
G01Y1600817D02*
Y1601604D01*
G01Y1597667D02*
Y1598455D01*
G01Y1594518D02*
Y1595305D01*
G01Y1591368D02*
Y1592155D01*
G01Y1588218D02*
Y1589006D01*
G01Y1585069D02*
Y1585856D01*
G01Y1581919D02*
Y1582707D01*
G01Y1578770D02*
Y1579557D01*
G01X1544197D02*
Y1578770D01*
G01Y1582707D02*
Y1581919D01*
G01Y1589006D02*
Y1588218D01*
G01Y1585856D02*
Y1585069D01*
G01Y1592155D02*
Y1591368D01*
G01Y1598455D02*
Y1597667D01*
G01Y1595305D02*
Y1594518D01*
G01Y1601604D02*
Y1600817D01*
G01Y1607903D02*
Y1607116D01*
G01Y1604754D02*
Y1603966D01*
G01Y1611053D02*
Y1610266D01*
G01Y1617352D02*
Y1616565D01*
G01Y1614203D02*
Y1613415D01*
G01Y1620502D02*
Y1619714D01*
G01Y1626801D02*
Y1626014D01*
G01Y1623651D02*
Y1622864D01*
G01Y1629951D02*
Y1629163D01*
G01Y1636250D02*
Y1635463D01*
G01Y1633100D02*
Y1632313D01*
G01Y1639400D02*
Y1638612D01*
G01Y1645699D02*
Y1644911D01*
G01Y1642549D02*
Y1641762D01*
G01Y1648848D02*
Y1648061D01*
G01X1542605Y1579557D02*
Y1578770D01*
G01Y1582707D02*
Y1581919D01*
G01Y1589006D02*
Y1588218D01*
G01Y1585856D02*
Y1585069D01*
G01Y1592155D02*
Y1591368D01*
G01Y1598455D02*
Y1597667D01*
G01Y1595305D02*
Y1594518D01*
G01Y1601604D02*
Y1600817D01*
G01Y1607903D02*
Y1607116D01*
G01Y1604754D02*
Y1603966D01*
G01Y1611053D02*
Y1610266D01*
G01Y1617352D02*
Y1616565D01*
G01Y1614203D02*
Y1613415D01*
G01Y1620502D02*
Y1619714D01*
G01Y1626801D02*
Y1626014D01*
G01Y1623651D02*
Y1622864D01*
G01Y1629951D02*
Y1629163D01*
G01Y1636250D02*
Y1635463D01*
G01Y1633100D02*
Y1632313D01*
G01Y1639400D02*
Y1638612D01*
G01Y1645699D02*
Y1644911D01*
G01Y1642549D02*
Y1641762D01*
G01Y1648848D02*
Y1648061D01*
G01X1542457Y1579557D02*
Y1578770D01*
G01Y1582707D02*
Y1581919D01*
G01Y1589006D02*
Y1588218D01*
G01Y1585856D02*
Y1585069D01*
G01Y1592155D02*
Y1591368D01*
G01Y1598455D02*
Y1597667D01*
G01Y1595305D02*
Y1594518D01*
G01Y1601604D02*
Y1600817D01*
G01Y1607903D02*
Y1607116D01*
G01Y1604754D02*
Y1603966D01*
G01Y1611053D02*
Y1610266D01*
G01Y1617352D02*
Y1616565D01*
G01Y1614203D02*
Y1613415D01*
G01Y1620502D02*
Y1619714D01*
G01Y1626801D02*
Y1626014D01*
G01Y1623651D02*
Y1622864D01*
G01Y1629951D02*
Y1629163D01*
G01Y1636250D02*
Y1635463D01*
G01Y1633100D02*
Y1632313D01*
G01Y1639400D02*
Y1638612D01*
G01Y1645699D02*
Y1644911D01*
G01Y1642549D02*
Y1641762D01*
G01Y1648848D02*
Y1648061D01*
G01X1541519Y1645699D02*
Y1648061D01*
G01Y1642549D02*
Y1644911D01*
G01Y1639400D02*
Y1641762D01*
G01Y1636250D02*
Y1638612D01*
G01Y1633100D02*
Y1635463D01*
G01Y1629951D02*
Y1632313D01*
G01Y1626801D02*
Y1629163D01*
G01Y1623651D02*
Y1626014D01*
G01Y1620502D02*
Y1622864D01*
G01Y1617352D02*
Y1619714D01*
G01Y1614203D02*
Y1616565D01*
G01Y1611053D02*
Y1613415D01*
G01Y1607903D02*
Y1610266D01*
G01Y1604754D02*
Y1607116D01*
G01Y1601604D02*
Y1603966D01*
G01Y1598455D02*
Y1600817D01*
G01Y1595305D02*
Y1597667D01*
G01Y1592155D02*
Y1594518D01*
G01Y1589006D02*
Y1591368D01*
G01Y1585856D02*
Y1588218D01*
G01Y1582707D02*
Y1585069D01*
G01Y1579557D02*
Y1581919D01*
G01X1539791Y1579557D02*
Y1578770D01*
G01Y1582707D02*
Y1581919D01*
G01Y1589006D02*
Y1588218D01*
G01Y1585856D02*
Y1585069D01*
G01Y1592155D02*
Y1591368D01*
G01Y1598455D02*
Y1597667D01*
G01Y1595305D02*
Y1594518D01*
G01Y1601604D02*
Y1600817D01*
G01Y1607903D02*
Y1607116D01*
G01Y1604754D02*
Y1603966D01*
G01Y1611053D02*
Y1610266D01*
G01Y1617352D02*
Y1616565D01*
G01Y1614203D02*
Y1613415D01*
G01Y1620502D02*
Y1619714D01*
G01Y1626801D02*
Y1626014D01*
G01Y1623651D02*
Y1622864D01*
G01Y1629951D02*
Y1629163D01*
G01Y1636250D02*
Y1635463D01*
G01Y1633100D02*
Y1632313D01*
G01Y1639400D02*
Y1638612D01*
G01Y1645699D02*
Y1644911D01*
G01Y1642549D02*
Y1641762D01*
G01Y1648848D02*
Y1648061D01*
G01X1539440Y1610187D02*
Y1607982D01*
G01Y1619636D02*
Y1617431D01*
G01X1539110Y1645522D02*
Y1647096D01*
G01Y1640522D02*
Y1642096D01*
G01Y1635522D02*
Y1637096D01*
G01Y1630522D02*
Y1632096D01*
G01Y1625522D02*
Y1627096D01*
G01Y1600522D02*
Y1602096D01*
G01Y1595522D02*
Y1597096D01*
G01Y1590522D02*
Y1592096D01*
G01Y1580522D02*
Y1582096D01*
G01X1538139Y1648061D02*
Y1648848D01*
G01Y1644911D02*
Y1645699D01*
G01Y1641762D02*
Y1642549D01*
G01Y1638612D02*
Y1639400D01*
G01Y1635463D02*
Y1636250D01*
G01Y1632313D02*
Y1633100D01*
G01Y1629163D02*
Y1629951D01*
G01Y1626014D02*
Y1626801D01*
G01Y1622864D02*
Y1623651D01*
G01Y1619714D02*
Y1620502D01*
G01Y1616565D02*
Y1617352D01*
G01Y1613415D02*
Y1614203D01*
G01Y1610266D02*
Y1611053D01*
G01Y1607116D02*
Y1607903D01*
G01Y1603966D02*
Y1604754D01*
G01Y1600817D02*
Y1601604D01*
G01Y1597667D02*
Y1598455D01*
G01Y1594518D02*
Y1595305D01*
G01Y1591368D02*
Y1592155D01*
G01Y1588218D02*
Y1589006D01*
G01Y1585069D02*
Y1585856D01*
G01Y1581919D02*
Y1582707D01*
G01Y1578770D02*
Y1579557D01*
G01X1537984Y1607982D02*
Y1604163D01*
G01Y1617431D02*
Y1610187D01*
G01Y1623455D02*
Y1619636D01*
G01X1537576Y1621092D02*
Y1622274D01*
G01Y1617943D02*
Y1619124D01*
G01Y1614793D02*
Y1615974D01*
G01Y1611644D02*
Y1612825D01*
G01Y1608494D02*
Y1609675D01*
G01Y1605344D02*
Y1606525D01*
G01X1537558Y1617431D02*
Y1619636D01*
G01Y1607982D02*
Y1610187D01*
G01X1537506Y1623455D02*
Y1604163D01*
G01X1537142Y1585522D02*
Y1587096D01*
G01X1536156Y1648061D02*
Y1648848D01*
G01Y1644911D02*
Y1645699D01*
G01Y1641762D02*
Y1642549D01*
G01Y1638612D02*
Y1639400D01*
G01Y1635463D02*
Y1636250D01*
G01Y1632313D02*
Y1633100D01*
G01Y1629163D02*
Y1629951D01*
G01Y1626014D02*
Y1626801D01*
G01Y1622864D02*
Y1623651D01*
G01Y1619714D02*
Y1620502D01*
G01Y1616565D02*
Y1617352D01*
G01Y1613415D02*
Y1614203D01*
G01Y1610266D02*
Y1611053D01*
G01Y1607116D02*
Y1607903D01*
G01Y1603966D02*
Y1604754D01*
G01Y1600817D02*
Y1601604D01*
G01Y1597667D02*
Y1598455D01*
G01Y1594518D02*
Y1595305D01*
G01Y1591368D02*
Y1592155D01*
G01Y1588218D02*
Y1589006D01*
G01Y1585069D02*
Y1585856D01*
G01Y1581919D02*
Y1582707D01*
G01Y1578770D02*
Y1579557D01*
G01X1535961Y1582096D02*
Y1580522D01*
G01Y1592096D02*
Y1590522D01*
G01Y1597096D02*
Y1595522D01*
G01Y1602096D02*
Y1600522D01*
G01Y1627096D02*
Y1625522D01*
G01Y1632096D02*
Y1630522D01*
G01Y1637096D02*
Y1635522D01*
G01Y1642096D02*
Y1640522D01*
G01Y1647096D02*
Y1645522D01*
G01X1534976Y1582884D02*
Y1579734D01*
G01Y1592884D02*
Y1589734D01*
G01Y1597884D02*
Y1594734D01*
G01Y1602884D02*
Y1599734D01*
G01Y1627884D02*
Y1624734D01*
G01Y1632884D02*
Y1629734D01*
G01Y1637884D02*
Y1634734D01*
G01Y1642884D02*
Y1639734D01*
G01Y1647884D02*
Y1644734D01*
G01X1534427Y1606525D02*
Y1605344D01*
G01Y1612825D02*
Y1611644D01*
G01Y1609675D02*
Y1608494D01*
G01Y1615974D02*
Y1614793D01*
G01Y1622274D02*
Y1621092D01*
G01Y1619124D02*
Y1617943D01*
G01X1534149Y1623455D02*
Y1604163D01*
G01X1533992Y1582884D02*
Y1579734D01*
G01Y1587096D02*
Y1585522D01*
G01Y1592884D02*
Y1589734D01*
G01Y1597884D02*
Y1594734D01*
G01Y1602884D02*
Y1599734D01*
G01Y1627884D02*
Y1624734D01*
G01Y1632884D02*
Y1629734D01*
G01Y1637884D02*
Y1634734D01*
G01Y1642884D02*
Y1639734D01*
G01Y1647884D02*
Y1644734D01*
G01X1533442Y1622963D02*
Y1604655D01*
G01X1533232Y1604163D02*
Y1623455D01*
G01X1533008Y1582096D02*
Y1580522D01*
G01Y1587884D02*
Y1584734D01*
G01Y1592096D02*
Y1590522D01*
G01Y1597096D02*
Y1595522D01*
G01Y1602096D02*
Y1600522D01*
G01Y1627096D02*
Y1625522D01*
G01Y1632096D02*
Y1630522D01*
G01Y1637096D02*
Y1635522D01*
G01Y1642096D02*
Y1640522D01*
G01Y1647096D02*
Y1645522D01*
G01X1532793Y1579557D02*
Y1578770D01*
G01Y1582707D02*
Y1581919D01*
G01Y1589006D02*
Y1588218D01*
G01Y1585856D02*
Y1585069D01*
G01Y1592155D02*
Y1591368D01*
G01Y1598455D02*
Y1597667D01*
G01Y1595305D02*
Y1594518D01*
G01Y1601604D02*
Y1600817D01*
G01Y1607903D02*
Y1607116D01*
G01Y1604754D02*
Y1603966D01*
G01Y1611053D02*
Y1610266D01*
G01Y1617352D02*
Y1616565D01*
G01Y1614203D02*
Y1613415D01*
G01Y1620502D02*
Y1619714D01*
G01Y1626801D02*
Y1626014D01*
G01Y1623651D02*
Y1622864D01*
G01Y1629951D02*
Y1629163D01*
G01Y1636250D02*
Y1635463D01*
G01Y1633100D02*
Y1632313D01*
G01Y1639400D02*
Y1638612D01*
G01Y1645699D02*
Y1644911D01*
G01Y1642549D02*
Y1641762D01*
G01Y1648848D02*
Y1648061D01*
G01X1532732Y1623455D02*
Y1604163D01*
G01X1532458Y1607116D02*
Y1604754D01*
G01Y1613415D02*
Y1611053D01*
G01Y1610266D02*
Y1607903D01*
G01Y1616565D02*
Y1614203D01*
G01Y1622864D02*
Y1620502D01*
G01Y1619714D02*
Y1617352D01*
G01X1532417Y1579557D02*
Y1578770D01*
G01Y1582707D02*
Y1581919D01*
G01Y1589006D02*
Y1588218D01*
G01Y1585856D02*
Y1585069D01*
G01Y1592155D02*
Y1591368D01*
G01Y1598455D02*
Y1597667D01*
G01Y1595305D02*
Y1594518D01*
G01Y1601604D02*
Y1600817D01*
G01Y1607903D02*
Y1607116D01*
G01Y1604754D02*
Y1603966D01*
G01Y1611053D02*
Y1610266D01*
G01Y1617352D02*
Y1616565D01*
G01Y1614203D02*
Y1613415D01*
G01Y1620502D02*
Y1619714D01*
G01Y1626801D02*
Y1626014D01*
G01Y1623651D02*
Y1622864D01*
G01Y1629951D02*
Y1629163D01*
G01Y1636250D02*
Y1635463D01*
G01Y1633100D02*
Y1632313D01*
G01Y1639400D02*
Y1638612D01*
G01Y1645699D02*
Y1644911D01*
G01Y1642549D02*
Y1641762D01*
G01Y1648848D02*
Y1648061D01*
G01X1532391Y1579557D02*
Y1578770D01*
G01Y1582707D02*
Y1581919D01*
G01Y1589006D02*
Y1588218D01*
G01Y1585856D02*
Y1585069D01*
G01Y1592155D02*
Y1591368D01*
G01Y1598455D02*
Y1597667D01*
G01Y1595305D02*
Y1594518D01*
G01Y1601604D02*
Y1600817D01*
G01Y1607903D02*
Y1607116D01*
G01Y1604754D02*
Y1603966D01*
G01Y1611053D02*
Y1610266D01*
G01Y1617352D02*
Y1616565D01*
G01Y1614203D02*
Y1613415D01*
G01Y1620502D02*
Y1619714D01*
G01Y1626801D02*
Y1626014D01*
G01Y1623651D02*
Y1622864D01*
G01Y1629951D02*
Y1629163D01*
G01Y1636250D02*
Y1635463D01*
G01Y1633100D02*
Y1632313D01*
G01Y1639400D02*
Y1638612D01*
G01Y1645699D02*
Y1644911D01*
G01Y1642549D02*
Y1641762D01*
G01Y1648848D02*
Y1648061D01*
G01X1532024Y1587884D02*
Y1584734D01*
G01X1531945Y1623455D02*
Y1604163D01*
G01X1531630D02*
Y1623455D01*
G01X1526433Y1643514D02*
Y1659931D01*
G01Y1625915D02*
Y1641151D01*
G01Y1604065D02*
Y1623553D01*
G01Y1601703D02*
Y1585364D01*
G01X1503974Y1648848D02*
X1503846Y1648821D01*
X1503758Y1648748D01*
X1503727Y1648651D01*
G01X1509023Y1651211D02*
X1509050Y1651214D01*
X1509075Y1651225D01*
X1509099Y1651243D01*
X1509121Y1651268D01*
X1509138Y1651298D01*
X1509150Y1651332D01*
X1509158Y1651368D01*
X1509161Y1651407D01*
G01X1503974Y1651211D02*
X1510058D01*
G01X1503590Y1651112D02*
X1510176D01*
G01X1504004Y1650522D02*
X1509749D01*
G01X1503974Y1648848D02*
X1510058D01*
G01X1503727Y1648651D02*
X1510338D01*
G01Y1648258D02*
X1503727D01*
G01X1508572Y1648848D02*
X1508610Y1648822D01*
X1508638Y1648750D01*
X1508648Y1648651D01*
G01X1503590Y1651112D02*
X1503727Y1650914D01*
X1503865Y1650718D01*
X1504004Y1650522D01*
G01X1503727Y1651407D02*
X1503758Y1651310D01*
X1503847Y1651238D01*
X1503974Y1651211D01*
G01X1509161Y1648651D02*
X1509158Y1648690D01*
X1509151Y1648726D01*
X1509138Y1648760D01*
X1509121Y1648791D01*
X1509100Y1648815D01*
X1509076Y1648833D01*
X1509050Y1648844D01*
X1509023Y1648848D01*
G01X1508208Y1651112D02*
X1508130Y1650522D01*
G01X1508648Y1651407D02*
X1508638Y1651309D01*
X1508610Y1651237D01*
X1508572Y1651211D01*
G01X1510338Y1648258D02*
Y1648651D01*
G01X1510176Y1651506D02*
Y1651112D01*
G01X1509332Y1651506D02*
Y1651112D01*
G01X1509161Y1648258D02*
Y1648651D01*
G01X1508648D02*
Y1648258D01*
G01X1508208Y1651112D02*
Y1651506D01*
G01X1503727Y1648651D02*
Y1648258D01*
G01X1503590Y1651112D02*
Y1651506D01*
G01X1509749Y1650522D02*
X1510176Y1651112D01*
G01X1509332D02*
X1509060Y1650522D01*
G01X1503974Y1655148D02*
X1503846Y1655120D01*
X1503758Y1655047D01*
X1503727Y1654951D01*
G01X1503974Y1651998D02*
X1503846Y1651970D01*
X1503758Y1651897D01*
X1503727Y1651801D01*
G01X1497772Y1673396D02*
X1551709D01*
G01X1524149Y1672214D02*
X1497772D01*
G01X1501709Y1665049D02*
X1551709D01*
G01X1499740D02*
X1496457D01*
G01X1530449Y1660522D02*
X1499740D01*
G01X1520212Y1660128D02*
X1501709D01*
G01X1509023Y1654360D02*
X1509050Y1654364D01*
X1509075Y1654375D01*
X1509099Y1654393D01*
X1509121Y1654418D01*
X1509138Y1654447D01*
X1509150Y1654481D01*
X1509158Y1654518D01*
X1509161Y1654557D01*
G01X1509749Y1657096D02*
X1504004D01*
G01X1510176Y1656506D02*
X1503590D01*
G01Y1656112D02*
X1510176D01*
G01X1504004Y1655522D02*
X1509749D01*
G01X1503974Y1655148D02*
X1510058D01*
G01X1503727Y1654951D02*
X1510338D01*
G01Y1654557D02*
X1503727D01*
G01X1503974Y1654360D02*
X1510058D01*
G01X1509749Y1652096D02*
X1504004D01*
G01X1503974Y1651998D02*
X1510058D01*
G01X1503727Y1651801D02*
X1510338D01*
G01X1510176Y1651506D02*
X1503590D01*
G01X1510338Y1651407D02*
X1503727D01*
G01X1508572Y1655148D02*
X1508610Y1655121D01*
X1508638Y1655049D01*
X1508648Y1654951D01*
G01X1508572Y1651998D02*
X1508610Y1651972D01*
X1508638Y1651899D01*
X1508648Y1651801D01*
G01X1499740Y1662096D02*
X1501709Y1660128D01*
G01X1509749Y1657096D02*
X1510176Y1656506D01*
G01X1503590Y1656112D02*
X1503727Y1655914D01*
X1503865Y1655718D01*
X1504004Y1655522D01*
G01X1509749Y1652096D02*
X1510176Y1651506D01*
G01X1509060Y1657096D02*
X1509332Y1656506D01*
G01X1509060Y1652096D02*
X1509332Y1651506D01*
G01X1503727Y1654557D02*
X1503758Y1654460D01*
X1503847Y1654388D01*
X1503974Y1654360D01*
G01X1508208Y1656506D02*
X1508130Y1657096D01*
G01X1508208Y1651506D02*
X1508130Y1652096D01*
G01X1497712Y1672674D02*
X1497767Y1672288D01*
G01X1509161Y1654951D02*
X1509158Y1654989D01*
X1509151Y1655026D01*
X1509138Y1655060D01*
X1509121Y1655090D01*
X1509100Y1655114D01*
X1509076Y1655132D01*
X1509050Y1655144D01*
X1509023Y1655148D01*
G01X1509161Y1651801D02*
X1509158Y1651839D01*
X1509151Y1651876D01*
X1509138Y1651910D01*
X1509121Y1651940D01*
X1509100Y1651965D01*
X1509076Y1651983D01*
X1509050Y1651994D01*
X1509023Y1651998D01*
G01X1508208Y1656112D02*
X1508130Y1655522D01*
G01X1510338Y1654557D02*
Y1654951D01*
G01Y1651407D02*
Y1651801D01*
G01X1510176Y1656506D02*
Y1656112D01*
G01X1509332Y1656506D02*
Y1656112D01*
G01X1509161Y1654557D02*
Y1654951D01*
G01Y1651407D02*
Y1651801D01*
G01X1508648Y1654951D02*
Y1654557D01*
G01Y1651801D02*
Y1651407D01*
G01X1508208Y1656112D02*
Y1656506D01*
G01X1503727Y1654951D02*
Y1654557D01*
G01Y1651801D02*
Y1651407D01*
G01X1503590Y1656112D02*
Y1656506D01*
G01X1497772Y1672214D02*
Y1665049D01*
G01X1508572Y1654360D02*
X1508610Y1654387D01*
X1508638Y1654459D01*
X1508648Y1654557D01*
G01X1509749Y1655522D02*
X1510176Y1656112D01*
G01X1504004Y1652096D02*
X1503865Y1651900D01*
X1503727Y1651703D01*
X1503590Y1651506D01*
G01X1509332Y1656112D02*
X1509060Y1655522D01*
G01X1497740Y1673364D02*
X1497683Y1673230D01*
X1497677Y1672994D01*
X1497714Y1672665D01*
G01X1497740Y1673364D02*
X1497682Y1673224D01*
X1497677Y1672985D01*
G01X1501709Y1665049D02*
X1499740Y1663081D01*
G01X1504004Y1657096D02*
X1503865Y1656900D01*
X1503727Y1656703D01*
X1503590Y1656506D01*
G01X1531945Y1650522D02*
G03X1531551Y1650128I0J-394D01*
G01X1542457Y1651211D02*
X1530449D01*
G01X1549937D02*
X1542605D01*
G01X1531945Y1650522D02*
X1539110D01*
G01X1534976Y1650325D02*
X1533992D01*
G01X1534976Y1649931D02*
X1533992D01*
G01X1534976Y1649734D02*
X1533992D01*
G01X1542605Y1648848D02*
X1549937D01*
G01X1542457D02*
X1530449D01*
G01X1549937Y1651998D02*
Y1651211D01*
G01X1548163Y1651998D02*
Y1651211D01*
G01X1547975D02*
Y1651998D01*
G01X1545138Y1651211D02*
Y1651998D01*
G01X1544197D02*
Y1651211D01*
G01X1542605Y1651998D02*
Y1651211D01*
G01X1542457Y1651998D02*
Y1651211D01*
G01X1541519Y1648848D02*
Y1651211D01*
G01X1539791Y1651998D02*
Y1651211D01*
G01X1539110Y1650522D02*
Y1652096D01*
G01X1538139Y1651211D02*
Y1651998D01*
G01X1536156Y1651211D02*
Y1651998D01*
G01X1535961Y1652096D02*
Y1650522D01*
G01X1534976Y1652884D02*
Y1649734D01*
G01X1533992Y1652884D02*
Y1649734D01*
G01X1533008Y1652096D02*
Y1650522D01*
G01X1532793Y1651998D02*
Y1651211D01*
G01X1532417Y1651998D02*
Y1651211D01*
G01X1532391Y1651998D02*
Y1651211D01*
G01X1541472Y1668612D02*
G03I-2165J0D01*
G01X1542653D02*
G03I-3346J0D01*
G01X1542811D02*
G03I-3504J0D01*
G01X1543835D02*
G03I-4528J0D01*
G01X1547119Y1667008D02*
G03X1549334Y1672175I-6937J6032D01*
G01X1546234Y1666934D02*
G03X1548448Y1672175I-7143J6105D01*
G01X1533205Y1697628D02*
G03Y1696447I0J-590D01*
G01Y1700384D02*
G03Y1699203I0J-590D01*
G01X1532220Y1678848D02*
G03Y1681998I0J1575D01*
G01X1533143Y1670453D02*
G03X1533685Y1671437I-1276J1344D01*
G01X1531945Y1655522D02*
G03X1531551Y1655128I0J-394D01*
G01Y1657490D02*
G03X1531945Y1657096I394J0D01*
G01X1531551Y1652490D02*
G03X1531945Y1652096I394J0D01*
G01X1526905Y1696447D02*
G03Y1697628I0J590D01*
G01Y1699203D02*
G03Y1700384I0J591D01*
G01X1527890Y1681998D02*
G03Y1678848I0J-1575D01*
G01X1533648Y1669909D02*
G03X1534718Y1671732I-2809J2874D01*
G01X1526672Y1667008D02*
G03X1528886Y1672175I-6938J6031D01*
G01X1525786Y1666934D02*
G03X1528001Y1672175I-7142J6107D01*
G01X1526522Y1658809D02*
X1526174Y1658724D01*
G01X1528177Y1658553D02*
X1527829Y1658468D01*
G01X1533205Y1700974D02*
X1526905D01*
G01X1531630Y1700679D02*
X1534779D01*
G01X1528480D02*
X1525331D01*
G01Y1698711D02*
X1528480D01*
G01X1534779D02*
X1531630D01*
G01X1525331Y1698120D02*
X1528480D01*
G01X1534779D02*
X1531630D01*
G01X1526916Y1697376D02*
X1527010D01*
G01Y1696628D02*
X1526916D01*
G01X1531630Y1696151D02*
X1534779D01*
G01X1528480D02*
X1525331D01*
G01X1526905Y1695856D02*
X1533205D01*
G01X1538244Y1686329D02*
X1521866D01*
G01X1527890Y1681998D02*
X1532220D01*
G01X1527264Y1681211D02*
X1532846D01*
G01Y1679636D02*
X1527264D01*
G01X1532220Y1678848D02*
X1527890D01*
G01X1538244Y1676151D02*
X1521866D01*
G01X1528886Y1672175D02*
X1528000D01*
G01X1534718D02*
X1530806D01*
G01X1549334D02*
X1548448D01*
G01X1530806Y1671437D02*
X1533684D01*
G01X1551709Y1671427D02*
X1528087D01*
G01X1534423Y1667967D02*
X1533611D01*
G01X1528087Y1667648D02*
X1551709D01*
G01X1529624Y1667008D02*
X1526672D01*
G01X1550072D02*
X1547119D01*
G01X1546234Y1666270D02*
X1550072D01*
G01X1525786D02*
X1529624D01*
G01X1551709Y1665679D02*
X1528087D01*
G01Y1663238D02*
X1551709D01*
G01X1536549Y1662746D02*
X1530449D01*
G01X1536549Y1662687D02*
X1530449D01*
G01X1550916Y1662293D02*
X1530449D01*
G01X1531551Y1661112D02*
X1522181D01*
G01X1521866Y1659931D02*
X1528401D01*
G01X1531551Y1659714D02*
X1551709D01*
G01X1531551Y1659340D02*
X1522181D01*
G01X1528526Y1658553D02*
X1528177D01*
G01X1528265Y1658041D02*
X1528439D01*
G01X1534976Y1657884D02*
X1533992D01*
G01X1535567Y1657726D02*
X1544551D01*
G01X1534976Y1657687D02*
X1533992D01*
G01X1534976Y1657293D02*
X1533992D01*
G01X1540075Y1657274D02*
X1532004D01*
G01X1531945Y1657096D02*
X1539110D01*
G01X1526696Y1656165D02*
X1526435D01*
G01X1526348Y1655653D02*
X1526784D01*
G01X1531945Y1655522D02*
X1539110D01*
G01X1534976Y1655325D02*
X1533992D01*
G01X1532004Y1655305D02*
X1540075D01*
G01X1542605Y1655148D02*
X1549937D01*
G01X1542457D02*
X1530449D01*
G01X1528177Y1654970D02*
X1528874D01*
G01X1534976Y1654931D02*
X1533992D01*
G01X1534976Y1654734D02*
X1533992D01*
G01X1525390Y1654459D02*
X1528787D01*
G01X1542457Y1654360D02*
X1530449D01*
G01X1549937D02*
X1542605D01*
G01X1529484Y1653947D02*
X1525390D01*
G01X1534976Y1652884D02*
X1533992D01*
G01X1534976Y1652687D02*
X1533992D01*
G01X1534976Y1652293D02*
X1533992D01*
G01X1531945Y1652096D02*
X1539110D01*
G01X1542605Y1651998D02*
X1549937D01*
G01X1542457D02*
X1530449D01*
G01X1528874Y1658468D02*
X1528526Y1658553D01*
G01X1532712Y1667008D02*
X1532365Y1667077D01*
G01X1528439Y1658041D02*
X1528700Y1657956D01*
G01X1543482Y1671359D02*
X1543843Y1671123D01*
X1544081Y1670773D01*
X1544167Y1670369D01*
X1544084Y1669967D01*
X1543848Y1669615D01*
X1543484Y1669375D01*
X1543059Y1669290D01*
G01X1542636Y1669374D02*
X1542276Y1669610D01*
X1542038Y1669960D01*
X1541952Y1670364D01*
X1542035Y1670766D01*
X1542271Y1671118D01*
X1542635Y1671358D01*
X1543059Y1671443D01*
G01X1538315Y1671359D02*
X1538675Y1671123D01*
X1538914Y1670773D01*
X1538999Y1670369D01*
X1538917Y1669967D01*
X1538680Y1669615D01*
X1538317Y1669375D01*
X1537892Y1669290D01*
G01X1537469Y1669374D02*
X1537109Y1669610D01*
X1536870Y1669960D01*
X1536785Y1670364D01*
X1536867Y1670766D01*
X1537104Y1671118D01*
X1537467Y1671358D01*
X1537892Y1671443D01*
G01X1526435Y1656165D02*
X1526174Y1656335D01*
G01X1532366Y1667077D02*
X1532086Y1667258D01*
G01X1543408Y1668567D02*
X1543691Y1668389D01*
X1543878Y1668124D01*
X1543945Y1667822D01*
X1543881Y1667522D01*
X1543695Y1667255D01*
X1543410Y1667073D01*
X1543059Y1667008D01*
G01X1542711Y1667073D02*
X1542428Y1667251D01*
X1542241Y1667516D01*
X1542174Y1667818D01*
X1542238Y1668118D01*
X1542424Y1668385D01*
X1542709Y1668566D01*
X1543059Y1668632D01*
G01X1538241Y1668567D02*
X1538524Y1668389D01*
X1538711Y1668124D01*
X1538778Y1667822D01*
X1538713Y1667522D01*
X1538528Y1667255D01*
X1538243Y1667073D01*
X1537892Y1667008D01*
G01X1537543Y1667073D02*
X1537261Y1667251D01*
X1537073Y1667516D01*
X1537006Y1667818D01*
X1537071Y1668118D01*
X1537256Y1668385D01*
X1537542Y1668566D01*
X1537892Y1668632D01*
G01X1525999Y1655823D02*
X1526348Y1655653D01*
G01X1528874Y1654970D02*
X1529484Y1654459D01*
G01X1528787D02*
X1528177Y1654970D01*
G01X1529223Y1658127D02*
X1528874Y1658468D01*
G01X1525651Y1656165D02*
X1525999Y1655823D01*
G01X1541862Y1668919D02*
X1541410Y1669359D01*
X1541140Y1669895D01*
X1541070Y1670465D01*
X1541211Y1671029D01*
X1541558Y1671554D01*
X1542085Y1671947D01*
X1542728Y1672150D01*
X1543407Y1672148D01*
X1544047Y1671940D01*
X1544570Y1671544D01*
X1544912Y1671020D01*
X1545050Y1670459D01*
X1544978Y1669891D01*
X1544708Y1669357D01*
G01X1536694Y1668919D02*
X1536243Y1669359D01*
X1535973Y1669895D01*
X1535902Y1670465D01*
X1536044Y1671029D01*
X1536391Y1671554D01*
X1536918Y1671947D01*
X1537561Y1672150D01*
X1538240Y1672148D01*
X1538880Y1671940D01*
X1539403Y1671544D01*
X1539744Y1671020D01*
X1539882Y1670459D01*
X1539811Y1669891D01*
X1539540Y1669357D01*
G01X1528700Y1657956D02*
X1528874Y1657700D01*
G01X1532086Y1667257D02*
X1531903Y1667522D01*
X1531839Y1667821D01*
X1531904Y1668118D01*
G01X1544257Y1668919D02*
X1544580Y1668499D01*
X1544742Y1668016D01*
X1544721Y1667511D01*
X1544518Y1667034D01*
X1544151Y1666631D01*
X1543645Y1666363D01*
X1543054Y1666270D01*
X1542464Y1666367D01*
X1541962Y1666635D01*
X1541598Y1667039D01*
X1541397Y1667517D01*
X1541377Y1668022D01*
X1541541Y1668503D01*
X1541862Y1668919D01*
G01X1539090D02*
X1539413Y1668499D01*
X1539575Y1668016D01*
X1539553Y1667511D01*
X1539350Y1667034D01*
X1538984Y1666631D01*
X1538477Y1666363D01*
X1537886Y1666270D01*
X1537297Y1666367D01*
X1536795Y1666635D01*
X1536431Y1667039D01*
X1536229Y1667517D01*
X1536210Y1668022D01*
X1536374Y1668503D01*
X1536694Y1668919D01*
G01X1529397Y1657785D02*
X1529223Y1658127D01*
G01X1525477Y1656506D02*
X1525651Y1656165D01*
G01X1536804Y1662293D02*
X1536549Y1662687D01*
G01X1526174Y1656335D02*
X1525999Y1656591D01*
G01X1528874Y1657700D02*
X1528961Y1657444D01*
G01X1525390Y1656932D02*
X1525477Y1656506D01*
G01X1529484Y1657444D02*
X1529397Y1657785D01*
G01X1525999Y1656591D02*
X1525912Y1656932D01*
G01X1551709Y1659714D02*
Y1673396D01*
G01X1551391Y1659714D02*
Y1665049D01*
G01X1550916Y1659714D02*
Y1662293D01*
G01X1550072Y1666270D02*
Y1667008D01*
G01X1549937Y1655148D02*
Y1654360D01*
G01X1548163Y1655148D02*
Y1654360D01*
G01X1547975D02*
Y1655148D01*
G01X1546234Y1666934D02*
Y1666270D01*
G01X1545138Y1654360D02*
Y1655148D01*
G01X1545062Y1665049D02*
Y1662293D01*
G01X1544197Y1655148D02*
Y1654360D01*
G01X1542605Y1655148D02*
Y1654360D01*
G01X1542457Y1655148D02*
Y1654360D01*
G01X1541519Y1655148D02*
Y1657726D01*
G01Y1651998D02*
Y1654360D01*
G01X1540075Y1655305D02*
Y1657274D01*
G01X1539791Y1655148D02*
Y1654360D01*
G01X1539110Y1655522D02*
Y1657096D01*
G01X1538244Y1686329D02*
Y1673396D01*
G01X1538139Y1654360D02*
Y1655148D01*
G01X1537188Y1665049D02*
Y1662293D01*
G01X1536549Y1662687D02*
Y1662746D01*
G01X1536156Y1654360D02*
Y1655148D01*
G01X1535961Y1657096D02*
Y1655522D01*
G01X1534976Y1657884D02*
Y1654734D01*
G01X1534779Y1696151D02*
Y1698120D01*
G01Y1700679D02*
Y1698711D01*
G01X1534718Y1671732D02*
Y1672175D01*
G01X1534423Y1667820D02*
Y1667967D01*
G01X1533992Y1662746D02*
Y1665049D01*
G01Y1657884D02*
Y1654734D01*
G01X1533611Y1667967D02*
Y1667820D01*
G01X1533205Y1697628D02*
Y1699203D01*
G01Y1700384D02*
Y1700974D01*
G01Y1695856D02*
Y1696447D01*
G01X1533008Y1657096D02*
Y1655522D01*
G01X1532846Y1679636D02*
Y1681211D01*
G01X1532811D02*
Y1679636D01*
G01X1532793Y1655148D02*
Y1654360D01*
G01X1532787Y1681211D02*
Y1679636D01*
G01X1532417Y1655148D02*
Y1654360D01*
G01X1532391Y1655148D02*
Y1654360D01*
G01X1532220Y1695856D02*
Y1700974D01*
G01X1532024D02*
Y1695856D01*
G01X1532004Y1657274D02*
Y1655305D01*
G01X1531630Y1698711D02*
Y1700679D01*
G01Y1698120D02*
Y1696151D01*
G01X1531464Y1679636D02*
Y1681211D01*
G01X1531094D02*
Y1679636D01*
G01X1530806Y1672175D02*
Y1671437D01*
G01X1529624Y1666270D02*
Y1667008D01*
G01X1529484Y1657018D02*
Y1657444D01*
G01Y1654459D02*
Y1653947D01*
G01X1529016Y1679636D02*
Y1681211D01*
G01X1528961Y1657444D02*
Y1656932D01*
G01X1528646Y1681211D02*
Y1679636D01*
G01X1528526Y1656421D02*
Y1655909D01*
G01X1528480Y1698711D02*
Y1700679D01*
G01Y1698120D02*
Y1696151D01*
G01X1528087Y1663238D02*
Y1665679D01*
G01Y1671427D02*
Y1667648D01*
G01Y1700974D02*
Y1695856D01*
G01X1527890D02*
Y1700974D01*
G01X1527742Y1656932D02*
Y1657444D01*
G01X1527324Y1679636D02*
Y1681211D01*
G01X1527299Y1679636D02*
Y1681211D01*
G01X1527264D02*
Y1679636D01*
G01X1527219Y1657444D02*
Y1656932D01*
G01X1527010Y1697376D02*
Y1696628D01*
G01X1526916D02*
Y1697249D01*
G01X1526905Y1696447D02*
Y1695856D01*
G01Y1699203D02*
Y1697628D01*
G01Y1700974D02*
Y1700384D01*
G01X1526823Y1697137D02*
Y1697264D01*
G01X1526522Y1658297D02*
Y1658809D01*
G01X1525912Y1656932D02*
Y1657615D01*
G01X1525786Y1666934D02*
Y1666270D01*
G01X1525390Y1653947D02*
Y1654459D01*
G01Y1657615D02*
Y1656932D01*
G01X1525331Y1696151D02*
Y1698120D01*
G01Y1700679D02*
Y1698711D01*
G01X1524149Y1673396D02*
Y1665049D01*
G01X1522181Y1661112D02*
Y1659340D01*
G01X1521866Y1659931D02*
Y1686329D01*
G01X1528526Y1655909D02*
X1528787Y1655994D01*
G01X1528003Y1657956D02*
X1528265Y1658041D01*
G01X1526261Y1658212D02*
X1526522Y1658297D01*
G01X1527219Y1656932D02*
X1527132Y1656591D01*
G01X1527306Y1657785D02*
X1527219Y1657444D01*
G01X1525912Y1657615D02*
X1525999Y1657956D01*
G01X1533543Y1667515D02*
X1533611Y1667820D01*
G01X1529397Y1656591D02*
X1529484Y1657018D01*
G01X1527655Y1656506D02*
X1527742Y1656932D01*
G01X1525477Y1658041D02*
X1525390Y1657615D01*
G01X1534423Y1667820D02*
X1534336Y1667343D01*
X1534088Y1666901D01*
X1533700Y1666549D01*
X1533193Y1666329D01*
X1532616Y1666273D01*
X1532052Y1666395D01*
X1531576Y1666677D01*
X1531237Y1667082D01*
X1531057Y1667539D01*
X1531042Y1668019D01*
X1531199Y1668489D01*
X1531514Y1668906D01*
G01X1528700Y1656506D02*
X1528526Y1656421D01*
G01X1526784Y1655653D02*
X1527132Y1655823D01*
G01X1526174Y1658724D02*
X1525738Y1658468D01*
G01X1533354Y1667248D02*
X1533067Y1667070D01*
X1532713Y1667008D01*
G01X1543408Y1667073D02*
X1543691Y1667251D01*
X1543878Y1667516D01*
X1543945Y1667818D01*
X1543881Y1668118D01*
X1543695Y1668385D01*
X1543410Y1668566D01*
X1543059Y1668632D01*
G01X1542711Y1668567D02*
X1542428Y1668389D01*
X1542241Y1668124D01*
X1542174Y1667822D01*
X1542238Y1667522D01*
X1542424Y1667255D01*
X1542709Y1667073D01*
X1543059Y1667008D01*
G01X1538241Y1667073D02*
X1538524Y1667251D01*
X1538711Y1667516D01*
X1538778Y1667818D01*
X1538713Y1668118D01*
X1538528Y1668385D01*
X1538243Y1668566D01*
X1537892Y1668632D01*
G01X1537543Y1668567D02*
X1537261Y1668389D01*
X1537073Y1668124D01*
X1537006Y1667822D01*
X1537071Y1667522D01*
X1537256Y1667255D01*
X1537542Y1667073D01*
X1537892Y1667008D01*
G01X1526958Y1656335D02*
X1526696Y1656165D01*
G01X1543482Y1669374D02*
X1543843Y1669610D01*
X1544081Y1669960D01*
X1544167Y1670364D01*
X1544084Y1670766D01*
X1543848Y1671118D01*
X1543484Y1671358D01*
X1543059Y1671443D01*
G01X1542636Y1671359D02*
X1542276Y1671123D01*
X1542038Y1670773D01*
X1541952Y1670369D01*
X1542035Y1669967D01*
X1542271Y1669615D01*
X1542635Y1669375D01*
X1543059Y1669290D01*
G01X1538315Y1669374D02*
X1538675Y1669610D01*
X1538914Y1669960D01*
X1538999Y1670364D01*
X1538917Y1670766D01*
X1538680Y1671118D01*
X1538317Y1671358D01*
X1537892Y1671443D01*
G01X1537469Y1671359D02*
X1537109Y1671123D01*
X1536870Y1670773D01*
X1536785Y1670369D01*
X1536867Y1669967D01*
X1537104Y1669615D01*
X1537467Y1669375D01*
X1537892Y1669290D01*
G01X1528787Y1655994D02*
X1529136Y1656250D01*
G01X1533143Y1670453D02*
X1531514Y1668906D01*
G01X1544257Y1668919D02*
X1544709Y1669359D01*
X1544979Y1669895D01*
X1545049Y1670465D01*
X1544908Y1671029D01*
X1544561Y1671554D01*
X1544034Y1671947D01*
X1543391Y1672150D01*
X1542712Y1672148D01*
X1542072Y1671940D01*
X1541549Y1671544D01*
X1541207Y1671020D01*
X1541069Y1670459D01*
X1541141Y1669891D01*
X1541411Y1669357D01*
G01X1539090Y1668919D02*
X1539542Y1669359D01*
X1539812Y1669895D01*
X1539882Y1670465D01*
X1539740Y1671029D01*
X1539394Y1671554D01*
X1538866Y1671947D01*
X1538224Y1672150D01*
X1537544Y1672148D01*
X1536904Y1671940D01*
X1536381Y1671544D01*
X1536040Y1671020D01*
X1535902Y1670459D01*
X1535974Y1669891D01*
X1536244Y1669357D01*
G01X1533648Y1669909D02*
X1532086Y1668382D01*
G01X1528874Y1656676D02*
X1528700Y1656506D01*
G01X1527132Y1655823D02*
X1527480Y1656165D01*
G01X1527829Y1658468D02*
X1527480Y1658127D01*
G01X1525999Y1657956D02*
X1526261Y1658212D01*
G01X1541862Y1668919D02*
X1541539Y1668499D01*
X1541376Y1668016D01*
X1541398Y1667511D01*
X1541601Y1667034D01*
X1541968Y1666631D01*
X1542474Y1666363D01*
X1543065Y1666270D01*
X1543654Y1666367D01*
X1544157Y1666635D01*
X1544521Y1667039D01*
X1544722Y1667517D01*
X1544741Y1668022D01*
X1544578Y1668503D01*
X1544257Y1668919D01*
G01X1536694D02*
X1536372Y1668499D01*
X1536209Y1668016D01*
X1536231Y1667511D01*
X1536434Y1667034D01*
X1536801Y1666631D01*
X1537307Y1666363D01*
X1537898Y1666270D01*
X1538487Y1666367D01*
X1538989Y1666635D01*
X1539354Y1667039D01*
X1539555Y1667517D01*
X1539574Y1668022D01*
X1539410Y1668503D01*
X1539090Y1668919D01*
G01X1529136Y1656250D02*
X1529397Y1656591D01*
G01X1531514Y1668906D02*
X1531177Y1668445D01*
X1531031Y1667926D01*
X1531092Y1667409D01*
X1531343Y1666925D01*
X1531779Y1666530D01*
X1532352Y1666307D01*
X1532987Y1666288D01*
X1533571Y1666474D01*
X1534026Y1666827D01*
X1534319Y1667299D01*
X1534423Y1667820D01*
G01X1533354Y1667248D02*
X1533544Y1667516D01*
G01X1532086Y1668382D02*
X1531903Y1668116D01*
X1531839Y1667818D01*
X1531904Y1667521D01*
G01X1527132Y1656591D02*
X1526958Y1656335D01*
G01X1527829Y1657700D02*
X1528003Y1657956D01*
G01X1525738Y1658468D02*
X1525477Y1658041D01*
G01X1527480Y1656165D02*
X1527655Y1656506D01*
G01X1527480Y1658127D02*
X1527306Y1657785D01*
G01X1528961Y1656932D02*
X1528874Y1656676D01*
G01X1527742Y1657444D02*
X1527829Y1657700D01*
G01X1526916Y1697249D02*
X1526823Y1697137D01*
G01Y1697264D02*
X1526916Y1697376D01*
G01X1592555Y1775777D02*
X1565980D01*
G01Y1755699D02*
X1592555D01*
G01X1565980Y1775777D02*
Y1755699D01*
G01X1509023Y1937037D02*
X1509050Y1937041D01*
X1509075Y1937052D01*
X1509099Y1937070D01*
X1509121Y1937095D01*
X1509138Y1937125D01*
X1509150Y1937159D01*
X1509158Y1937195D01*
X1509161Y1937234D01*
G01X1503974Y1937825D02*
X1503846Y1937797D01*
X1503758Y1937724D01*
X1503727Y1937628D01*
G01X1503974Y1937825D02*
X1510058D01*
G01X1503727Y1937628D02*
X1510338D01*
G01X1509749Y1937608D02*
X1504004D01*
G01X1510338Y1937234D02*
X1503727D01*
G01X1503974Y1937037D02*
X1510058D01*
G01X1510176Y1937018D02*
X1503590D01*
G01Y1936624D02*
X1510176D01*
G01X1504004Y1936033D02*
X1509749D01*
G01X1501709Y1933002D02*
X1520212D01*
G01X1499740Y1932608D02*
X1530449D01*
G01X1501709Y1928081D02*
X1551709D01*
G01X1499740D02*
X1496457D01*
G01X1497772Y1920915D02*
X1524149D01*
G01X1551709Y1919734D02*
X1497772D01*
G01X1508572Y1937825D02*
X1508610Y1937798D01*
X1508638Y1937726D01*
X1508648Y1937628D01*
G01X1499740Y1930049D02*
X1501709Y1928081D01*
G01X1509749Y1937608D02*
X1510176Y1937018D01*
G01X1503590Y1936624D02*
X1503727Y1936426D01*
X1503865Y1936229D01*
X1504004Y1936033D01*
G01X1509060Y1937608D02*
X1509332Y1937018D01*
G01X1497740Y1919765D02*
X1497682Y1919905D01*
X1497677Y1920145D01*
G01X1503727Y1937234D02*
X1503758Y1937137D01*
X1503847Y1937065D01*
X1503974Y1937037D01*
G01X1508208Y1937018D02*
X1508130Y1937608D01*
G01X1509161Y1937628D02*
X1509158Y1937666D01*
X1509151Y1937703D01*
X1509138Y1937737D01*
X1509121Y1937767D01*
X1509100Y1937791D01*
X1509076Y1937810D01*
X1509050Y1937821D01*
X1509023Y1937825D01*
G01X1508648Y1937234D02*
X1508638Y1937136D01*
X1508610Y1937064D01*
X1508572Y1937037D01*
G01X1510338Y1937234D02*
Y1937628D01*
G01X1510176Y1937018D02*
Y1936624D01*
G01X1509332Y1937018D02*
Y1936624D01*
G01X1509161Y1937234D02*
Y1937628D01*
G01X1508648D02*
Y1937234D01*
G01X1508208Y1936624D02*
Y1937018D01*
G01X1503727Y1937628D02*
Y1937234D01*
G01X1503590Y1936624D02*
Y1937018D01*
G01X1501709Y2065640D02*
Y1933002D01*
G01X1500921Y1932214D02*
Y2003120D01*
G01X1500862Y1932608D02*
Y2066033D01*
G01X1499740Y2070561D02*
Y1928081D01*
G01X1497772D02*
Y1920915D01*
G01X1497714Y1920464D02*
X1497767Y1920842D01*
G01X1508208Y1936624D02*
X1508130Y1936033D01*
G01X1497714Y1920466D02*
X1497677Y1920142D01*
X1497683Y1919901D01*
X1497740Y1919765D01*
G01X1509332Y1936624D02*
X1509060Y1936033D01*
G01X1501709Y1933002D02*
X1499740Y1931033D01*
G01X1509749Y1936033D02*
X1510176Y1936624D01*
G01X1504004Y1937608D02*
X1503865Y1937412D01*
X1503727Y1937215D01*
X1503590Y1937018D01*
G01X1543875Y1923561D02*
G03X1542450I-713J82D01*
G01X1542889Y1920936D02*
G03X1544475Y1921223I263J3073D01*
G01X1543223Y1921927D02*
G03X1543814Y1922292I10J646D01*
G01X1542450Y1922735D02*
G03X1543223Y1921927I791J-17D01*
G01X1544475Y1921223D02*
G03X1545318Y1922292I-704J1422D01*
G01X1545109Y1924178D02*
G03X1543875Y1925152I-1735J-930D01*
G01X1542232Y1925108D02*
G03X1541068Y1923969I730J-1910D01*
G01X1541154Y1921954D02*
G03X1542893Y1920936I1807J1093D01*
G01X1543875Y1925151D02*
G03X1542232Y1925108I-757J-2475D01*
G01X1540894Y1922813D02*
G03X1541156Y1921951I2971J432D01*
G01X1545448Y1922735D02*
G03X1545109Y1924178I-3015J53D01*
G01X1540894Y1923309D02*
G03Y1922812I3524J-249D01*
G01X1541068Y1923969D02*
G03X1540894Y1923309I4018J-1412D01*
G01X1541472Y1924518D02*
G03I-2165J0D01*
G01X1541261Y1921801D02*
G03Y1927234I-1954J2717D01*
G01X1537353D02*
G03Y1921801I1954J-2717D01*
G01X1542811Y1924518D02*
G03I-3504J0D01*
G01X1537003Y1928415D02*
G03Y1920620I2304J-3898D01*
G01X1541611D02*
G03Y1928415I-2304J3897D01*
G01X1537545Y1921346D02*
G03X1538065Y1921912I-833J1287D01*
G01Y1924224D02*
G03X1537544Y1924789I-1351J-723D01*
G01X1535250Y1923929D02*
G03Y1922245I2236J-842D01*
G01D02*
G03X1536723I736J277D01*
G01Y1923929D02*
G03X1535250I-737J-277D01*
G01X1533043Y1924065D02*
G03X1532749Y1924736I-913J0D01*
G01X1533978Y1921910D02*
G03X1534499Y1921345I1351J723D01*
G01X1534498Y1924789D02*
G03X1533977Y1924224I830J-1288D01*
G01X1532220Y1911132D02*
G03Y1914281I0J1574D01*
G01X1536723Y1922245D02*
G03Y1923929I-2237J842D01*
G01X1533977Y1924224D02*
G03X1533978Y1921910I2163J-1156D01*
G01X1538065Y1921912D02*
G03Y1924224I-2163J1156D01*
G01X1534499Y1921345D02*
G03X1537545Y1921346I1522J2362D01*
G01X1537544Y1924789D02*
G03X1534498I-1523J-2361D01*
G01X1531945Y1936033D02*
G03X1531551Y1935640I0J-394D01*
G01Y1938002D02*
G03X1531945Y1937608I394J0D01*
G01X1528761Y1923661D02*
G03X1527330I-716J0D01*
G01X1531651D02*
G03X1530220I-716J0D01*
G01X1527890Y1914281D02*
G03Y1911132I0J-1575D01*
G01X1532749Y1924736D02*
G03X1530114Y1924591I-1247J-1352D01*
G01D02*
G03X1527333Y1924586I-1388J-1206D01*
G01X1534976Y1938396D02*
X1533992D01*
G01X1534976Y1938199D02*
X1533992D01*
G01X1542605Y1937825D02*
X1549937D01*
G01X1542457D02*
X1530449D01*
G01X1534976Y1937805D02*
X1533992D01*
G01X1531945Y1937608D02*
X1539110D01*
G01X1542457Y1937037D02*
X1530449D01*
G01X1549937D02*
X1542605D01*
G01X1531945Y1936033D02*
X1539110D01*
G01X1534976Y1935837D02*
X1533992D01*
G01X1534976Y1935443D02*
X1533992D01*
G01X1544551Y1935364D02*
X1535567D01*
G01X1534976Y1935246D02*
X1533992D01*
G01X1531551Y1933789D02*
X1522181D01*
G01X1551709Y1933612D02*
X1531551D01*
G01X1521866Y1933199D02*
X1528401D01*
G01X1531551Y1932018D02*
X1522181D01*
G01X1550916Y1930837D02*
X1530449D01*
G01X1536549Y1930443D02*
X1530449D01*
G01X1536549Y1930384D02*
X1530449D01*
G01X1551709Y1929852D02*
X1528087D01*
G01X1541611Y1928415D02*
X1537003D01*
G01X1551709Y1927451D02*
X1528087D01*
G01X1537353Y1927234D02*
X1541261D01*
G01X1540303Y1926890D02*
X1538843D01*
G01X1551709Y1925482D02*
X1528087D01*
G01X1527333Y1925143D02*
X1525890D01*
G01X1549942D02*
X1548560D01*
G01X1547265D02*
X1545648D01*
G01X1543875Y1923561D02*
X1542450D01*
G01X1545448Y1922735D02*
X1542449D01*
G01X1545318Y1922292D02*
X1543814D01*
G01X1541261Y1921801D02*
X1537353D01*
G01X1551709Y1921703D02*
X1528087D01*
G01X1527330Y1921136D02*
X1525890D01*
G01X1530220D02*
X1528761D01*
G01X1533043D02*
X1531651D01*
G01X1540303D02*
X1538843D01*
G01X1549968D02*
X1548419D01*
G01X1546882D02*
X1545474D01*
G01X1537003Y1920620D02*
X1541611D01*
G01X1538244Y1916978D02*
X1521866D01*
G01X1527890Y1914281D02*
X1532220D01*
G01X1527264Y1913494D02*
X1532846D01*
G01Y1911919D02*
X1527264D01*
G01X1532220Y1911132D02*
X1527890D01*
G01X1521866Y1906801D02*
X1538244D01*
G01X1545648Y1925143D02*
X1546917Y1923283D01*
G01X1547673Y1922414D02*
X1548419Y1921136D01*
G01X1548647Y1923291D02*
X1549968Y1921136D01*
G01X1547265Y1925143D02*
X1547870Y1924157D01*
G01X1541261Y1921801D02*
X1541279Y1921745D01*
X1541331Y1921580D01*
X1541410Y1921321D01*
X1541506Y1920994D01*
X1541611Y1920620D01*
G01X1537353Y1927234D02*
X1537335Y1927290D01*
X1537283Y1927456D01*
X1537204Y1927714D01*
X1537108Y1928041D01*
X1537003Y1928415D01*
G01X1551709Y1919734D02*
Y1933612D01*
G01X1551391Y1928081D02*
Y1933612D01*
G01X1550916Y1930837D02*
Y1933612D01*
G01X1549937Y1937825D02*
Y1937037D01*
G01X1548163Y1937825D02*
Y1937037D01*
G01X1547975D02*
Y1937825D01*
G01X1545138Y1937037D02*
Y1937825D01*
G01X1545062Y1930837D02*
Y1928081D01*
G01X1544551Y1930837D02*
Y2067805D01*
G01X1544197Y1937825D02*
Y1937037D01*
G01X1542605Y1937825D02*
Y1937037D01*
G01X1542457Y1937825D02*
Y1937037D01*
G01X1541519Y1937825D02*
Y1940187D01*
G01Y1935364D02*
Y1937037D01*
G01X1540303Y1926890D02*
Y1921136D01*
G01X1539791Y1937825D02*
Y1937037D01*
G01X1539110Y1936033D02*
Y1937608D01*
G01X1538843Y1921136D02*
Y1926890D01*
G01X1538244Y1919734D02*
Y1906801D01*
G01X1538139Y1937037D02*
Y1937825D01*
G01X1537188Y1930837D02*
Y1928081D01*
G01X1536549Y1930384D02*
Y1930443D01*
G01X1536156Y1937037D02*
Y1937825D01*
G01X1536021Y2065226D02*
Y1933612D01*
G01X1535961Y1937608D02*
Y1936033D01*
G01X1535567Y2067805D02*
Y1930837D01*
G01X1534976Y1938396D02*
Y1935246D01*
G01X1533992Y1928081D02*
Y1930384D01*
G01Y1938396D02*
Y1935246D01*
G01X1533043Y1924065D02*
Y1921136D01*
G01X1533008Y1937608D02*
Y1936033D01*
G01X1532846Y1911919D02*
Y1913494D01*
G01X1532811D02*
Y1911919D01*
G01X1532793Y1937825D02*
Y1937037D01*
G01X1532787Y1913494D02*
Y1911919D01*
G01X1532417Y1937825D02*
Y1937037D01*
G01X1532391Y1937825D02*
Y1937037D01*
G01X1531651Y1921136D02*
Y1923661D01*
G01X1531551Y2067805D02*
Y1930837D01*
G01X1531464Y1911919D02*
Y1913494D01*
G01X1531094D02*
Y1911919D01*
G01X1530449Y1930384D02*
Y2068258D01*
G01X1530220Y1923661D02*
Y1921136D01*
G01X1529016Y1911919D02*
Y1913494D01*
G01X1528761Y1921136D02*
Y1923661D01*
G01X1528646Y1913494D02*
Y1911919D01*
G01X1528401Y2065443D02*
Y1933199D01*
G01X1528087Y1925482D02*
Y1921703D01*
G01Y1929852D02*
Y1927451D01*
G01X1527333Y1925143D02*
Y1924586D01*
G01X1527330Y1923661D02*
Y1921136D01*
G01X1527324Y1911919D02*
Y1913494D01*
G01X1527299Y1911919D02*
Y1913494D01*
G01X1527264D02*
Y1911919D01*
G01X1526433Y1950718D02*
Y1933199D01*
G01X1525890Y1925143D02*
Y1921136D01*
G01X1524149Y1919734D02*
Y1928081D01*
G01X1522181Y1933789D02*
Y1932018D01*
G01X1521866Y1933199D02*
Y1906801D01*
G01X1520212Y1933002D02*
Y2065640D01*
G01X1537003Y1920620D02*
X1537106Y1920989D01*
X1537203Y1921319D01*
X1537283Y1921581D01*
X1537335Y1921747D01*
X1537353Y1921801D01*
G01X1541261Y1927234D02*
X1541279Y1927290D01*
X1541331Y1927455D01*
X1541410Y1927714D01*
X1541506Y1928041D01*
X1541611Y1928415D01*
G01X1549942Y1925143D02*
X1548647Y1923291D01*
G01X1548560Y1925143D02*
X1547870Y1924157D01*
G01X1546917Y1923283D02*
X1545474Y1921136D01*
G01X1536549Y1930443D02*
X1536804Y1930837D01*
G01X1547673Y1922414D02*
X1546882Y1921136D01*
G01X1509023Y1940187D02*
X1509050Y1940191D01*
X1509075Y1940202D01*
X1509099Y1940220D01*
X1509121Y1940245D01*
X1509138Y1940274D01*
X1509150Y1940308D01*
X1509158Y1940345D01*
X1509161Y1940384D01*
G01X1503974Y1940974D02*
X1503846Y1940947D01*
X1503758Y1940874D01*
X1503727Y1940777D01*
G01X1509749Y1942608D02*
X1504004D01*
G01X1510176Y1942018D02*
X1503590D01*
G01Y1941624D02*
X1510176D01*
G01X1504004Y1941033D02*
X1509749D01*
G01X1503974Y1940974D02*
X1510058D01*
G01X1503727Y1940777D02*
X1510338D01*
G01Y1940384D02*
X1503727D01*
G01X1503974Y1940187D02*
X1510058D01*
G01X1508572Y1940974D02*
X1508610Y1940948D01*
X1508638Y1940876D01*
X1508648Y1940777D01*
G01X1509749Y1942608D02*
X1510176Y1942018D01*
G01X1503590Y1941624D02*
X1503727Y1941426D01*
X1503865Y1941229D01*
X1504004Y1941033D01*
G01X1509060Y1942608D02*
X1509332Y1942018D01*
G01X1503727Y1940384D02*
X1503758Y1940287D01*
X1503847Y1940215D01*
X1503974Y1940187D01*
G01X1508130Y1942608D02*
X1508208Y1942018D01*
G01X1509161Y1940777D02*
X1509158Y1940816D01*
X1509151Y1940852D01*
X1509138Y1940886D01*
X1509121Y1940917D01*
X1509100Y1940941D01*
X1509076Y1940959D01*
X1509050Y1940970D01*
X1509023Y1940974D01*
G01X1508648Y1940384D02*
X1508638Y1940285D01*
X1508610Y1940213D01*
X1508572Y1940187D01*
G01X1510338Y1940384D02*
Y1940777D01*
G01X1510176Y1942018D02*
Y1941624D01*
G01X1509332Y1942018D02*
Y1941624D01*
G01X1509161Y1940384D02*
Y1940777D01*
G01X1508648D02*
Y1940384D01*
G01X1508208Y1942018D02*
Y1941624D01*
G01X1503727Y1940777D02*
Y1940384D01*
G01X1503590Y1941624D02*
Y1942018D01*
G01X1508130Y1941033D02*
X1508208Y1941624D01*
G01X1509332D02*
X1509060Y1941033D01*
G01X1509749D02*
X1510176Y1941624D01*
G01X1504004Y1942608D02*
X1503865Y1942412D01*
X1503727Y1942215D01*
X1503590Y1942018D01*
G01X1509023Y2009478D02*
X1509050Y2009482D01*
X1509075Y2009493D01*
X1509099Y2009511D01*
X1509121Y2009536D01*
X1509138Y2009566D01*
X1509150Y2009599D01*
X1509158Y2009636D01*
X1509161Y2009675D01*
G01X1509023Y2006329D02*
X1509050Y2006332D01*
X1509075Y2006343D01*
X1509099Y2006362D01*
X1509121Y2006386D01*
X1509138Y2006416D01*
X1509150Y2006450D01*
X1509158Y2006487D01*
X1509161Y2006525D01*
G01X1509023Y2003179D02*
X1509050Y2003183D01*
X1509075Y2003194D01*
X1509099Y2003212D01*
X1509121Y2003237D01*
X1509138Y2003266D01*
X1509150Y2003300D01*
X1509158Y2003337D01*
X1509161Y2003376D01*
G01X1509023Y2000029D02*
X1509050Y2000033D01*
X1509075Y2000044D01*
X1509099Y2000062D01*
X1509121Y2000087D01*
X1509138Y2000117D01*
X1509150Y2000151D01*
X1509158Y2000187D01*
X1509161Y2000226D01*
G01X1509023Y1996880D02*
X1509050Y1996884D01*
X1509075Y1996895D01*
X1509099Y1996913D01*
X1509121Y1996937D01*
X1509138Y1996967D01*
X1509150Y1997001D01*
X1509158Y1997038D01*
X1509161Y1997077D01*
G01X1509023Y1993730D02*
X1509050Y1993734D01*
X1509075Y1993745D01*
X1509099Y1993763D01*
X1509121Y1993788D01*
X1509138Y1993818D01*
X1509150Y1993851D01*
X1509158Y1993888D01*
X1509161Y1993927D01*
G01X1509023Y1990581D02*
X1509050Y1990584D01*
X1509075Y1990595D01*
X1509099Y1990613D01*
X1509121Y1990638D01*
X1509138Y1990668D01*
X1509150Y1990702D01*
X1509158Y1990739D01*
X1509161Y1990777D01*
G01X1509023Y1987431D02*
X1509050Y1987435D01*
X1509075Y1987446D01*
X1509099Y1987464D01*
X1509121Y1987489D01*
X1509138Y1987518D01*
X1509150Y1987552D01*
X1509158Y1987589D01*
X1509161Y1987628D01*
G01X1503964Y2012134D02*
X1503838Y2012106D01*
X1503748Y2012034D01*
X1503717Y2011937D01*
G01X1503974Y2010266D02*
X1503846Y2010238D01*
X1503758Y2010165D01*
X1503727Y2010069D01*
G01X1503974Y2007116D02*
X1503846Y2007088D01*
X1503758Y2007015D01*
X1503727Y2006919D01*
G01X1503974Y2003966D02*
X1503846Y2003939D01*
X1503758Y2003866D01*
X1503727Y2003770D01*
G01X1503974Y2000817D02*
X1503846Y2000789D01*
X1503758Y2000716D01*
X1503727Y2000620D01*
G01X1503974Y1997667D02*
X1503846Y1997639D01*
X1503758Y1997567D01*
X1503727Y1997470D01*
G01X1503974Y1994518D02*
X1503846Y1994490D01*
X1503758Y1994417D01*
X1503727Y1994321D01*
G01X1503974Y1991368D02*
X1503846Y1991340D01*
X1503758Y1991267D01*
X1503727Y1991171D01*
G01X1503974Y1988218D02*
X1503846Y1988191D01*
X1503758Y1988118D01*
X1503727Y1988022D01*
G01X1503974Y1985069D02*
X1503846Y1985041D01*
X1503758Y1984968D01*
X1503727Y1984872D01*
G01X1503974Y1981919D02*
X1503846Y1981891D01*
X1503758Y1981819D01*
X1503727Y1981722D01*
G01X1503974Y1975620D02*
X1503846Y1975592D01*
X1503758Y1975519D01*
X1503727Y1975423D01*
G01X1503974Y1972470D02*
X1503846Y1972443D01*
X1503758Y1972370D01*
X1503727Y1972274D01*
G01X1503974Y1969321D02*
X1503846Y1969293D01*
X1503758Y1969220D01*
X1503727Y1969124D01*
G01X1503974Y1966171D02*
X1503846Y1966143D01*
X1503758Y1966071D01*
X1503727Y1965974D01*
G01X1503974Y1963022D02*
X1503846Y1962994D01*
X1503758Y1962921D01*
X1503727Y1962825D01*
G01X1510035Y2011937D02*
X1503717D01*
G01Y2010952D02*
X1510035D01*
G01X1509772Y2010756D02*
X1503964D01*
G01X1503974Y2010266D02*
X1510058D01*
G01X1503727Y2010069D02*
X1510338D01*
G01Y2009675D02*
X1503727D01*
G01X1506209Y2009577D02*
X1528401D01*
G01X1520212Y2009557D02*
X1501709D01*
G01X1503974Y2009478D02*
X1510058D01*
G01X1506209Y2008396D02*
X1499740D01*
G01X1509817Y2007608D02*
X1503904D01*
G01X1528401Y2007214D02*
X1501709D01*
G01X1503974Y2007116D02*
X1510058D01*
G01X1510241Y2007018D02*
X1503499D01*
G01X1503727Y2006919D02*
X1510338D01*
G01X1503499Y2006624D02*
X1510241D01*
G01X1510338Y2006525D02*
X1503727D01*
G01X1503974Y2006329D02*
X1510058D01*
G01X1509817Y2006033D02*
X1503904D01*
G01X1503974Y2003966D02*
X1510058D01*
G01X1503727Y2003770D02*
X1510338D01*
G01Y2003376D02*
X1503727D01*
G01X1503974Y2003179D02*
X1510058D01*
G01X1500751Y2003120D02*
X1520212D01*
G01X1509749Y2002608D02*
X1504004D01*
G01X1510176Y2002018D02*
X1503590D01*
G01Y2001624D02*
X1510176D01*
G01X1504004Y2001033D02*
X1509749D01*
G01X1503974Y2000817D02*
X1510058D01*
G01X1503727Y2000620D02*
X1510338D01*
G01Y2000226D02*
X1503727D01*
G01X1503974Y2000029D02*
X1510058D01*
G01X1503974Y1997667D02*
X1510058D01*
G01X1509749Y1997608D02*
X1504004D01*
G01X1503727Y1997470D02*
X1510338D01*
G01Y1997077D02*
X1503727D01*
G01X1510176Y1997018D02*
X1503590D01*
G01X1503974Y1996880D02*
X1510058D01*
G01X1503590Y1996624D02*
X1510176D01*
G01X1504004Y1996033D02*
X1509749D01*
G01X1503974Y1994518D02*
X1510058D01*
G01X1503727Y1994321D02*
X1510338D01*
G01Y1993927D02*
X1503727D01*
G01X1503974Y1993730D02*
X1510058D01*
G01X1507781Y1992608D02*
X1502036D01*
G01X1508207Y1992018D02*
X1501621D01*
G01Y1991624D02*
X1508207D01*
G01X1503974Y1991368D02*
X1510058D01*
G01X1503727Y1991171D02*
X1510338D01*
G01X1502036Y1991033D02*
X1507781D01*
G01X1501709Y1990876D02*
X1528401D01*
G01X1510338Y1990777D02*
X1503727D01*
G01X1503974Y1990581D02*
X1510058D01*
G01X1528401Y1988514D02*
X1501709D01*
G01X1503974Y1988218D02*
X1510058D01*
G01X1503727Y1988022D02*
X1510338D01*
G01Y1987628D02*
X1503727D01*
G01X1509749Y1987608D02*
X1504004D01*
G01X1503974Y1987431D02*
X1510058D01*
G01X1510176Y1987018D02*
X1503590D01*
G01Y1986624D02*
X1510176D01*
G01X1504004Y1986033D02*
X1509749D01*
G01X1503974Y1985069D02*
X1510058D01*
G01X1503727Y1984872D02*
X1510338D01*
G01Y1984478D02*
X1503727D01*
G01X1503974Y1984281D02*
X1510058D01*
G01X1509749Y1982608D02*
X1504004D01*
G01X1510176Y1982018D02*
X1503590D01*
G01X1503974Y1981919D02*
X1510058D01*
G01X1503727Y1981722D02*
X1510338D01*
G01X1503590Y1981624D02*
X1510176D01*
G01X1510338Y1981329D02*
X1503727D01*
G01X1503974Y1981132D02*
X1510058D01*
G01X1504004Y1981033D02*
X1509749D01*
G01X1503974Y1978770D02*
X1510058D01*
G01X1503727Y1978573D02*
X1510338D01*
G01Y1978179D02*
X1503727D01*
G01X1503974Y1977982D02*
X1510058D01*
G01X1509749Y1977608D02*
X1504004D01*
G01X1510176Y1977018D02*
X1503590D01*
G01Y1976624D02*
X1510176D01*
G01X1504004Y1976033D02*
X1509749D01*
G01X1503974Y1975620D02*
X1510058D01*
G01X1503727Y1975423D02*
X1510338D01*
G01Y1975029D02*
X1503727D01*
G01X1503974Y1974833D02*
X1510058D01*
G01X1509749Y1972608D02*
X1504004D01*
G01X1503974Y1972470D02*
X1510058D01*
G01X1503727Y1972274D02*
X1510338D01*
G01X1510176Y1972018D02*
X1503590D01*
G01X1501709Y1971978D02*
X1528401D01*
G01X1510338Y1971880D02*
X1503727D01*
G01X1503974Y1971683D02*
X1510058D01*
G01X1503590Y1971624D02*
X1510176D01*
G01X1504004Y1971033D02*
X1509749D01*
G01X1528401Y1969616D02*
X1501709D01*
G01X1503974Y1969321D02*
X1510058D01*
G01X1503727Y1969124D02*
X1510338D01*
G01Y1968730D02*
X1503727D01*
G01X1503974Y1968533D02*
X1510058D01*
G01X1509749Y1967608D02*
X1504004D01*
G01X1510176Y1967018D02*
X1503590D01*
G01Y1966624D02*
X1510176D01*
G01X1509023Y1984281D02*
X1509050Y1984285D01*
X1509075Y1984296D01*
X1509099Y1984314D01*
X1509121Y1984339D01*
X1509138Y1984369D01*
X1509150Y1984403D01*
X1509158Y1984439D01*
X1509161Y1984478D01*
G01X1509023Y1981132D02*
X1509050Y1981136D01*
X1509075Y1981147D01*
X1509099Y1981165D01*
X1509121Y1981189D01*
X1509138Y1981219D01*
X1509150Y1981253D01*
X1509158Y1981290D01*
X1509161Y1981329D01*
G01X1509023Y1977982D02*
X1509050Y1977986D01*
X1509075Y1977997D01*
X1509099Y1978015D01*
X1509121Y1978040D01*
X1509138Y1978070D01*
X1509150Y1978103D01*
X1509158Y1978140D01*
X1509161Y1978179D01*
G01X1509023Y1974833D02*
X1509050Y1974836D01*
X1509075Y1974847D01*
X1509099Y1974865D01*
X1509121Y1974890D01*
X1509138Y1974920D01*
X1509150Y1974954D01*
X1509158Y1974991D01*
X1509161Y1975029D01*
G01X1509023Y1971683D02*
X1509050Y1971687D01*
X1509075Y1971698D01*
X1509099Y1971716D01*
X1509121Y1971741D01*
X1509138Y1971770D01*
X1509150Y1971804D01*
X1509158Y1971841D01*
X1509161Y1971880D01*
G01X1509023Y1968533D02*
X1509050Y1968537D01*
X1509075Y1968548D01*
X1509099Y1968566D01*
X1509121Y1968591D01*
X1509138Y1968621D01*
X1509150Y1968655D01*
X1509158Y1968691D01*
X1509161Y1968730D01*
G01X1509023Y1965384D02*
X1509050Y1965388D01*
X1509075Y1965399D01*
X1509099Y1965417D01*
X1509121Y1965441D01*
X1509138Y1965471D01*
X1509150Y1965505D01*
X1509158Y1965542D01*
X1509161Y1965581D01*
G01X1509023Y1962234D02*
X1509050Y1962238D01*
X1509075Y1962249D01*
X1509099Y1962267D01*
X1509121Y1962292D01*
X1509138Y1962321D01*
X1509150Y1962355D01*
X1509158Y1962392D01*
X1509161Y1962431D01*
G01X1509023Y1959085D02*
X1509050Y1959088D01*
X1509075Y1959099D01*
X1509099Y1959117D01*
X1509121Y1959142D01*
X1509138Y1959172D01*
X1509150Y1959206D01*
X1509158Y1959242D01*
X1509161Y1959281D01*
G01X1509023Y1955935D02*
X1509050Y1955939D01*
X1509075Y1955950D01*
X1509099Y1955968D01*
X1509121Y1955993D01*
X1509138Y1956022D01*
X1509150Y1956056D01*
X1509158Y1956093D01*
X1509161Y1956132D01*
G01X1509023Y1952785D02*
X1509050Y1952789D01*
X1509075Y1952800D01*
X1509099Y1952818D01*
X1509121Y1952843D01*
X1509138Y1952873D01*
X1509150Y1952907D01*
X1509158Y1952943D01*
X1509161Y1952982D01*
G01X1509023Y1949636D02*
X1509050Y1949639D01*
X1509075Y1949651D01*
X1509099Y1949669D01*
X1509121Y1949693D01*
X1509138Y1949723D01*
X1509150Y1949757D01*
X1509158Y1949794D01*
X1509161Y1949833D01*
G01X1509023Y1946486D02*
X1509050Y1946490D01*
X1509075Y1946501D01*
X1509099Y1946519D01*
X1509121Y1946544D01*
X1509138Y1946573D01*
X1509150Y1946607D01*
X1509158Y1946644D01*
X1509161Y1946683D01*
G01X1509023Y1943337D02*
X1509050Y1943340D01*
X1509075Y1943351D01*
X1509099Y1943369D01*
X1509121Y1943394D01*
X1509138Y1943424D01*
X1509150Y1943458D01*
X1509158Y1943494D01*
X1509161Y1943533D01*
G01X1503974Y1959872D02*
X1503846Y1959844D01*
X1503758Y1959771D01*
X1503727Y1959675D01*
G01X1503974Y1956722D02*
X1503846Y1956695D01*
X1503758Y1956622D01*
X1503727Y1956525D01*
G01X1503974Y1953573D02*
X1503846Y1953545D01*
X1503758Y1953472D01*
X1503727Y1953376D01*
G01X1503974Y1947274D02*
X1503846Y1947246D01*
X1503758Y1947173D01*
X1503727Y1947077D01*
G01X1503974Y1944124D02*
X1503846Y1944096D01*
X1503758Y1944023D01*
X1503727Y1943927D01*
G01X1508945Y2012134D02*
X1508974Y2012130D01*
X1509001Y2012119D01*
X1509027Y2012101D01*
X1509049Y2012076D01*
X1509068Y2012046D01*
X1509081Y2012012D01*
X1509090Y2011976D01*
X1509093Y2011937D01*
G01X1503974Y1966171D02*
X1510058D01*
G01X1504004Y1966033D02*
X1509749D01*
G01X1503727Y1965974D02*
X1510338D01*
G01Y1965581D02*
X1503727D01*
G01X1503974Y1965384D02*
X1510058D01*
G01X1503974Y1963022D02*
X1510058D01*
G01X1503727Y1962825D02*
X1510338D01*
G01X1509749Y1962608D02*
X1504004D01*
G01X1510338Y1962431D02*
X1503727D01*
G01X1503974Y1962234D02*
X1510058D01*
G01X1510176Y1962018D02*
X1503590D01*
G01Y1961624D02*
X1510176D01*
G01X1504004Y1961033D02*
X1509749D01*
G01X1503974Y1959872D02*
X1510058D01*
G01X1503727Y1959675D02*
X1510338D01*
G01Y1959281D02*
X1503727D01*
G01X1503974Y1959085D02*
X1510058D01*
G01X1509749Y1957608D02*
X1504004D01*
G01X1510176Y1957018D02*
X1503590D01*
G01X1503974Y1956722D02*
X1510058D01*
G01X1503590Y1956624D02*
X1510176D01*
G01X1503727Y1956525D02*
X1510338D01*
G01Y1956132D02*
X1503727D01*
G01X1504004Y1956033D02*
X1509749D01*
G01X1503974Y1955935D02*
X1510058D01*
G01X1503974Y1953573D02*
X1510058D01*
G01X1503727Y1953376D02*
X1510338D01*
G01X1501709Y1953081D02*
X1528401D01*
G01X1510338Y1952982D02*
X1503727D01*
G01X1503974Y1952785D02*
X1510058D01*
G01X1507781Y1952608D02*
X1502036D01*
G01X1508207Y1952018D02*
X1501621D01*
G01Y1951624D02*
X1508207D01*
G01X1502036Y1951033D02*
X1507781D01*
G01X1528401Y1950718D02*
X1501709D01*
G01X1503974Y1950423D02*
X1510058D01*
G01X1503727Y1950226D02*
X1510338D01*
G01Y1949833D02*
X1503727D01*
G01X1503974Y1949636D02*
X1510058D01*
G01X1509749Y1947608D02*
X1504004D01*
G01X1503974Y1947274D02*
X1510058D01*
G01X1503727Y1947077D02*
X1510338D01*
G01X1510176Y1947018D02*
X1503590D01*
G01X1510338Y1946683D02*
X1503727D01*
G01X1503590Y1946624D02*
X1510176D01*
G01X1503974Y1946486D02*
X1510058D01*
G01X1504004Y1946033D02*
X1509749D01*
G01X1503974Y1944124D02*
X1510058D01*
G01X1503727Y1943927D02*
X1510338D01*
G01Y1943533D02*
X1503727D01*
G01X1503974Y1943337D02*
X1510058D01*
G01X1503974Y1977982D02*
X1503847Y1978010D01*
X1503758Y1978082D01*
X1503727Y1978179D01*
G01X1503974Y1949636D02*
X1503847Y1949663D01*
X1503758Y1949736D01*
X1503727Y1949833D01*
G01X1507908Y2012134D02*
X1507914Y2012130D01*
X1507920Y2012119D01*
X1507926Y2012101D01*
X1507931Y2012076D01*
X1507935Y2012046D01*
X1507938Y2012012D01*
X1507940Y2011976D01*
X1507941Y2011937D01*
G01X1508572Y2010266D02*
X1508610Y2010239D01*
X1508638Y2010167D01*
X1508648Y2010069D01*
G01X1508572Y2007116D02*
X1508610Y2007090D01*
X1508638Y2007018D01*
X1508648Y2006919D01*
G01X1508572Y2003966D02*
X1508610Y2003940D01*
X1508638Y2003868D01*
X1508648Y2003770D01*
G01X1508572Y2000817D02*
X1508610Y2000790D01*
X1508638Y2000718D01*
X1508648Y2000620D01*
G01X1508572Y1997667D02*
X1508610Y1997641D01*
X1508638Y1997569D01*
X1508648Y1997470D01*
G01X1508572Y1994518D02*
X1508610Y1994491D01*
X1508638Y1994419D01*
X1508648Y1994321D01*
G01X1508572Y1991368D02*
X1508610Y1991342D01*
X1508638Y1991270D01*
X1508648Y1991171D01*
G01X1508572Y1988218D02*
X1508610Y1988192D01*
X1508638Y1988120D01*
X1508648Y1988022D01*
G01X1508572Y1985069D02*
X1508610Y1985042D01*
X1508638Y1984970D01*
X1508648Y1984872D01*
G01X1508572Y1981919D02*
X1508610Y1981893D01*
X1508638Y1981821D01*
X1508648Y1981722D01*
G01X1508572Y1978770D02*
X1508610Y1978743D01*
X1508638Y1978671D01*
X1508648Y1978573D01*
G01X1508572Y1975620D02*
X1508610Y1975594D01*
X1508638Y1975521D01*
X1508648Y1975423D01*
G01X1508572Y1972470D02*
X1508610Y1972444D01*
X1508638Y1972372D01*
X1508648Y1972274D01*
G01X1508572Y1969321D02*
X1508610Y1969294D01*
X1508638Y1969222D01*
X1508648Y1969124D01*
G01X1508572Y1966171D02*
X1508610Y1966145D01*
X1508638Y1966073D01*
X1508648Y1965974D01*
G01X1508572Y1963022D02*
X1508610Y1962995D01*
X1508638Y1962923D01*
X1508648Y1962825D01*
G01X1508572Y1959872D02*
X1508610Y1959846D01*
X1508638Y1959773D01*
X1508648Y1959675D01*
G01X1508572Y1956722D02*
X1508610Y1956696D01*
X1508638Y1956624D01*
X1508648Y1956525D01*
G01X1508572Y1953573D02*
X1508610Y1953546D01*
X1508638Y1953474D01*
X1508648Y1953376D01*
G01X1508572Y1950423D02*
X1508610Y1950397D01*
X1508638Y1950325D01*
X1508648Y1950226D01*
G01X1508572Y1947274D02*
X1508610Y1947247D01*
X1508638Y1947175D01*
X1508648Y1947077D01*
G01X1508572Y1944124D02*
X1508610Y1944097D01*
X1508638Y1944025D01*
X1508648Y1943927D01*
G01X1503499Y2006624D02*
X1503633Y2006426D01*
X1503768Y2006230D01*
X1503904Y2006033D01*
G01X1503590Y2001624D02*
X1503727Y2001426D01*
X1503865Y2001229D01*
X1504004Y2001033D01*
G01X1503590Y1996624D02*
X1503727Y1996426D01*
X1503865Y1996229D01*
X1504004Y1996033D01*
G01X1501621Y1991624D02*
X1501758Y1991426D01*
X1501896Y1991229D01*
X1502036Y1991033D01*
G01X1503590Y1986624D02*
X1503727Y1986426D01*
X1503865Y1986229D01*
X1504004Y1986033D01*
G01X1503590Y1981624D02*
X1503727Y1981426D01*
X1503865Y1981229D01*
X1504004Y1981033D01*
G01X1503590Y1976624D02*
X1503727Y1976426D01*
X1503865Y1976229D01*
X1504004Y1976033D01*
G01X1503590Y1971624D02*
X1503727Y1971426D01*
X1503865Y1971229D01*
X1504004Y1971033D01*
G01X1503590Y1966624D02*
X1503727Y1966426D01*
X1503865Y1966229D01*
X1504004Y1966033D01*
G01X1503590Y1961624D02*
X1503727Y1961426D01*
X1503865Y1961229D01*
X1504004Y1961033D01*
G01X1503590Y1956624D02*
X1503727Y1956426D01*
X1503865Y1956229D01*
X1504004Y1956033D01*
G01X1509817Y2007608D02*
X1510241Y2007018D01*
G01X1509749Y2002608D02*
X1510176Y2002018D01*
G01X1509749Y1997608D02*
X1510176Y1997018D01*
G01X1507781Y1992608D02*
X1508207Y1992018D01*
G01X1509749Y1987608D02*
X1510176Y1987018D01*
G01X1509749Y1982608D02*
X1510176Y1982018D01*
G01X1509749Y1977608D02*
X1510176Y1977018D01*
G01X1509749Y1972608D02*
X1510176Y1972018D01*
G01X1509749Y1967608D02*
X1510176Y1967018D01*
G01X1509749Y1962608D02*
X1510176Y1962018D01*
G01X1509749Y1957608D02*
X1510176Y1957018D01*
G01X1507781Y1952608D02*
X1508207Y1952018D01*
G01X1509749Y1947608D02*
X1510176Y1947018D01*
G01X1501621Y1951624D02*
X1501758Y1951426D01*
X1501896Y1951229D01*
X1502036Y1951033D01*
G01X1503590Y1946624D02*
X1503727Y1946426D01*
X1503865Y1946229D01*
X1504004Y1946033D01*
G01X1509060Y2007608D02*
X1509332Y2007018D01*
G01X1509060Y2002608D02*
X1509332Y2002018D01*
G01X1509060Y1997608D02*
X1509332Y1997018D01*
G01X1507091Y1992608D02*
X1507364Y1992018D01*
G01X1509060Y1987608D02*
X1509332Y1987018D01*
G01X1509060Y1982608D02*
X1509332Y1982018D01*
G01X1509060Y1977608D02*
X1509332Y1977018D01*
G01X1509060Y1972608D02*
X1509332Y1972018D01*
G01X1509060Y1967608D02*
X1509332Y1967018D01*
G01X1509060Y1962608D02*
X1509332Y1962018D01*
G01X1509060Y1957608D02*
X1509332Y1957018D01*
G01X1507091Y1952608D02*
X1507364Y1952018D01*
G01X1509060Y1947608D02*
X1509332Y1947018D01*
G01X1503727Y2009675D02*
X1503758Y2009578D01*
X1503847Y2009506D01*
X1503974Y2009478D01*
G01X1503727Y2006525D02*
X1503758Y2006428D01*
X1503847Y2006356D01*
X1503974Y2006329D01*
G01X1503727Y2003376D02*
X1503758Y2003279D01*
X1503847Y2003207D01*
X1503974Y2003179D01*
G01X1503727Y2000226D02*
X1503758Y2000129D01*
X1503847Y2000057D01*
X1503974Y2000029D01*
G01X1503727Y1997077D02*
X1503758Y1996980D01*
X1503847Y1996907D01*
X1503974Y1996880D01*
G01X1503727Y1993927D02*
X1503758Y1993830D01*
X1503847Y1993758D01*
X1503974Y1993730D01*
G01X1503727Y1990777D02*
X1503758Y1990680D01*
X1503847Y1990608D01*
X1503974Y1990581D01*
G01X1503727Y1987628D02*
X1503758Y1987531D01*
X1503847Y1987459D01*
X1503974Y1987431D01*
G01X1503727Y1984478D02*
X1503758Y1984381D01*
X1503847Y1984309D01*
X1503974Y1984281D01*
G01X1503727Y1981329D02*
X1503758Y1981232D01*
X1503847Y1981159D01*
X1503974Y1981132D01*
G01X1503727Y1975029D02*
X1503758Y1974932D01*
X1503847Y1974860D01*
X1503974Y1974833D01*
G01X1503717Y2010952D02*
X1503750Y2010853D01*
X1503838Y2010783D01*
X1503964Y2010756D01*
G01X1503727Y1971880D02*
X1503758Y1971783D01*
X1503847Y1971711D01*
X1503974Y1971683D01*
G01X1503727Y1968730D02*
X1503758Y1968633D01*
X1503847Y1968561D01*
X1503974Y1968533D01*
G01X1503727Y1965581D02*
X1503758Y1965484D01*
X1503847Y1965411D01*
X1503974Y1965384D01*
G01X1503727Y1962431D02*
X1503758Y1962334D01*
X1503847Y1962262D01*
X1503974Y1962234D01*
G01X1503727Y1959281D02*
X1503758Y1959184D01*
X1503847Y1959112D01*
X1503974Y1959085D01*
G01X1503727Y1956132D02*
X1503758Y1956035D01*
X1503847Y1955963D01*
X1503974Y1955935D01*
G01X1503727Y1952982D02*
X1503758Y1952885D01*
X1503847Y1952813D01*
X1503974Y1952785D01*
G01X1503727Y1946683D02*
X1503758Y1946586D01*
X1503847Y1946514D01*
X1503974Y1946486D01*
G01X1503727Y1943533D02*
X1503758Y1943436D01*
X1503847Y1943364D01*
X1503974Y1943337D01*
G01X1508208Y2007018D02*
X1508130Y2007608D01*
G01X1508208Y2002018D02*
X1508130Y2002608D01*
G01X1508208Y1997018D02*
X1508130Y1997608D01*
G01X1508208Y1987018D02*
X1508130Y1987608D01*
G01X1508208Y1982018D02*
X1508130Y1982608D01*
G01X1506239Y1992018D02*
X1506161Y1992608D01*
G01X1508208Y1977018D02*
X1508130Y1977608D01*
G01X1508208Y1972018D02*
X1508130Y1972608D01*
G01X1508208Y1967018D02*
X1508130Y1967608D01*
G01X1508208Y1962018D02*
X1508130Y1962608D01*
G01X1508208Y1957018D02*
X1508130Y1957608D01*
G01X1508208Y1947018D02*
X1508130Y1947608D01*
G01X1506239Y1952018D02*
X1506161Y1952608D01*
G01X1509161Y2010069D02*
X1509158Y2010107D01*
X1509151Y2010144D01*
X1509138Y2010178D01*
X1509121Y2010208D01*
X1509100Y2010232D01*
X1509076Y2010251D01*
X1509050Y2010262D01*
X1509023Y2010266D01*
G01X1509161Y2006919D02*
X1509158Y2006957D01*
X1509151Y2006994D01*
X1509138Y2007028D01*
X1509121Y2007058D01*
X1509100Y2007083D01*
X1509076Y2007101D01*
X1509050Y2007112D01*
X1509023Y2007116D01*
G01X1509161Y2003770D02*
X1509158Y2003808D01*
X1509151Y2003845D01*
X1509138Y2003879D01*
X1509121Y2003909D01*
X1509100Y2003933D01*
X1509076Y2003951D01*
X1509050Y2003963D01*
X1509023Y2003966D01*
G01X1509161Y2000620D02*
X1509158Y2000658D01*
X1509151Y2000695D01*
X1509138Y2000729D01*
X1509121Y2000759D01*
X1509100Y2000784D01*
X1509076Y2000802D01*
X1509050Y2000813D01*
X1509023Y2000817D01*
G01X1509161Y1997470D02*
X1509158Y1997509D01*
X1509151Y1997545D01*
X1509138Y1997579D01*
X1509121Y1997610D01*
X1509100Y1997634D01*
X1509076Y1997652D01*
X1509050Y1997663D01*
X1509023Y1997667D01*
G01X1509161Y1994321D02*
X1509158Y1994359D01*
X1509151Y1994396D01*
X1509138Y1994430D01*
X1509121Y1994460D01*
X1509100Y1994484D01*
X1509076Y1994503D01*
X1509050Y1994514D01*
X1509023Y1994518D01*
G01X1509161Y1991171D02*
X1509158Y1991209D01*
X1509151Y1991246D01*
X1509138Y1991280D01*
X1509121Y1991310D01*
X1509100Y1991335D01*
X1509076Y1991353D01*
X1509050Y1991364D01*
X1509023Y1991368D01*
G01X1509161Y1988022D02*
X1509158Y1988060D01*
X1509151Y1988097D01*
X1509138Y1988130D01*
X1509121Y1988161D01*
X1509100Y1988185D01*
X1509076Y1988203D01*
X1509050Y1988215D01*
X1509023Y1988218D01*
G01X1509161Y1984872D02*
X1509158Y1984910D01*
X1509151Y1984947D01*
X1509138Y1984981D01*
X1509121Y1985011D01*
X1509100Y1985036D01*
X1509076Y1985054D01*
X1509050Y1985065D01*
X1509023Y1985069D01*
G01X1509161Y1981722D02*
X1509158Y1981761D01*
X1509151Y1981797D01*
X1509138Y1981831D01*
X1509121Y1981862D01*
X1509100Y1981886D01*
X1509076Y1981904D01*
X1509050Y1981915D01*
X1509023Y1981919D01*
G01X1509161Y1978573D02*
X1509158Y1978611D01*
X1509151Y1978648D01*
X1509138Y1978682D01*
X1509121Y1978712D01*
X1509100Y1978736D01*
X1509076Y1978754D01*
X1509050Y1978766D01*
X1509023Y1978770D01*
G01X1509161Y1975423D02*
X1509158Y1975461D01*
X1509151Y1975498D01*
X1509138Y1975532D01*
X1509121Y1975562D01*
X1509100Y1975587D01*
X1509076Y1975605D01*
X1509050Y1975616D01*
X1509023Y1975620D01*
G01X1509161Y1972274D02*
X1509158Y1972312D01*
X1509151Y1972349D01*
X1509138Y1972382D01*
X1509121Y1972413D01*
X1509100Y1972437D01*
X1509076Y1972455D01*
X1509050Y1972466D01*
X1509023Y1972470D01*
G01X1509161Y1969124D02*
X1509158Y1969162D01*
X1509151Y1969199D01*
X1509138Y1969233D01*
X1509121Y1969263D01*
X1509100Y1969287D01*
X1509076Y1969306D01*
X1509050Y1969317D01*
X1509023Y1969321D01*
G01X1509161Y1965974D02*
X1509158Y1966013D01*
X1509151Y1966049D01*
X1509138Y1966083D01*
X1509121Y1966114D01*
X1509100Y1966138D01*
X1509076Y1966156D01*
X1509050Y1966167D01*
X1509023Y1966171D01*
G01X1509161Y1962825D02*
X1509158Y1962863D01*
X1509151Y1962900D01*
X1509138Y1962934D01*
X1509121Y1962964D01*
X1509100Y1962988D01*
X1509076Y1963006D01*
X1509050Y1963018D01*
X1509023Y1963022D01*
G01X1509161Y1959675D02*
X1509158Y1959713D01*
X1509151Y1959750D01*
X1509138Y1959784D01*
X1509121Y1959814D01*
X1509100Y1959839D01*
X1509076Y1959857D01*
X1509050Y1959868D01*
X1509023Y1959872D01*
G01X1509161Y1956525D02*
X1509158Y1956564D01*
X1509151Y1956601D01*
X1509138Y1956634D01*
X1509121Y1956665D01*
X1509100Y1956689D01*
X1509076Y1956707D01*
X1509050Y1956718D01*
X1509023Y1956722D01*
G01X1509161Y1953376D02*
X1509158Y1953414D01*
X1509151Y1953451D01*
X1509138Y1953485D01*
X1509121Y1953515D01*
X1509100Y1953539D01*
X1509076Y1953558D01*
X1509050Y1953569D01*
X1509023Y1953573D01*
G01X1509161Y1950226D02*
X1509158Y1950265D01*
X1509151Y1950301D01*
X1509138Y1950335D01*
X1509121Y1950365D01*
X1509100Y1950390D01*
X1509076Y1950408D01*
X1509050Y1950419D01*
X1509023Y1950423D01*
G01X1509161Y1947077D02*
X1509158Y1947115D01*
X1509151Y1947152D01*
X1509138Y1947186D01*
X1509121Y1947216D01*
X1509100Y1947240D01*
X1509076Y1947258D01*
X1509050Y1947270D01*
X1509023Y1947274D01*
G01X1509161Y1943927D02*
X1509158Y1943965D01*
X1509151Y1944002D01*
X1509138Y1944036D01*
X1509121Y1944066D01*
X1509100Y1944091D01*
X1509076Y1944109D01*
X1509050Y1944120D01*
X1509023Y1944124D01*
G01X1508648Y1943533D02*
X1508638Y1943435D01*
X1508610Y1943363D01*
X1508572Y1943337D01*
G01X1508648Y1946683D02*
X1508638Y1946585D01*
X1508610Y1946513D01*
X1508572Y1946486D01*
G01X1508648Y1949833D02*
X1508638Y1949734D01*
X1508610Y1949662D01*
X1508572Y1949636D01*
G01X1508648Y1952982D02*
X1508638Y1952884D01*
X1508610Y1952812D01*
X1508572Y1952785D01*
G01X1508648Y1956132D02*
X1508638Y1956033D01*
X1508610Y1955961D01*
X1508572Y1955935D01*
G01X1509093Y2010952D02*
X1509090Y2010914D01*
X1509081Y2010877D01*
X1509068Y2010844D01*
X1509049Y2010813D01*
X1509027Y2010789D01*
X1509002Y2010771D01*
X1508974Y2010759D01*
X1508945Y2010756D01*
G01X1507941Y2010952D02*
X1507940Y2010914D01*
X1507938Y2010877D01*
X1507935Y2010844D01*
X1507931Y2010813D01*
X1507926Y2010789D01*
X1507921Y2010771D01*
X1507915Y2010759D01*
X1507908Y2010756D01*
G01X1510338Y2009675D02*
Y2010069D01*
G01Y2006525D02*
Y2006919D01*
G01Y2003376D02*
Y2003770D01*
G01Y2000226D02*
Y2000620D01*
G01Y1997077D02*
Y1997470D01*
G01Y1993927D02*
Y1994321D01*
G01Y1990777D02*
Y1991171D01*
G01Y1987628D02*
Y1988022D01*
G01Y1984478D02*
Y1984872D01*
G01Y1981329D02*
Y1981722D01*
G01Y1978179D02*
Y1978573D01*
G01Y1975029D02*
Y1975423D01*
G01Y1971880D02*
Y1972274D01*
G01Y1965581D02*
Y1965974D01*
G01Y1968730D02*
Y1969124D01*
G01Y1962431D02*
Y1962825D01*
G01Y1956132D02*
Y1956525D01*
G01Y1959281D02*
Y1959675D01*
G01Y1952982D02*
Y1953376D01*
G01Y1946683D02*
Y1947077D01*
G01Y1949833D02*
Y1950226D01*
G01Y1943533D02*
Y1943927D01*
G01X1510241Y2007018D02*
Y2006624D01*
G01X1510176Y1947018D02*
Y1946624D01*
G01Y1957018D02*
Y1956624D01*
G01Y1962018D02*
Y1961624D01*
G01Y1967018D02*
Y1966624D01*
G01Y1972018D02*
Y1971624D01*
G01Y1977018D02*
Y1976624D01*
G01Y1982018D02*
Y1981624D01*
G01Y1987018D02*
Y1986624D01*
G01Y1997018D02*
Y1996624D01*
G01Y2002018D02*
Y2001624D01*
G01X1510035Y2011937D02*
Y2010952D01*
G01X1509332Y1947018D02*
Y1946624D01*
G01Y1957018D02*
Y1956624D01*
G01Y1962018D02*
Y1961624D01*
G01Y1967018D02*
Y1966624D01*
G01Y1972018D02*
Y1971624D01*
G01Y1977018D02*
Y1976624D01*
G01Y1982018D02*
Y1981624D01*
G01Y1987018D02*
Y1986624D01*
G01Y1997018D02*
Y1996624D01*
G01Y2002018D02*
Y2001624D01*
G01Y2007018D02*
Y2006624D01*
G01X1509161Y2009675D02*
Y2010069D01*
G01Y2006525D02*
Y2006919D01*
G01Y2003376D02*
Y2003770D01*
G01Y2000226D02*
Y2000620D01*
G01Y1997077D02*
Y1997470D01*
G01Y1993927D02*
Y1994321D01*
G01Y1990777D02*
Y1991171D01*
G01Y1987628D02*
Y1988022D01*
G01Y1984478D02*
Y1984872D01*
G01Y1981329D02*
Y1981722D01*
G01Y1978179D02*
Y1978573D01*
G01Y1975029D02*
Y1975423D01*
G01Y1971880D02*
Y1972274D01*
G01Y1965581D02*
Y1965974D01*
G01Y1968730D02*
Y1969124D01*
G01Y1962431D02*
Y1962825D01*
G01Y1956132D02*
Y1956525D01*
G01Y1959281D02*
Y1959675D01*
G01Y1952982D02*
Y1953376D01*
G01Y1946683D02*
Y1947077D01*
G01Y1949833D02*
Y1950226D01*
G01Y1943533D02*
Y1943927D01*
G01X1509093Y2011937D02*
Y2010952D01*
G01X1508648Y1943927D02*
Y1943533D01*
G01Y1947077D02*
Y1946683D01*
G01Y1950226D02*
Y1949833D01*
G01Y1953376D02*
Y1952982D01*
G01Y1956525D02*
Y1956132D01*
G01Y1959675D02*
Y1959281D01*
G01Y1962825D02*
Y1962431D01*
G01Y1965974D02*
Y1965581D01*
G01Y1969124D02*
Y1968730D01*
G01Y1972274D02*
Y1971880D01*
G01Y1978573D02*
Y1978179D01*
G01Y1975423D02*
Y1975029D01*
G01Y1981722D02*
Y1981329D01*
G01Y1988022D02*
Y1987628D01*
G01Y1984872D02*
Y1984478D01*
G01Y1991171D02*
Y1990777D01*
G01Y1997470D02*
Y1997077D01*
G01Y1994321D02*
Y1993927D01*
G01Y2000620D02*
Y2000226D01*
G01Y2006919D02*
Y2006525D01*
G01Y2003770D02*
Y2003376D01*
G01Y2010069D02*
Y2009675D01*
G01X1508208Y2006624D02*
Y2007018D01*
G01Y2001624D02*
Y2002018D01*
G01Y1996624D02*
Y1997018D01*
G01Y1986624D02*
Y1987018D01*
G01Y1981624D02*
Y1982018D01*
G01Y1976624D02*
Y1977018D01*
G01Y1971624D02*
Y1972018D01*
G01Y1966624D02*
Y1967018D01*
G01Y1961624D02*
Y1962018D01*
G01Y1956624D02*
Y1957018D01*
G01Y1946624D02*
Y1947018D01*
G01X1508207Y1952018D02*
Y1951624D01*
G01Y1992018D02*
Y1991624D01*
G01X1507941Y2011937D02*
Y2010952D01*
G01X1507364Y1952018D02*
Y1951624D01*
G01Y1992018D02*
Y1991624D01*
G01X1506239D02*
Y1992018D01*
G01Y1951624D02*
Y1952018D01*
G01X1506209Y2008396D02*
Y2009577D01*
G01X1503727Y1943927D02*
Y1943533D01*
G01Y1947077D02*
Y1946683D01*
G01Y1950226D02*
Y1949833D01*
G01Y1953376D02*
Y1952982D01*
G01Y1956525D02*
Y1956132D01*
G01Y1959675D02*
Y1959281D01*
G01Y1962825D02*
Y1962431D01*
G01Y1965974D02*
Y1965581D01*
G01Y1969124D02*
Y1968730D01*
G01Y1972274D02*
Y1971880D01*
G01Y1978573D02*
Y1978179D01*
G01Y1975423D02*
Y1975029D01*
G01Y1981722D02*
Y1981329D01*
G01Y1988022D02*
Y1987628D01*
G01Y1984872D02*
Y1984478D01*
G01Y1991171D02*
Y1990777D01*
G01Y1997470D02*
Y1997077D01*
G01Y1994321D02*
Y1993927D01*
G01Y2000620D02*
Y2000226D01*
G01Y2006919D02*
Y2006525D01*
G01Y2003770D02*
Y2003376D01*
G01Y2010069D02*
Y2009675D01*
G01X1503717Y2010952D02*
Y2011937D01*
G01X1503590Y2001624D02*
Y2002018D01*
G01Y1996624D02*
Y1997018D01*
G01Y1986624D02*
Y1987018D01*
G01Y1981624D02*
Y1982018D01*
G01Y1976624D02*
Y1977018D01*
G01Y1971624D02*
Y1972018D01*
G01Y1966624D02*
Y1967018D01*
G01Y1961624D02*
Y1962018D01*
G01Y1956624D02*
Y1957018D01*
G01Y1946624D02*
Y1947018D01*
G01X1503499Y2006624D02*
Y2007018D01*
G01X1501621Y1991624D02*
Y1992018D01*
G01Y1951624D02*
Y1952018D01*
G01X1500921Y2030246D02*
Y2008396D01*
G01X1500751Y2003120D02*
Y2008600D01*
G01X1508208Y1946624D02*
X1508130Y1946033D01*
G01X1508208Y1956624D02*
X1508130Y1956033D01*
G01X1508208Y1961624D02*
X1508130Y1961033D01*
G01X1506239Y1951624D02*
X1506161Y1951033D01*
G01X1508208Y1966624D02*
X1508130Y1966033D01*
G01X1508208Y1971624D02*
X1508130Y1971033D01*
G01X1508208Y1976624D02*
X1508130Y1976033D01*
G01X1508208Y1981624D02*
X1508130Y1981033D01*
G01X1508208Y1986624D02*
X1508130Y1986033D01*
G01X1508208Y1996624D02*
X1508130Y1996033D01*
G01X1508208Y2001624D02*
X1508130Y2001033D01*
G01X1506239Y1991624D02*
X1506161Y1991033D01*
G01X1508208Y2006624D02*
X1508130Y2006033D01*
G01X1508648Y1959281D02*
X1508638Y1959183D01*
X1508610Y1959111D01*
X1508572Y1959085D01*
G01X1508648Y1962431D02*
X1508638Y1962333D01*
X1508610Y1962261D01*
X1508572Y1962234D01*
G01X1508648Y1965581D02*
X1508638Y1965482D01*
X1508610Y1965410D01*
X1508572Y1965384D01*
G01X1508648Y1968730D02*
X1508638Y1968632D01*
X1508610Y1968560D01*
X1508572Y1968533D01*
G01X1508648Y1971880D02*
X1508638Y1971781D01*
X1508610Y1971709D01*
X1508572Y1971683D01*
G01X1508648Y1975029D02*
X1508638Y1974931D01*
X1508610Y1974859D01*
X1508572Y1974833D01*
G01X1508648Y1978179D02*
X1508638Y1978081D01*
X1508610Y1978009D01*
X1508572Y1977982D01*
G01X1508648Y1981329D02*
X1508638Y1981230D01*
X1508610Y1981158D01*
X1508572Y1981132D01*
G01X1508648Y1984478D02*
X1508638Y1984380D01*
X1508610Y1984308D01*
X1508572Y1984281D01*
G01X1508648Y1987628D02*
X1508638Y1987530D01*
X1508610Y1987457D01*
X1508572Y1987431D01*
G01X1508648Y1990777D02*
X1508638Y1990679D01*
X1508610Y1990607D01*
X1508572Y1990581D01*
G01X1508648Y1993927D02*
X1508638Y1993829D01*
X1508610Y1993757D01*
X1508572Y1993730D01*
G01X1508648Y1997077D02*
X1508638Y1996978D01*
X1508610Y1996906D01*
X1508572Y1996880D01*
G01X1508648Y2000226D02*
X1508638Y2000128D01*
X1508610Y2000056D01*
X1508572Y2000029D01*
G01X1508648Y2003376D02*
X1508638Y2003278D01*
X1508610Y2003205D01*
X1508572Y2003179D01*
G01X1508648Y2006525D02*
X1508638Y2006427D01*
X1508610Y2006355D01*
X1508572Y2006329D01*
G01X1508648Y2009675D02*
X1508638Y2009577D01*
X1508610Y2009505D01*
X1508572Y2009478D01*
G01X1503727Y1950226D02*
X1503760Y1950325D01*
X1503848Y1950396D01*
X1503974Y1950423D01*
G01X1503727Y1978573D02*
X1503760Y1978672D01*
X1503848Y1978743D01*
X1503974Y1978770D01*
G01X1509332Y1946624D02*
X1509060Y1946033D01*
G01X1507364Y1951624D02*
X1507091Y1951033D01*
G01X1509332Y1956624D02*
X1509060Y1956033D01*
G01X1509332Y1961624D02*
X1509060Y1961033D01*
G01X1509332Y1966624D02*
X1509060Y1966033D01*
G01X1509332Y1971624D02*
X1509060Y1971033D01*
G01X1509332Y1976624D02*
X1509060Y1976033D01*
G01X1509332Y1981624D02*
X1509060Y1981033D01*
G01X1509332Y1986624D02*
X1509060Y1986033D01*
G01X1507364Y1991624D02*
X1507091Y1991033D01*
G01X1509332Y1996624D02*
X1509060Y1996033D01*
G01X1509332Y2001624D02*
X1509060Y2001033D01*
G01X1509332Y2006624D02*
X1509060Y2006033D01*
G01X1509749Y1946033D02*
X1510176Y1946624D01*
G01X1507781Y1951033D02*
X1508207Y1951624D01*
G01X1509749Y1956033D02*
X1510176Y1956624D01*
G01X1509749Y1961033D02*
X1510176Y1961624D01*
G01X1509749Y1966033D02*
X1510176Y1966624D01*
G01X1509749Y1971033D02*
X1510176Y1971624D01*
G01X1509749Y1976033D02*
X1510176Y1976624D01*
G01X1509749Y1981033D02*
X1510176Y1981624D01*
G01X1509749Y1986033D02*
X1510176Y1986624D01*
G01X1507781Y1991033D02*
X1508207Y1991624D01*
G01X1509749Y1996033D02*
X1510176Y1996624D01*
G01X1509749Y2001033D02*
X1510176Y2001624D01*
G01X1509817Y2006033D02*
X1510241Y2006624D01*
G01X1504004Y1947608D02*
X1503865Y1947412D01*
X1503727Y1947215D01*
X1503590Y1947018D01*
G01X1502036Y1952608D02*
X1501896Y1952412D01*
X1501758Y1952215D01*
X1501621Y1952018D01*
G01X1504004Y1957608D02*
X1503865Y1957412D01*
X1503727Y1957215D01*
X1503590Y1957018D01*
G01X1504004Y1962608D02*
X1503865Y1962412D01*
X1503727Y1962215D01*
X1503590Y1962018D01*
G01X1504004Y1967608D02*
X1503865Y1967412D01*
X1503727Y1967215D01*
X1503590Y1967018D01*
G01X1504004Y1972608D02*
X1503865Y1972412D01*
X1503727Y1972215D01*
X1503590Y1972018D01*
G01X1504004Y1977608D02*
X1503865Y1977412D01*
X1503727Y1977215D01*
X1503590Y1977018D01*
G01X1504004Y1982608D02*
X1503865Y1982412D01*
X1503727Y1982215D01*
X1503590Y1982018D01*
G01X1504004Y1987608D02*
X1503865Y1987412D01*
X1503727Y1987215D01*
X1503590Y1987018D01*
G01X1502036Y1992608D02*
X1501896Y1992412D01*
X1501758Y1992215D01*
X1501621Y1992018D01*
G01X1504004Y1997608D02*
X1503865Y1997412D01*
X1503727Y1997215D01*
X1503590Y1997018D01*
G01X1504004Y2002608D02*
X1503865Y2002412D01*
X1503727Y2002215D01*
X1503590Y2002018D01*
G01X1503904Y2007608D02*
X1503768Y2007412D01*
X1503633Y2007215D01*
X1503499Y2007018D01*
G01X1499740Y2007588D02*
X1501709Y2009557D01*
G01X1531945Y1941033D02*
G03X1531551Y1940640I0J-394D01*
G01Y1943002D02*
G03X1531945Y1942608I394J0D01*
G01X1534976Y1942805D02*
X1533992D01*
G01X1539110Y1942608D02*
X1531945D01*
G01X1539110Y1941033D02*
X1531945D01*
G01X1542605Y1940974D02*
X1549937D01*
G01X1542457D02*
X1530449D01*
G01X1534976Y1940837D02*
X1533992D01*
G01X1534976Y1940443D02*
X1533992D01*
G01X1534976Y1940246D02*
X1533992D01*
G01X1542457Y1940187D02*
X1530449D01*
G01X1549937D02*
X1542605D01*
G01X1549937Y1940974D02*
Y1940187D01*
G01X1548163Y1940974D02*
Y1940187D01*
G01X1547975D02*
Y1940974D01*
G01X1545138Y1940187D02*
Y1940974D01*
G01X1544197D02*
Y1940187D01*
G01X1542605Y1940974D02*
Y1940187D01*
G01X1542457Y1940974D02*
Y1940187D01*
G01X1541519Y1940974D02*
Y1943337D01*
G01X1539791Y1940974D02*
Y1940187D01*
G01X1539110Y1941033D02*
Y1942608D01*
G01X1538139Y1940187D02*
Y1940974D01*
G01X1536156Y1940187D02*
Y1940974D01*
G01X1535961Y1942608D02*
Y1941033D01*
G01X1534976Y1943396D02*
Y1940246D01*
G01X1533992Y1943396D02*
Y1940246D01*
G01X1533008Y1942608D02*
Y1941033D01*
G01X1532793Y1940974D02*
Y1940187D01*
G01X1532417Y1940974D02*
Y1940187D01*
G01X1532391Y1940974D02*
Y1940187D01*
G01X1531945Y1986033D02*
G03X1531551Y1985640I0J-394D01*
G01Y1988002D02*
G03X1531945Y1987608I394J0D01*
G01Y2001033D02*
G03X1531551Y2000640I0J-394D01*
G01Y2003002D02*
G03X1531945Y2002608I394J0D01*
G01Y1996033D02*
G03X1531551Y1995640I0J-394D01*
G01Y1998002D02*
G03X1531945Y1997608I394J0D01*
G01Y1976033D02*
G03X1531551Y1975640I0J-394D01*
G01Y1978002D02*
G03X1531945Y1977608I394J0D01*
G01Y1971033D02*
G03X1531551Y1970640I0J-394D01*
G01Y1973002D02*
G03X1531945Y1972608I394J0D01*
G01Y1961033D02*
G03X1531551Y1960640I0J-394D01*
G01Y1963002D02*
G03X1531945Y1962608I394J0D01*
G01Y1966033D02*
G03X1531551Y1965640I0J-394D01*
G01Y1968002D02*
G03X1531945Y1967608I394J0D01*
G01Y1981033D02*
G03X1531551Y1980640I0J-394D01*
G01Y1983002D02*
G03X1531945Y1982608I394J0D01*
G01Y2006033D02*
G03X1531551Y2005640I0J-394D01*
G01Y2008002D02*
G03X1531945Y2007608I394J0D01*
G01Y1956033D02*
G03X1531551Y1955640I0J-394D01*
G01Y1958002D02*
G03X1531945Y1957608I394J0D01*
G01Y1946033D02*
G03X1531551Y1945640I0J-394D01*
G01Y1948002D02*
G03X1531945Y1947608I394J0D01*
G01X1531551Y2010856D02*
X1537576D01*
G01X1533442Y2010659D02*
X1532458D01*
G01X1533442Y2010463D02*
X1532458D01*
G01X1542605Y2010266D02*
X1549937D01*
G01X1542457D02*
X1530449D01*
G01X1533442Y2010167D02*
X1535567D01*
G01X1530449Y2009675D02*
X1537984D01*
G01X1531551Y2009557D02*
X1530449D01*
G01X1542457Y2009478D02*
X1530449D01*
G01X1549937D02*
X1542605D01*
G01X1534976Y2008396D02*
X1533992D01*
G01X1534976Y2008199D02*
X1533992D01*
G01X1534976Y2007805D02*
X1533992D01*
G01X1531945Y2007608D02*
X1539110D01*
G01X1542605Y2007116D02*
X1549937D01*
G01X1542457D02*
X1530449D01*
G01X1542457Y2006329D02*
X1530449D01*
G01X1549937D02*
X1542605D01*
G01X1531945Y2006033D02*
X1539110D01*
G01X1534976Y2005837D02*
X1533992D01*
G01X1534976Y2005443D02*
X1533992D01*
G01X1534976Y2005246D02*
X1533992D01*
G01X1542605Y2003966D02*
X1549937D01*
G01X1542457D02*
X1530449D01*
G01X1534976Y2003396D02*
X1533992D01*
G01X1534976Y2003199D02*
X1533992D01*
G01X1542457Y2003179D02*
X1530449D01*
G01X1549937D02*
X1542605D01*
G01X1534976Y2002805D02*
X1533992D01*
G01X1531945Y2002608D02*
X1539110D01*
G01X1531945Y2001033D02*
X1539110D01*
G01X1534976Y2000837D02*
X1533992D01*
G01X1542605Y2000817D02*
X1549937D01*
G01X1542457D02*
X1530449D01*
G01X1534976Y2000443D02*
X1533992D01*
G01X1534976Y2000246D02*
X1533992D01*
G01X1542457Y2000029D02*
X1530449D01*
G01X1549937D02*
X1542605D01*
G01X1534976Y1998396D02*
X1533992D01*
G01X1534976Y1998199D02*
X1533992D01*
G01X1534976Y1997805D02*
X1533992D01*
G01X1542605Y1997667D02*
X1549937D01*
G01X1542457D02*
X1530449D01*
G01X1531945Y1997608D02*
X1539110D01*
G01X1542457Y1996880D02*
X1530449D01*
G01X1549937D02*
X1542605D01*
G01X1531945Y1996033D02*
X1539110D01*
G01X1534976Y1995837D02*
X1533992D01*
G01X1534976Y1995443D02*
X1533992D01*
G01X1534976Y1995246D02*
X1533992D01*
G01X1542605Y1994518D02*
X1549937D01*
G01X1542457D02*
X1530449D01*
G01Y1994025D02*
X1531551D01*
G01X1542457Y1993730D02*
X1530449D01*
G01X1549937D02*
X1542605D01*
G01X1533008Y1993396D02*
X1532024D01*
G01X1533008Y1993199D02*
X1532024D01*
G01X1533008Y1992805D02*
X1532024D01*
G01X1531551Y1992608D02*
X1537142D01*
G01X1542605Y1991368D02*
X1549937D01*
G01X1542457D02*
X1530449D01*
G01X1531551Y1991033D02*
X1537142D01*
G01X1533008Y1990837D02*
X1532024D01*
G01X1542457Y1990581D02*
X1530449D01*
G01X1549937D02*
X1542605D01*
G01X1533008Y1990443D02*
X1532024D01*
G01X1533008Y1990246D02*
X1532024D01*
G01X1531551Y1989616D02*
X1530449D01*
G01X1534976Y1988396D02*
X1533992D01*
G01X1542605Y1988218D02*
X1549937D01*
G01X1542457D02*
X1530449D01*
G01X1534976Y1988199D02*
X1533992D01*
G01X1534976Y1987805D02*
X1533992D01*
G01X1531945Y1987608D02*
X1539110D01*
G01X1542457Y1987431D02*
X1530449D01*
G01X1549937D02*
X1542605D01*
G01X1531945Y1986033D02*
X1539110D01*
G01X1534976Y1985837D02*
X1533992D01*
G01X1534976Y1985443D02*
X1533992D01*
G01X1534976Y1985246D02*
X1533992D01*
G01X1542605Y1985069D02*
X1549937D01*
G01X1542457D02*
X1530449D01*
G01X1542457Y1984281D02*
X1530449D01*
G01X1549937D02*
X1542605D01*
G01X1534976Y1983396D02*
X1533992D01*
G01X1534976Y1983199D02*
X1533992D01*
G01X1534976Y1982805D02*
X1533992D01*
G01X1531945Y1982608D02*
X1539110D01*
G01X1542605Y1981919D02*
X1549937D01*
G01X1542457D02*
X1530449D01*
G01X1542457Y1981132D02*
X1530449D01*
G01X1549937D02*
X1542605D01*
G01X1531945Y1981033D02*
X1539110D01*
G01X1534976Y1980837D02*
X1533992D01*
G01X1534976Y1980443D02*
X1533992D01*
G01X1534976Y1980246D02*
X1533992D01*
G01X1542605Y1978770D02*
X1549937D01*
G01X1542457D02*
X1530449D01*
G01X1534976Y1978396D02*
X1533992D01*
G01X1534976Y1978199D02*
X1533992D01*
G01X1542457Y1977982D02*
X1530449D01*
G01X1549937D02*
X1542605D01*
G01X1534976Y1977805D02*
X1533992D01*
G01X1531945Y1977608D02*
X1539110D01*
G01X1531945Y1976033D02*
X1539110D01*
G01X1534976Y1975837D02*
X1533992D01*
G01X1542605Y1975620D02*
X1549937D01*
G01X1542457D02*
X1530449D01*
G01X1534976Y1975443D02*
X1533992D01*
G01X1534976Y1975246D02*
X1533992D01*
G01X1542457Y1974833D02*
X1530449D01*
G01X1549937D02*
X1542605D01*
G01X1534976Y1973396D02*
X1533992D01*
G01X1534976Y1973199D02*
X1533992D01*
G01X1534976Y1972805D02*
X1533992D01*
G01X1531945Y1972608D02*
X1539110D01*
G01X1542605Y1972470D02*
X1549937D01*
G01X1542457D02*
X1530449D01*
G01X1542457Y1971683D02*
X1530449D01*
G01X1549937D02*
X1542605D01*
G01X1531945Y1971033D02*
X1539110D01*
G01X1534976Y1970837D02*
X1533992D01*
G01X1534976Y1970443D02*
X1533992D01*
G01X1534976Y1970246D02*
X1533992D01*
G01X1542605Y1969321D02*
X1549937D01*
G01X1542457D02*
X1530449D01*
G01X1542457Y1968533D02*
X1530449D01*
G01X1549937D02*
X1542605D01*
G01X1534976Y1968396D02*
X1533992D01*
G01X1534976Y1968199D02*
X1533992D01*
G01X1534976Y1967805D02*
X1533992D01*
G01X1531945Y1967608D02*
X1539110D01*
G01X1542605Y1966171D02*
X1549937D01*
G01X1542457D02*
X1530449D01*
G01X1531945Y1966033D02*
X1539110D01*
G01X1534976Y1965837D02*
X1533992D01*
G01X1534976Y1965443D02*
X1533992D01*
G01X1542457Y1965384D02*
X1530449D01*
G01X1549937D02*
X1542605D01*
G01X1534976Y1965246D02*
X1533992D01*
G01X1534976Y1963396D02*
X1533992D01*
G01X1534976Y1963199D02*
X1533992D01*
G01X1542605Y1963022D02*
X1549937D01*
G01X1542457D02*
X1530449D01*
G01X1534976Y1962805D02*
X1533992D01*
G01X1531945Y1962608D02*
X1539110D01*
G01X1542457Y1962234D02*
X1530449D01*
G01X1549937D02*
X1542605D01*
G01X1531945Y1961033D02*
X1539110D01*
G01X1534976Y1960837D02*
X1533992D01*
G01X1534976Y1960443D02*
X1533992D01*
G01X1534976Y1960246D02*
X1533992D01*
G01X1542605Y1959872D02*
X1549937D01*
G01X1542457D02*
X1530449D01*
G01X1542457Y1959085D02*
X1530449D01*
G01X1549937D02*
X1542605D01*
G01X1534976Y1958396D02*
X1533992D01*
G01X1534976Y1958199D02*
X1533992D01*
G01X1534976Y1957805D02*
X1533992D01*
G01X1531945Y1957608D02*
X1539110D01*
G01X1542605Y1956722D02*
X1549937D01*
G01X1542457D02*
X1530449D01*
G01X1531945Y1956033D02*
X1539110D01*
G01X1542457Y1955935D02*
X1530449D01*
G01X1549937D02*
X1542605D01*
G01X1534976Y1955837D02*
X1533992D01*
G01X1534976Y1955443D02*
X1533992D01*
G01X1534976Y1955246D02*
X1533992D01*
G01X1530449Y1954025D02*
X1531551D01*
G01X1542605Y1953573D02*
X1549937D01*
G01X1542457D02*
X1530449D01*
G01X1533008Y1953396D02*
X1532024D01*
G01X1533008Y1953199D02*
X1532024D01*
G01X1533008Y1952805D02*
X1532024D01*
G01X1542457Y1952785D02*
X1530449D01*
G01X1549937D02*
X1542605D01*
G01X1531551Y1952608D02*
X1537142D01*
G01X1531551Y1951033D02*
X1537142D01*
G01X1533008Y1950837D02*
X1532024D01*
G01X1533008Y1950443D02*
X1532024D01*
G01X1542605Y1950423D02*
X1549937D01*
G01X1542457D02*
X1530449D01*
G01X1533008Y1950246D02*
X1532024D01*
G01X1542457Y1949636D02*
X1530449D01*
G01X1549937D02*
X1542605D01*
G01X1530449Y1949616D02*
X1531551D01*
G01X1534976Y1948396D02*
X1533992D01*
G01X1534976Y1948199D02*
X1533992D01*
G01X1534976Y1947805D02*
X1533992D01*
G01X1531945Y1947608D02*
X1539110D01*
G01X1542605Y1947274D02*
X1549937D01*
G01X1542457D02*
X1530449D01*
G01X1542457Y1946486D02*
X1530449D01*
G01X1549937D02*
X1542605D01*
G01X1531945Y1946033D02*
X1539110D01*
G01X1534976Y1945837D02*
X1533992D01*
G01X1534976Y1945443D02*
X1533992D01*
G01X1534976Y1945246D02*
X1533992D01*
G01X1542605Y1944124D02*
X1549937D01*
G01X1542457D02*
X1530449D01*
G01X1534976Y1943396D02*
X1533992D01*
G01X1542457Y1943337D02*
X1530449D01*
G01X1549937D02*
X1542605D01*
G01X1534976Y1943199D02*
X1533992D01*
G01X1549937Y1944124D02*
Y1943337D01*
G01Y1950423D02*
Y1949636D01*
G01Y1947274D02*
Y1946486D01*
G01Y1953573D02*
Y1952785D01*
G01Y1959872D02*
Y1959085D01*
G01Y1956722D02*
Y1955935D01*
G01Y1963022D02*
Y1962234D01*
G01Y1969321D02*
Y1968533D01*
G01Y1966171D02*
Y1965384D01*
G01Y1972470D02*
Y1971683D01*
G01Y1978770D02*
Y1977982D01*
G01Y1975620D02*
Y1974833D01*
G01Y1981919D02*
Y1981132D01*
G01Y1988218D02*
Y1987431D01*
G01Y1985069D02*
Y1984281D01*
G01Y1991368D02*
Y1990581D01*
G01Y1994518D02*
Y1993730D01*
G01Y2000817D02*
Y2000029D01*
G01Y1997667D02*
Y1996880D01*
G01Y2003966D02*
Y2003179D01*
G01Y2010266D02*
Y2009478D01*
G01Y2007116D02*
Y2006329D01*
G01X1548163Y1944124D02*
Y1943337D01*
G01Y1950423D02*
Y1949636D01*
G01Y1947274D02*
Y1946486D01*
G01Y1953573D02*
Y1952785D01*
G01Y1959872D02*
Y1959085D01*
G01Y1956722D02*
Y1955935D01*
G01Y1963022D02*
Y1962234D01*
G01Y1969321D02*
Y1968533D01*
G01Y1966171D02*
Y1965384D01*
G01Y1972470D02*
Y1971683D01*
G01Y1978770D02*
Y1977982D01*
G01Y1975620D02*
Y1974833D01*
G01Y1981919D02*
Y1981132D01*
G01Y1988218D02*
Y1987431D01*
G01Y1985069D02*
Y1984281D01*
G01Y1991368D02*
Y1990581D01*
G01Y1994518D02*
Y1993730D01*
G01Y2000817D02*
Y2000029D01*
G01Y1997667D02*
Y1996880D01*
G01Y2003966D02*
Y2003179D01*
G01Y2010266D02*
Y2009478D01*
G01Y2007116D02*
Y2006329D01*
G01X1547975Y2009478D02*
Y2010266D01*
G01Y2006329D02*
Y2007116D01*
G01Y2003179D02*
Y2003966D01*
G01Y2000029D02*
Y2000817D01*
G01Y1996880D02*
Y1997667D01*
G01Y1993730D02*
Y1994518D01*
G01Y1990581D02*
Y1991368D01*
G01Y1987431D02*
Y1988218D01*
G01Y1984281D02*
Y1985069D01*
G01Y1981132D02*
Y1981919D01*
G01Y1977982D02*
Y1978770D01*
G01Y1974833D02*
Y1975620D01*
G01Y1971683D02*
Y1972470D01*
G01Y1968533D02*
Y1969321D01*
G01Y1965384D02*
Y1966171D01*
G01Y1962234D02*
Y1963022D01*
G01Y1959085D02*
Y1959872D01*
G01Y1955935D02*
Y1956722D01*
G01Y1952785D02*
Y1953573D01*
G01Y1949636D02*
Y1950423D01*
G01Y1946486D02*
Y1947274D01*
G01Y1943337D02*
Y1944124D01*
G01X1545138Y2009478D02*
Y2010266D01*
G01Y2006329D02*
Y2007116D01*
G01Y2003179D02*
Y2003966D01*
G01Y2000029D02*
Y2000817D01*
G01Y1996880D02*
Y1997667D01*
G01Y1993730D02*
Y1994518D01*
G01Y1990581D02*
Y1991368D01*
G01Y1987431D02*
Y1988218D01*
G01Y1984281D02*
Y1985069D01*
G01Y1981132D02*
Y1981919D01*
G01Y1977982D02*
Y1978770D01*
G01Y1974833D02*
Y1975620D01*
G01Y1971683D02*
Y1972470D01*
G01Y1968533D02*
Y1969321D01*
G01Y1965384D02*
Y1966171D01*
G01Y1962234D02*
Y1963022D01*
G01Y1959085D02*
Y1959872D01*
G01Y1955935D02*
Y1956722D01*
G01Y1952785D02*
Y1953573D01*
G01Y1949636D02*
Y1950423D01*
G01Y1946486D02*
Y1947274D01*
G01Y1943337D02*
Y1944124D01*
G01X1544197D02*
Y1943337D01*
G01Y1950423D02*
Y1949636D01*
G01Y1947274D02*
Y1946486D01*
G01Y1953573D02*
Y1952785D01*
G01Y1959872D02*
Y1959085D01*
G01Y1956722D02*
Y1955935D01*
G01Y1963022D02*
Y1962234D01*
G01Y1969321D02*
Y1968533D01*
G01Y1966171D02*
Y1965384D01*
G01Y1972470D02*
Y1971683D01*
G01Y1978770D02*
Y1977982D01*
G01Y1975620D02*
Y1974833D01*
G01Y1981919D02*
Y1981132D01*
G01Y1988218D02*
Y1987431D01*
G01Y1985069D02*
Y1984281D01*
G01Y1991368D02*
Y1990581D01*
G01Y1994518D02*
Y1993730D01*
G01Y2000817D02*
Y2000029D01*
G01Y1997667D02*
Y1996880D01*
G01Y2003966D02*
Y2003179D01*
G01Y2010266D02*
Y2009478D01*
G01Y2007116D02*
Y2006329D01*
G01X1542605Y1944124D02*
Y1943337D01*
G01Y1950423D02*
Y1949636D01*
G01Y1947274D02*
Y1946486D01*
G01Y1953573D02*
Y1952785D01*
G01Y1959872D02*
Y1959085D01*
G01Y1956722D02*
Y1955935D01*
G01Y1963022D02*
Y1962234D01*
G01Y1969321D02*
Y1968533D01*
G01Y1966171D02*
Y1965384D01*
G01Y1972470D02*
Y1971683D01*
G01Y1978770D02*
Y1977982D01*
G01Y1975620D02*
Y1974833D01*
G01Y1981919D02*
Y1981132D01*
G01Y1988218D02*
Y1987431D01*
G01Y1985069D02*
Y1984281D01*
G01Y1991368D02*
Y1990581D01*
G01Y1994518D02*
Y1993730D01*
G01Y2000817D02*
Y2000029D01*
G01Y1997667D02*
Y1996880D01*
G01Y2003966D02*
Y2003179D01*
G01Y2010266D02*
Y2009478D01*
G01Y2007116D02*
Y2006329D01*
G01X1542457Y1944124D02*
Y1943337D01*
G01Y1950423D02*
Y1949636D01*
G01Y1947274D02*
Y1946486D01*
G01Y1953573D02*
Y1952785D01*
G01Y1959872D02*
Y1959085D01*
G01Y1956722D02*
Y1955935D01*
G01Y1963022D02*
Y1962234D01*
G01Y1969321D02*
Y1968533D01*
G01Y1966171D02*
Y1965384D01*
G01Y1972470D02*
Y1971683D01*
G01Y1978770D02*
Y1977982D01*
G01Y1975620D02*
Y1974833D01*
G01Y1981919D02*
Y1981132D01*
G01Y1988218D02*
Y1987431D01*
G01Y1985069D02*
Y1984281D01*
G01Y1991368D02*
Y1990581D01*
G01Y1994518D02*
Y1993730D01*
G01Y2000817D02*
Y2000029D01*
G01Y1997667D02*
Y1996880D01*
G01Y2003966D02*
Y2003179D01*
G01Y2010266D02*
Y2009478D01*
G01Y2007116D02*
Y2006329D01*
G01X1541519Y2010266D02*
Y2012628D01*
G01Y2007116D02*
Y2009478D01*
G01Y2003966D02*
Y2006329D01*
G01Y2000817D02*
Y2003179D01*
G01Y1997667D02*
Y2000029D01*
G01Y1994518D02*
Y1996880D01*
G01Y1991368D02*
Y1993730D01*
G01Y1988218D02*
Y1990581D01*
G01Y1985069D02*
Y1987431D01*
G01Y1981919D02*
Y1984281D01*
G01Y1978770D02*
Y1981132D01*
G01Y1975620D02*
Y1977982D01*
G01Y1972470D02*
Y1974833D01*
G01Y1969321D02*
Y1971683D01*
G01Y1966171D02*
Y1968533D01*
G01Y1963022D02*
Y1965384D01*
G01Y1959872D02*
Y1962234D01*
G01Y1956722D02*
Y1959085D01*
G01Y1953573D02*
Y1955935D01*
G01Y1950423D02*
Y1952785D01*
G01Y1947274D02*
Y1949636D01*
G01Y1944124D02*
Y1946486D01*
G01X1539791Y1944124D02*
Y1943337D01*
G01Y1950423D02*
Y1949636D01*
G01Y1947274D02*
Y1946486D01*
G01Y1953573D02*
Y1952785D01*
G01Y1959872D02*
Y1959085D01*
G01Y1956722D02*
Y1955935D01*
G01Y1963022D02*
Y1962234D01*
G01Y1969321D02*
Y1968533D01*
G01Y1966171D02*
Y1965384D01*
G01Y1972470D02*
Y1971683D01*
G01Y1978770D02*
Y1977982D01*
G01Y1975620D02*
Y1974833D01*
G01Y1981919D02*
Y1981132D01*
G01Y1988218D02*
Y1987431D01*
G01Y1985069D02*
Y1984281D01*
G01Y1991368D02*
Y1990581D01*
G01Y1994518D02*
Y1993730D01*
G01Y2000817D02*
Y2000029D01*
G01Y1997667D02*
Y1996880D01*
G01Y2003966D02*
Y2003179D01*
G01Y2010266D02*
Y2009478D01*
G01Y2007116D02*
Y2006329D01*
G01X1539110Y2006033D02*
Y2007608D01*
G01Y2001033D02*
Y2002608D01*
G01Y1996033D02*
Y1997608D01*
G01Y1986033D02*
Y1987608D01*
G01Y1981033D02*
Y1982608D01*
G01Y1976033D02*
Y1977608D01*
G01Y1971033D02*
Y1972608D01*
G01Y1966033D02*
Y1967608D01*
G01Y1961033D02*
Y1962608D01*
G01Y1956033D02*
Y1957608D01*
G01Y1946033D02*
Y1947608D01*
G01X1538139Y2009478D02*
Y2010266D01*
G01Y2006329D02*
Y2007116D01*
G01Y2003179D02*
Y2003966D01*
G01Y2000029D02*
Y2000817D01*
G01Y1996880D02*
Y1997667D01*
G01Y1993730D02*
Y1994518D01*
G01Y1990581D02*
Y1991368D01*
G01Y1987431D02*
Y1988218D01*
G01Y1984281D02*
Y1985069D01*
G01Y1981132D02*
Y1981919D01*
G01Y1977982D02*
Y1978770D01*
G01Y1974833D02*
Y1975620D01*
G01Y1971683D02*
Y1972470D01*
G01Y1968533D02*
Y1969321D01*
G01Y1965384D02*
Y1966171D01*
G01Y1962234D02*
Y1963022D01*
G01Y1959085D02*
Y1959872D01*
G01Y1955935D02*
Y1956722D01*
G01Y1952785D02*
Y1953573D01*
G01Y1949636D02*
Y1950423D01*
G01Y1946486D02*
Y1947274D01*
G01Y1943337D02*
Y1944124D01*
G01X1537984Y2013494D02*
Y2009675D01*
G01X1537576Y2010856D02*
Y2012037D01*
G01X1537506Y2028966D02*
Y2009675D01*
G01X1537142Y1991033D02*
Y1992608D01*
G01Y1951033D02*
Y1952608D01*
G01X1536156Y2009478D02*
Y2010266D01*
G01Y2006329D02*
Y2007116D01*
G01Y2003179D02*
Y2003966D01*
G01Y2000029D02*
Y2000817D01*
G01Y1996880D02*
Y1997667D01*
G01Y1993730D02*
Y1994518D01*
G01Y1990581D02*
Y1991368D01*
G01Y1987431D02*
Y1988218D01*
G01Y1984281D02*
Y1985069D01*
G01Y1981132D02*
Y1981919D01*
G01Y1977982D02*
Y1978770D01*
G01Y1974833D02*
Y1975620D01*
G01Y1971683D02*
Y1972470D01*
G01Y1968533D02*
Y1969321D01*
G01Y1965384D02*
Y1966171D01*
G01Y1962234D02*
Y1963022D01*
G01Y1959085D02*
Y1959872D01*
G01Y1955935D02*
Y1956722D01*
G01Y1952785D02*
Y1953573D01*
G01Y1949636D02*
Y1950423D01*
G01Y1946486D02*
Y1947274D01*
G01Y1943337D02*
Y1944124D01*
G01X1535961Y1947608D02*
Y1946033D01*
G01Y1957608D02*
Y1956033D01*
G01Y1962608D02*
Y1961033D01*
G01Y1967608D02*
Y1966033D01*
G01Y1972608D02*
Y1971033D01*
G01Y1977608D02*
Y1976033D01*
G01Y1982608D02*
Y1981033D01*
G01Y1987608D02*
Y1986033D01*
G01Y1997608D02*
Y1996033D01*
G01Y2002608D02*
Y2001033D01*
G01Y2007608D02*
Y2006033D01*
G01X1534976Y1948396D02*
Y1945246D01*
G01Y1958396D02*
Y1955246D01*
G01Y1963396D02*
Y1960246D01*
G01Y1968396D02*
Y1965246D01*
G01Y1973396D02*
Y1970246D01*
G01Y1978396D02*
Y1975246D01*
G01Y1983396D02*
Y1980246D01*
G01Y1988396D02*
Y1985246D01*
G01Y1998396D02*
Y1995246D01*
G01Y2003396D02*
Y2000246D01*
G01Y2008396D02*
Y2005246D01*
G01X1534427Y2012037D02*
Y2010856D01*
G01X1534149Y2028966D02*
Y2009675D01*
G01X1533992Y1948396D02*
Y1945246D01*
G01Y1952608D02*
Y1951033D01*
G01Y1958396D02*
Y1955246D01*
G01Y1963396D02*
Y1960246D01*
G01Y1968396D02*
Y1965246D01*
G01Y1973396D02*
Y1970246D01*
G01Y1978396D02*
Y1975246D01*
G01Y1983396D02*
Y1980246D01*
G01Y1992608D02*
Y1991033D01*
G01Y1988396D02*
Y1985246D01*
G01Y1998396D02*
Y1995246D01*
G01Y2003396D02*
Y2000246D01*
G01Y2008396D02*
Y2005246D01*
G01X1533442Y2028474D02*
Y2010167D01*
G01X1533232Y2009675D02*
Y2028966D01*
G01X1533008Y1947608D02*
Y1946033D01*
G01Y1953396D02*
Y1950246D01*
G01Y1957608D02*
Y1956033D01*
G01Y1962608D02*
Y1961033D01*
G01Y1967608D02*
Y1966033D01*
G01Y1972608D02*
Y1971033D01*
G01Y1977608D02*
Y1976033D01*
G01Y1982608D02*
Y1981033D01*
G01Y1987608D02*
Y1986033D01*
G01Y1993396D02*
Y1990246D01*
G01Y1997608D02*
Y1996033D01*
G01Y2002608D02*
Y2001033D01*
G01Y2007608D02*
Y2006033D01*
G01X1532793Y1944124D02*
Y1943337D01*
G01Y1950423D02*
Y1949636D01*
G01Y1947274D02*
Y1946486D01*
G01Y1953573D02*
Y1952785D01*
G01Y1959872D02*
Y1959085D01*
G01Y1956722D02*
Y1955935D01*
G01Y1963022D02*
Y1962234D01*
G01Y1969321D02*
Y1968533D01*
G01Y1966171D02*
Y1965384D01*
G01Y1972470D02*
Y1971683D01*
G01Y1978770D02*
Y1977982D01*
G01Y1975620D02*
Y1974833D01*
G01Y1981919D02*
Y1981132D01*
G01Y1988218D02*
Y1987431D01*
G01Y1985069D02*
Y1984281D01*
G01Y1991368D02*
Y1990581D01*
G01Y1994518D02*
Y1993730D01*
G01Y2000817D02*
Y2000029D01*
G01Y1997667D02*
Y1996880D01*
G01Y2003966D02*
Y2003179D01*
G01Y2010266D02*
Y2009478D01*
G01Y2007116D02*
Y2006329D01*
G01X1532732Y2028966D02*
Y2009675D01*
G01X1532458Y2012628D02*
Y2010266D01*
G01X1532417Y1944124D02*
Y1943337D01*
G01Y1950423D02*
Y1949636D01*
G01Y1947274D02*
Y1946486D01*
G01Y1953573D02*
Y1952785D01*
G01Y1959872D02*
Y1959085D01*
G01Y1956722D02*
Y1955935D01*
G01Y1963022D02*
Y1962234D01*
G01Y1969321D02*
Y1968533D01*
G01Y1966171D02*
Y1965384D01*
G01Y1972470D02*
Y1971683D01*
G01Y1978770D02*
Y1977982D01*
G01Y1975620D02*
Y1974833D01*
G01Y1981919D02*
Y1981132D01*
G01Y1988218D02*
Y1987431D01*
G01Y1985069D02*
Y1984281D01*
G01Y1991368D02*
Y1990581D01*
G01Y1994518D02*
Y1993730D01*
G01Y2000817D02*
Y2000029D01*
G01Y1997667D02*
Y1996880D01*
G01Y2003966D02*
Y2003179D01*
G01Y2010266D02*
Y2009478D01*
G01Y2007116D02*
Y2006329D01*
G01X1532391Y1944124D02*
Y1943337D01*
G01Y1950423D02*
Y1949636D01*
G01Y1947274D02*
Y1946486D01*
G01Y1953573D02*
Y1952785D01*
G01Y1959872D02*
Y1959085D01*
G01Y1956722D02*
Y1955935D01*
G01Y1963022D02*
Y1962234D01*
G01Y1969321D02*
Y1968533D01*
G01Y1966171D02*
Y1965384D01*
G01Y1972470D02*
Y1971683D01*
G01Y1978770D02*
Y1977982D01*
G01Y1975620D02*
Y1974833D01*
G01Y1981919D02*
Y1981132D01*
G01Y1988218D02*
Y1987431D01*
G01Y1985069D02*
Y1984281D01*
G01Y1991368D02*
Y1990581D01*
G01Y1994518D02*
Y1993730D01*
G01Y2000817D02*
Y2000029D01*
G01Y1997667D02*
Y1996880D01*
G01Y2003966D02*
Y2003179D01*
G01Y2010266D02*
Y2009478D01*
G01Y2007116D02*
Y2006329D01*
G01X1532024Y1953396D02*
Y1950246D01*
G01Y1993396D02*
Y1990246D01*
G01X1531945Y2028966D02*
Y2009675D01*
G01X1531630D02*
Y2028966D01*
G01X1526433Y2009577D02*
Y2029065D01*
G01Y1969616D02*
Y1953081D01*
G01Y1988514D02*
Y1971978D01*
G01Y2007214D02*
Y1990876D01*
G01X1509023Y2012628D02*
X1509050Y2012632D01*
X1509075Y2012643D01*
X1509099Y2012661D01*
X1509121Y2012686D01*
X1509138Y2012715D01*
X1509150Y2012749D01*
X1509158Y2012786D01*
X1509161Y2012825D01*
G01X1503964Y2015283D02*
X1503838Y2015256D01*
X1503748Y2015183D01*
X1503717Y2015086D01*
G01X1503974Y2013415D02*
X1503846Y2013388D01*
X1503758Y2013315D01*
X1503727Y2013218D01*
G01X1509772Y2015283D02*
X1503964D01*
G01X1510035Y2015086D02*
X1503717D01*
G01Y2014102D02*
X1510035D01*
G01X1509772Y2013905D02*
X1503964D01*
G01X1503974Y2013415D02*
X1510058D01*
G01X1503727Y2013218D02*
X1510338D01*
G01Y2012825D02*
X1503727D01*
G01X1503974Y2012628D02*
X1510058D01*
G01X1509772Y2012134D02*
X1503964D01*
G01X1508945Y2015283D02*
X1508974Y2015279D01*
X1509001Y2015268D01*
X1509027Y2015250D01*
X1509049Y2015226D01*
X1509068Y2015196D01*
X1509081Y2015162D01*
X1509090Y2015125D01*
X1509093Y2015086D01*
G01X1507908Y2015283D02*
X1507914Y2015279D01*
X1507920Y2015268D01*
X1507926Y2015250D01*
X1507931Y2015226D01*
X1507935Y2015196D01*
X1507938Y2015162D01*
X1507940Y2015125D01*
X1507941Y2015086D01*
G01X1508572Y2013415D02*
X1508610Y2013389D01*
X1508638Y2013317D01*
X1508648Y2013218D01*
G01X1503727Y2012825D02*
X1503758Y2012728D01*
X1503847Y2012656D01*
X1503974Y2012628D01*
G01X1503717Y2014102D02*
X1503750Y2014003D01*
X1503838Y2013932D01*
X1503964Y2013905D01*
G01X1509161Y2013218D02*
X1509158Y2013257D01*
X1509151Y2013293D01*
X1509138Y2013327D01*
X1509121Y2013358D01*
X1509100Y2013382D01*
X1509076Y2013400D01*
X1509050Y2013411D01*
X1509023Y2013415D01*
G01X1509093Y2014102D02*
X1509090Y2014064D01*
X1509081Y2014027D01*
X1509068Y2013993D01*
X1509049Y2013963D01*
X1509027Y2013939D01*
X1509002Y2013920D01*
X1508974Y2013909D01*
X1508945Y2013905D01*
G01X1507941Y2014102D02*
X1507940Y2014064D01*
X1507938Y2014027D01*
X1507935Y2013993D01*
X1507931Y2013963D01*
X1507926Y2013939D01*
X1507921Y2013920D01*
X1507915Y2013909D01*
X1507908Y2013905D01*
G01X1510338Y2012825D02*
Y2013218D01*
G01X1510035Y2015086D02*
Y2014102D01*
G01X1509161Y2012825D02*
Y2013218D01*
G01X1509093Y2015086D02*
Y2014102D01*
G01X1508648Y2013218D02*
Y2012825D01*
G01X1507941Y2015086D02*
Y2014102D01*
G01X1503727Y2013218D02*
Y2012825D01*
G01X1503717Y2014102D02*
Y2015086D01*
G01X1508648Y2012825D02*
X1508638Y2012726D01*
X1508610Y2012654D01*
X1508572Y2012628D01*
G01X1503974Y2060659D02*
X1503846Y2060632D01*
X1503758Y2060559D01*
X1503727Y2060463D01*
G01X1503974Y2057510D02*
X1503846Y2057482D01*
X1503758Y2057409D01*
X1503727Y2057313D01*
G01X1503974Y2054360D02*
X1503846Y2054332D01*
X1503758Y2054260D01*
X1503727Y2054163D01*
G01X1503974Y2051211D02*
X1503846Y2051183D01*
X1503758Y2051110D01*
X1503727Y2051014D01*
G01X1503974Y2048061D02*
X1503846Y2048033D01*
X1503758Y2047960D01*
X1503727Y2047864D01*
G01X1503974Y2044911D02*
X1503846Y2044884D01*
X1503758Y2044811D01*
X1503727Y2044714D01*
G01X1503974Y2041762D02*
X1503846Y2041734D01*
X1503758Y2041661D01*
X1503727Y2041565D01*
G01X1497772Y2078907D02*
X1551709D01*
G01X1524149Y2077726D02*
X1497772D01*
G01X1501709Y2070561D02*
X1551709D01*
G01X1499740D02*
X1496457D01*
G01X1530449Y2066033D02*
X1499740D01*
G01X1520212Y2065640D02*
X1501709D01*
G01X1509749Y2062608D02*
X1504004D01*
G01X1510176Y2062018D02*
X1503590D01*
G01Y2061624D02*
X1510176D01*
G01X1504004Y2061033D02*
X1509749D01*
G01X1503974Y2060659D02*
X1510058D01*
G01X1503727Y2060463D02*
X1510338D01*
G01Y2060069D02*
X1503727D01*
G01X1503974Y2059872D02*
X1510058D01*
G01X1509749Y2057608D02*
X1504004D01*
G01X1503974Y2057510D02*
X1510058D01*
G01X1503727Y2057313D02*
X1510338D01*
G01X1510176Y2057018D02*
X1503590D01*
G01X1510338Y2056919D02*
X1503727D01*
G01X1503974Y2056722D02*
X1510058D01*
G01X1503590Y2056624D02*
X1510176D01*
G01X1504004Y2056033D02*
X1509749D01*
G01X1503974Y2054360D02*
X1510058D01*
G01X1503727Y2054163D02*
X1510338D01*
G01Y2053770D02*
X1503727D01*
G01X1503974Y2053573D02*
X1510058D01*
G01X1509749Y2052608D02*
X1504004D01*
G01X1510176Y2052018D02*
X1503590D01*
G01Y2051624D02*
X1510176D01*
G01X1503974Y2051211D02*
X1510058D01*
G01X1504004Y2051033D02*
X1509749D01*
G01X1503727Y2051014D02*
X1510338D01*
G01Y2050620D02*
X1503727D01*
G01X1503974Y2050423D02*
X1510058D01*
G01X1501709Y2049025D02*
X1528401D01*
G01X1503974Y2048061D02*
X1510058D01*
G01X1503727Y2047864D02*
X1510338D01*
G01X1509749Y2047608D02*
X1504004D01*
G01X1510338Y2047470D02*
X1503727D01*
G01X1503974Y2047274D02*
X1510058D01*
G01X1510176Y2047018D02*
X1503590D01*
G01X1528401Y2046663D02*
X1501709D01*
G01X1503590Y2046624D02*
X1510176D01*
G01X1504004Y2046033D02*
X1509749D01*
G01X1503974Y2044911D02*
X1510058D01*
G01X1503727Y2044714D02*
X1510338D01*
G01Y2044321D02*
X1503727D01*
G01X1503974Y2044124D02*
X1510058D01*
G01X1509023Y2059872D02*
X1509050Y2059876D01*
X1509075Y2059887D01*
X1509099Y2059905D01*
X1509121Y2059930D01*
X1509138Y2059959D01*
X1509150Y2059993D01*
X1509158Y2060030D01*
X1509161Y2060069D01*
G01X1509023Y2056722D02*
X1509050Y2056726D01*
X1509075Y2056737D01*
X1509099Y2056755D01*
X1509121Y2056780D01*
X1509138Y2056810D01*
X1509150Y2056844D01*
X1509158Y2056880D01*
X1509161Y2056919D01*
G01X1509023Y2053573D02*
X1509050Y2053576D01*
X1509075Y2053588D01*
X1509099Y2053606D01*
X1509121Y2053630D01*
X1509138Y2053660D01*
X1509150Y2053694D01*
X1509158Y2053731D01*
X1509161Y2053770D01*
G01X1509023Y2050423D02*
X1509050Y2050427D01*
X1509075Y2050438D01*
X1509099Y2050456D01*
X1509121Y2050481D01*
X1509138Y2050510D01*
X1509150Y2050544D01*
X1509158Y2050581D01*
X1509161Y2050620D01*
G01X1509023Y2047274D02*
X1509050Y2047277D01*
X1509075Y2047288D01*
X1509099Y2047306D01*
X1509121Y2047331D01*
X1509138Y2047361D01*
X1509150Y2047395D01*
X1509158Y2047431D01*
X1509161Y2047470D01*
G01X1509023Y2044124D02*
X1509050Y2044128D01*
X1509075Y2044139D01*
X1509099Y2044157D01*
X1509121Y2044182D01*
X1509138Y2044211D01*
X1509150Y2044245D01*
X1509158Y2044282D01*
X1509161Y2044321D01*
G01X1509023Y2040974D02*
X1509050Y2040978D01*
X1509075Y2040989D01*
X1509099Y2041007D01*
X1509121Y2041032D01*
X1509138Y2041062D01*
X1509150Y2041096D01*
X1509158Y2041132D01*
X1509161Y2041171D01*
G01X1509023Y2037825D02*
X1509050Y2037828D01*
X1509075Y2037840D01*
X1509099Y2037858D01*
X1509121Y2037882D01*
X1509138Y2037912D01*
X1509150Y2037946D01*
X1509158Y2037983D01*
X1509161Y2038022D01*
G01X1509023Y2034675D02*
X1509050Y2034679D01*
X1509075Y2034690D01*
X1509099Y2034708D01*
X1509121Y2034733D01*
X1509138Y2034762D01*
X1509150Y2034796D01*
X1509158Y2034833D01*
X1509161Y2034872D01*
G01X1509023Y2031525D02*
X1509050Y2031529D01*
X1509075Y2031540D01*
X1509099Y2031558D01*
X1509121Y2031583D01*
X1509138Y2031613D01*
X1509150Y2031647D01*
X1509158Y2031683D01*
X1509161Y2031722D01*
G01X1509023Y2028376D02*
X1509050Y2028380D01*
X1509075Y2028391D01*
X1509099Y2028409D01*
X1509121Y2028434D01*
X1509138Y2028463D01*
X1509150Y2028497D01*
X1509158Y2028534D01*
X1509161Y2028573D01*
G01X1509023Y2025226D02*
X1509050Y2025230D01*
X1509075Y2025241D01*
X1509099Y2025259D01*
X1509121Y2025284D01*
X1509138Y2025314D01*
X1509150Y2025347D01*
X1509158Y2025384D01*
X1509161Y2025423D01*
G01X1509023Y2022077D02*
X1509050Y2022080D01*
X1509075Y2022092D01*
X1509099Y2022110D01*
X1509121Y2022134D01*
X1509138Y2022164D01*
X1509150Y2022198D01*
X1509158Y2022235D01*
X1509161Y2022274D01*
G01X1509023Y2018927D02*
X1509050Y2018931D01*
X1509075Y2018942D01*
X1509099Y2018960D01*
X1509121Y2018985D01*
X1509138Y2019014D01*
X1509150Y2019048D01*
X1509158Y2019085D01*
X1509161Y2019124D01*
G01X1509023Y2015777D02*
X1509050Y2015781D01*
X1509075Y2015792D01*
X1509099Y2015810D01*
X1509121Y2015835D01*
X1509138Y2015865D01*
X1509150Y2015899D01*
X1509158Y2015935D01*
X1509161Y2015974D01*
G01X1503964Y2027882D02*
X1503838Y2027854D01*
X1503748Y2027782D01*
X1503717Y2027685D01*
G01X1503964Y2024732D02*
X1503838Y2024705D01*
X1503748Y2024632D01*
X1503717Y2024535D01*
G01X1503964Y2021582D02*
X1503838Y2021555D01*
X1503748Y2021482D01*
X1503717Y2021386D01*
G01X1503964Y2018433D02*
X1503838Y2018405D01*
X1503748Y2018333D01*
X1503717Y2018236D01*
G01X1503974Y2038612D02*
X1503846Y2038584D01*
X1503758Y2038511D01*
X1503727Y2038415D01*
G01X1503974Y2035463D02*
X1503846Y2035435D01*
X1503758Y2035362D01*
X1503727Y2035266D01*
G01X1503974Y2032313D02*
X1503846Y2032285D01*
X1503758Y2032212D01*
X1503727Y2032116D01*
G01X1503974Y2029163D02*
X1503846Y2029136D01*
X1503758Y2029063D01*
X1503727Y2028966D01*
G01X1503974Y2026014D02*
X1503846Y2025986D01*
X1503758Y2025913D01*
X1503727Y2025817D01*
G01X1503974Y2022864D02*
X1503846Y2022836D01*
X1503758Y2022763D01*
X1503727Y2022667D01*
G01X1503974Y2019714D02*
X1503846Y2019687D01*
X1503758Y2019614D01*
X1503727Y2019518D01*
G01X1503974Y2016565D02*
X1503846Y2016537D01*
X1503758Y2016464D01*
X1503727Y2016368D01*
G01X1509749Y2042608D02*
X1504004D01*
G01X1510176Y2042018D02*
X1503590D01*
G01X1503974Y2041762D02*
X1510058D01*
G01X1503590Y2041624D02*
X1510176D01*
G01X1503727Y2041565D02*
X1510338D01*
G01Y2041171D02*
X1503727D01*
G01X1504004Y2041033D02*
X1509749D01*
G01X1503974Y2040974D02*
X1510058D01*
G01X1503974Y2038612D02*
X1510058D01*
G01X1503727Y2038415D02*
X1510338D01*
G01Y2038022D02*
X1503727D01*
G01X1503974Y2037825D02*
X1510058D01*
G01X1509749Y2037608D02*
X1504004D01*
G01X1510176Y2037018D02*
X1503590D01*
G01Y2036624D02*
X1510176D01*
G01X1504004Y2036033D02*
X1509749D01*
G01X1503974Y2035463D02*
X1510058D01*
G01X1520212Y2035423D02*
X1500751D01*
G01X1503727Y2035266D02*
X1510338D01*
G01Y2034872D02*
X1503727D01*
G01X1503974Y2034675D02*
X1510058D01*
G01X1509817Y2032608D02*
X1503904D01*
G01X1503974Y2032313D02*
X1510058D01*
G01X1503727Y2032116D02*
X1510338D01*
G01X1510241Y2032018D02*
X1503499D01*
G01X1510338Y2031722D02*
X1503727D01*
G01X1503499Y2031624D02*
X1510241D01*
G01X1503974Y2031525D02*
X1510058D01*
G01X1501709Y2031427D02*
X1528401D01*
G01X1509817Y2031033D02*
X1503904D01*
G01X1499740Y2030246D02*
X1506209D01*
G01X1503974Y2029163D02*
X1510058D01*
G01X1520212Y2029085D02*
X1501709D01*
G01X1528401Y2029065D02*
X1506209D01*
G01X1503727Y2028966D02*
X1510338D01*
G01Y2028573D02*
X1503727D01*
G01X1503974Y2028376D02*
X1510058D01*
G01X1509772Y2027882D02*
X1503964D01*
G01X1510035Y2027685D02*
X1503717D01*
G01Y2026701D02*
X1510035D01*
G01X1509772Y2026504D02*
X1503964D01*
G01X1503974Y2026014D02*
X1510058D01*
G01X1503727Y2025817D02*
X1510338D01*
G01Y2025423D02*
X1503727D01*
G01X1503974Y2025226D02*
X1510058D01*
G01X1509772Y2024732D02*
X1503964D01*
G01X1510035Y2024535D02*
X1503717D01*
G01Y2023551D02*
X1510035D01*
G01X1509772Y2023354D02*
X1503964D01*
G01X1503974Y2022864D02*
X1510058D01*
G01X1503727Y2022667D02*
X1510338D01*
G01Y2022274D02*
X1503727D01*
G01X1503974Y2022077D02*
X1510058D01*
G01X1509772Y2021582D02*
X1503964D01*
G01X1510035Y2021386D02*
X1503717D01*
G01Y2020401D02*
X1510035D01*
G01X1509772Y2020204D02*
X1503964D01*
G01X1503974Y2019714D02*
X1510058D01*
G01X1503727Y2019518D02*
X1510338D01*
G01Y2019124D02*
X1503727D01*
G01X1503974Y2018927D02*
X1510058D01*
G01X1509772Y2018433D02*
X1503964D01*
G01X1510035Y2018236D02*
X1503717D01*
G01Y2017252D02*
X1510035D01*
G01X1509772Y2017055D02*
X1503964D01*
G01X1503974Y2016565D02*
X1510058D01*
G01X1503727Y2016368D02*
X1510338D01*
G01Y2015974D02*
X1503727D01*
G01X1503974Y2015777D02*
X1510058D01*
G01X1508945Y2027882D02*
X1508974Y2027878D01*
X1509001Y2027867D01*
X1509027Y2027849D01*
X1509049Y2027824D01*
X1509068Y2027794D01*
X1509081Y2027760D01*
X1509090Y2027724D01*
X1509093Y2027685D01*
G01X1508945Y2024732D02*
X1508974Y2024728D01*
X1509001Y2024717D01*
X1509027Y2024699D01*
X1509049Y2024674D01*
X1509068Y2024645D01*
X1509081Y2024611D01*
X1509090Y2024574D01*
X1509093Y2024535D01*
G01X1508945Y2021582D02*
X1508974Y2021579D01*
X1509001Y2021568D01*
X1509027Y2021549D01*
X1509049Y2021525D01*
X1509068Y2021495D01*
X1509081Y2021461D01*
X1509090Y2021424D01*
X1509093Y2021386D01*
G01X1508945Y2018433D02*
X1508974Y2018429D01*
X1509001Y2018418D01*
X1509027Y2018400D01*
X1509049Y2018375D01*
X1509068Y2018345D01*
X1509081Y2018312D01*
X1509090Y2018275D01*
X1509093Y2018236D01*
G01X1508572Y2060659D02*
X1508610Y2060633D01*
X1508638Y2060561D01*
X1508648Y2060463D01*
G01X1507908Y2027882D02*
X1507914Y2027878D01*
X1507920Y2027867D01*
X1507926Y2027849D01*
X1507931Y2027824D01*
X1507935Y2027794D01*
X1507938Y2027760D01*
X1507940Y2027724D01*
X1507941Y2027685D01*
G01X1507908Y2024732D02*
X1507914Y2024728D01*
X1507920Y2024717D01*
X1507926Y2024699D01*
X1507931Y2024674D01*
X1507935Y2024645D01*
X1507938Y2024611D01*
X1507940Y2024574D01*
X1507941Y2024535D01*
G01X1507908Y2021582D02*
X1507914Y2021579D01*
X1507920Y2021568D01*
X1507926Y2021549D01*
X1507931Y2021525D01*
X1507935Y2021495D01*
X1507938Y2021461D01*
X1507940Y2021424D01*
X1507941Y2021386D01*
G01X1507908Y2018433D02*
X1507914Y2018429D01*
X1507920Y2018418D01*
X1507926Y2018400D01*
X1507931Y2018375D01*
X1507935Y2018345D01*
X1507938Y2018312D01*
X1507940Y2018275D01*
X1507941Y2018236D01*
G01X1508572Y2057510D02*
X1508610Y2057483D01*
X1508638Y2057411D01*
X1508648Y2057313D01*
G01X1508572Y2054360D02*
X1508610Y2054334D01*
X1508638Y2054262D01*
X1508648Y2054163D01*
G01X1508572Y2051211D02*
X1508610Y2051184D01*
X1508638Y2051112D01*
X1508648Y2051014D01*
G01X1508572Y2048061D02*
X1508610Y2048035D01*
X1508638Y2047962D01*
X1508648Y2047864D01*
G01X1508572Y2044911D02*
X1508610Y2044885D01*
X1508638Y2044813D01*
X1508648Y2044714D01*
G01X1508572Y2041762D02*
X1508610Y2041735D01*
X1508638Y2041663D01*
X1508648Y2041565D01*
G01X1508572Y2038612D02*
X1508610Y2038586D01*
X1508638Y2038514D01*
X1508648Y2038415D01*
G01X1508572Y2035463D02*
X1508610Y2035436D01*
X1508638Y2035364D01*
X1508648Y2035266D01*
G01X1508572Y2032313D02*
X1508610Y2032286D01*
X1508638Y2032214D01*
X1508648Y2032116D01*
G01X1508572Y2029163D02*
X1508610Y2029137D01*
X1508638Y2029065D01*
X1508648Y2028966D01*
G01X1508572Y2026014D02*
X1508610Y2025987D01*
X1508638Y2025915D01*
X1508648Y2025817D01*
G01X1508572Y2022864D02*
X1508610Y2022838D01*
X1508638Y2022766D01*
X1508648Y2022667D01*
G01X1508572Y2019714D02*
X1508610Y2019688D01*
X1508638Y2019616D01*
X1508648Y2019518D01*
G01X1508572Y2016565D02*
X1508610Y2016538D01*
X1508638Y2016466D01*
X1508648Y2016368D01*
G01X1499740Y2067608D02*
X1501709Y2065640D01*
G01Y2029085D02*
X1499740Y2031053D01*
G01X1509749Y2062608D02*
X1510176Y2062018D01*
G01X1509749Y2057608D02*
X1510176Y2057018D01*
G01X1509749Y2052608D02*
X1510176Y2052018D01*
G01X1509749Y2047608D02*
X1510176Y2047018D01*
G01X1503499Y2031624D02*
X1503633Y2031426D01*
X1503768Y2031230D01*
X1503904Y2031033D01*
G01X1503590Y2061624D02*
X1503727Y2061426D01*
X1503865Y2061229D01*
X1504004Y2061033D01*
G01X1503590Y2056624D02*
X1503727Y2056426D01*
X1503865Y2056229D01*
X1504004Y2056033D01*
G01X1503590Y2051624D02*
X1503727Y2051426D01*
X1503865Y2051229D01*
X1504004Y2051033D01*
G01X1503590Y2046624D02*
X1503727Y2046426D01*
X1503865Y2046229D01*
X1504004Y2046033D01*
G01X1503590Y2041624D02*
X1503727Y2041426D01*
X1503865Y2041229D01*
X1504004Y2041033D01*
G01X1503590Y2036624D02*
X1503727Y2036426D01*
X1503865Y2036229D01*
X1504004Y2036033D01*
G01X1509817Y2032608D02*
X1510241Y2032018D01*
G01X1509749Y2042608D02*
X1510176Y2042018D01*
G01X1509749Y2037608D02*
X1510176Y2037018D01*
G01X1509060Y2062608D02*
X1509332Y2062018D01*
G01X1509060Y2057608D02*
X1509332Y2057018D01*
G01X1509060Y2052608D02*
X1509332Y2052018D01*
G01X1509060Y2047608D02*
X1509332Y2047018D01*
G01X1509060Y2042608D02*
X1509332Y2042018D01*
G01X1509060Y2037608D02*
X1509332Y2037018D01*
G01X1509060Y2032608D02*
X1509332Y2032018D01*
G01X1503727Y2060069D02*
X1503758Y2059972D01*
X1503847Y2059900D01*
X1503974Y2059872D01*
G01X1503727Y2056919D02*
X1503758Y2056822D01*
X1503847Y2056750D01*
X1503974Y2056722D01*
G01X1503727Y2053770D02*
X1503758Y2053673D01*
X1503847Y2053600D01*
X1503974Y2053573D01*
G01X1503727Y2050620D02*
X1503758Y2050523D01*
X1503847Y2050451D01*
X1503974Y2050423D01*
G01X1503727Y2047470D02*
X1503758Y2047373D01*
X1503847Y2047301D01*
X1503974Y2047274D01*
G01X1503727Y2044321D02*
X1503758Y2044224D01*
X1503847Y2044152D01*
X1503974Y2044124D01*
G01X1503727Y2041171D02*
X1503758Y2041074D01*
X1503847Y2041002D01*
X1503974Y2040974D01*
G01X1503727Y2038022D02*
X1503758Y2037925D01*
X1503847Y2037852D01*
X1503974Y2037825D01*
G01X1503727Y2034872D02*
X1503758Y2034775D01*
X1503847Y2034703D01*
X1503974Y2034675D01*
G01X1503727Y2031722D02*
X1503758Y2031625D01*
X1503847Y2031553D01*
X1503974Y2031525D01*
G01X1503727Y2028573D02*
X1503758Y2028476D01*
X1503847Y2028404D01*
X1503974Y2028376D01*
G01X1503727Y2025423D02*
X1503758Y2025326D01*
X1503847Y2025254D01*
X1503974Y2025226D01*
G01X1503727Y2022274D02*
X1503758Y2022177D01*
X1503847Y2022104D01*
X1503974Y2022077D01*
G01X1503727Y2019124D02*
X1503758Y2019027D01*
X1503847Y2018955D01*
X1503974Y2018927D01*
G01X1503727Y2015974D02*
X1503758Y2015877D01*
X1503847Y2015805D01*
X1503974Y2015777D01*
G01X1503717Y2026701D02*
X1503750Y2026601D01*
X1503838Y2026531D01*
X1503964Y2026504D01*
G01X1503717Y2023551D02*
X1503750Y2023452D01*
X1503838Y2023381D01*
X1503964Y2023354D01*
G01X1503717Y2020401D02*
X1503750Y2020302D01*
X1503838Y2020231D01*
X1503964Y2020204D01*
G01X1503717Y2017252D02*
X1503750Y2017153D01*
X1503838Y2017082D01*
X1503964Y2017055D01*
G01X1508208Y2062018D02*
X1508130Y2062608D01*
G01X1508208Y2057018D02*
X1508130Y2057608D01*
G01X1508208Y2052018D02*
X1508130Y2052608D01*
G01X1508208Y2047018D02*
X1508130Y2047608D01*
G01X1508208Y2042018D02*
X1508130Y2042608D01*
G01X1508208Y2037018D02*
X1508130Y2037608D01*
G01X1508208Y2032018D02*
X1508130Y2032608D01*
G01X1497712Y2078185D02*
X1497767Y2077800D01*
G01X1509161Y2060463D02*
X1509158Y2060501D01*
X1509151Y2060538D01*
X1509138Y2060571D01*
X1509121Y2060602D01*
X1509100Y2060626D01*
X1509076Y2060644D01*
X1509050Y2060655D01*
X1509023Y2060659D01*
G01X1509161Y2057313D02*
X1509158Y2057351D01*
X1509151Y2057388D01*
X1509138Y2057422D01*
X1509121Y2057452D01*
X1509100Y2057476D01*
X1509076Y2057495D01*
X1509050Y2057506D01*
X1509023Y2057510D01*
G01X1509161Y2054163D02*
X1509158Y2054202D01*
X1509151Y2054238D01*
X1509138Y2054272D01*
X1509121Y2054302D01*
X1509100Y2054327D01*
X1509076Y2054345D01*
X1509050Y2054356D01*
X1509023Y2054360D01*
G01X1509161Y2051014D02*
X1509158Y2051052D01*
X1509151Y2051089D01*
X1509138Y2051123D01*
X1509121Y2051153D01*
X1509100Y2051177D01*
X1509076Y2051195D01*
X1509050Y2051207D01*
X1509023Y2051211D01*
G01X1509161Y2047864D02*
X1509158Y2047902D01*
X1509151Y2047939D01*
X1509138Y2047973D01*
X1509121Y2048003D01*
X1509100Y2048028D01*
X1509076Y2048046D01*
X1509050Y2048057D01*
X1509023Y2048061D01*
G01X1509161Y2044714D02*
X1509158Y2044753D01*
X1509151Y2044789D01*
X1509138Y2044823D01*
X1509121Y2044854D01*
X1509100Y2044878D01*
X1509076Y2044896D01*
X1509050Y2044907D01*
X1509023Y2044911D01*
G01X1509161Y2041565D02*
X1509158Y2041603D01*
X1509151Y2041640D01*
X1509138Y2041674D01*
X1509121Y2041704D01*
X1509100Y2041728D01*
X1509076Y2041747D01*
X1509050Y2041758D01*
X1509023Y2041762D01*
G01X1509161Y2038415D02*
X1509158Y2038453D01*
X1509151Y2038490D01*
X1509138Y2038524D01*
X1509121Y2038554D01*
X1509100Y2038579D01*
X1509076Y2038597D01*
X1509050Y2038608D01*
X1509023Y2038612D01*
G01X1509161Y2035266D02*
X1509158Y2035304D01*
X1509151Y2035341D01*
X1509138Y2035375D01*
X1509121Y2035405D01*
X1509100Y2035429D01*
X1509076Y2035447D01*
X1509050Y2035459D01*
X1509023Y2035463D01*
G01X1509161Y2032116D02*
X1509158Y2032154D01*
X1509151Y2032191D01*
X1509138Y2032225D01*
X1509121Y2032255D01*
X1509100Y2032280D01*
X1509076Y2032298D01*
X1509050Y2032309D01*
X1509023Y2032313D01*
G01X1509161Y2028966D02*
X1509158Y2029005D01*
X1509151Y2029041D01*
X1509138Y2029075D01*
X1509121Y2029106D01*
X1509100Y2029130D01*
X1509076Y2029148D01*
X1509050Y2029159D01*
X1509023Y2029163D01*
G01X1509161Y2025817D02*
X1509158Y2025855D01*
X1509151Y2025892D01*
X1509138Y2025926D01*
X1509121Y2025956D01*
X1509100Y2025980D01*
X1509076Y2025999D01*
X1509050Y2026010D01*
X1509023Y2026014D01*
G01X1509161Y2022667D02*
X1509158Y2022705D01*
X1509151Y2022742D01*
X1509138Y2022776D01*
X1509121Y2022806D01*
X1509100Y2022831D01*
X1509076Y2022849D01*
X1509050Y2022860D01*
X1509023Y2022864D01*
G01X1509161Y2019518D02*
X1509158Y2019556D01*
X1509151Y2019593D01*
X1509138Y2019627D01*
X1509121Y2019657D01*
X1509100Y2019681D01*
X1509076Y2019699D01*
X1509050Y2019711D01*
X1509023Y2019714D01*
G01X1509161Y2016368D02*
X1509158Y2016406D01*
X1509151Y2016443D01*
X1509138Y2016477D01*
X1509121Y2016507D01*
X1509100Y2016532D01*
X1509076Y2016550D01*
X1509050Y2016561D01*
X1509023Y2016565D01*
G01X1509093Y2017252D02*
X1509090Y2017213D01*
X1509081Y2017177D01*
X1509068Y2017143D01*
X1509049Y2017112D01*
X1509027Y2017088D01*
X1509002Y2017070D01*
X1508974Y2017059D01*
X1508945Y2017055D01*
G01X1509093Y2020401D02*
X1509090Y2020363D01*
X1509081Y2020326D01*
X1509068Y2020292D01*
X1509049Y2020262D01*
X1509027Y2020238D01*
X1509002Y2020220D01*
X1508974Y2020208D01*
X1508945Y2020204D01*
G01X1509093Y2023551D02*
X1509090Y2023513D01*
X1509081Y2023476D01*
X1509068Y2023442D01*
X1509049Y2023412D01*
X1509027Y2023387D01*
X1509002Y2023369D01*
X1508974Y2023358D01*
X1508945Y2023354D01*
G01X1509093Y2026701D02*
X1509090Y2026662D01*
X1509081Y2026625D01*
X1509068Y2026592D01*
X1509049Y2026561D01*
X1509027Y2026537D01*
X1509002Y2026519D01*
X1508974Y2026508D01*
X1508945Y2026504D01*
G01X1507941Y2017252D02*
X1507940Y2017213D01*
X1507938Y2017177D01*
X1507935Y2017143D01*
X1507931Y2017112D01*
X1507926Y2017088D01*
X1507921Y2017070D01*
X1507915Y2017059D01*
X1507908Y2017055D01*
G01X1507941Y2020401D02*
X1507940Y2020363D01*
X1507938Y2020326D01*
X1507935Y2020292D01*
X1507931Y2020262D01*
X1507926Y2020238D01*
X1507921Y2020220D01*
X1507915Y2020208D01*
X1507908Y2020204D01*
G01X1507941Y2023551D02*
X1507940Y2023513D01*
X1507938Y2023476D01*
X1507935Y2023442D01*
X1507931Y2023412D01*
X1507926Y2023387D01*
X1507921Y2023369D01*
X1507915Y2023358D01*
X1507908Y2023354D01*
G01X1507941Y2026701D02*
X1507940Y2026662D01*
X1507938Y2026625D01*
X1507935Y2026592D01*
X1507931Y2026561D01*
X1507926Y2026537D01*
X1507921Y2026519D01*
X1507915Y2026508D01*
X1507908Y2026504D01*
G01X1510338Y2060069D02*
Y2060463D01*
G01Y2056919D02*
Y2057313D01*
G01Y2053770D02*
Y2054163D01*
G01Y2050620D02*
Y2051014D01*
G01Y2047470D02*
Y2047864D01*
G01Y2044321D02*
Y2044714D01*
G01Y2041171D02*
Y2041565D01*
G01Y2038022D02*
Y2038415D01*
G01Y2034872D02*
Y2035266D01*
G01Y2031722D02*
Y2032116D01*
G01Y2025423D02*
Y2025817D01*
G01Y2028573D02*
Y2028966D01*
G01Y2022274D02*
Y2022667D01*
G01Y2015974D02*
Y2016368D01*
G01Y2019124D02*
Y2019518D01*
G01X1510241Y2032018D02*
Y2031624D01*
G01X1510176Y2037018D02*
Y2036624D01*
G01Y2042018D02*
Y2041624D01*
G01Y2047018D02*
Y2046624D01*
G01Y2052018D02*
Y2051624D01*
G01Y2057018D02*
Y2056624D01*
G01Y2062018D02*
Y2061624D01*
G01X1510035Y2018236D02*
Y2017252D01*
G01Y2021386D02*
Y2020401D01*
G01Y2024535D02*
Y2023551D01*
G01Y2027685D02*
Y2026701D01*
G01X1509332Y2032018D02*
Y2031624D01*
G01Y2037018D02*
Y2036624D01*
G01Y2042018D02*
Y2041624D01*
G01Y2047018D02*
Y2046624D01*
G01Y2052018D02*
Y2051624D01*
G01Y2057018D02*
Y2056624D01*
G01Y2062018D02*
Y2061624D01*
G01X1509161Y2060069D02*
Y2060463D01*
G01Y2056919D02*
Y2057313D01*
G01Y2053770D02*
Y2054163D01*
G01Y2050620D02*
Y2051014D01*
G01Y2047470D02*
Y2047864D01*
G01Y2044321D02*
Y2044714D01*
G01Y2041171D02*
Y2041565D01*
G01Y2038022D02*
Y2038415D01*
G01Y2034872D02*
Y2035266D01*
G01Y2031722D02*
Y2032116D01*
G01Y2025423D02*
Y2025817D01*
G01Y2028573D02*
Y2028966D01*
G01Y2022274D02*
Y2022667D01*
G01Y2015974D02*
Y2016368D01*
G01Y2019124D02*
Y2019518D01*
G01X1509093Y2018236D02*
Y2017252D01*
G01Y2021386D02*
Y2020401D01*
G01Y2024535D02*
Y2023551D01*
G01Y2027685D02*
Y2026701D01*
G01X1508648Y2016368D02*
Y2015974D01*
G01Y2019518D02*
Y2019124D01*
G01Y2022667D02*
Y2022274D01*
G01Y2025817D02*
Y2025423D01*
G01Y2028966D02*
Y2028573D01*
G01Y2032116D02*
Y2031722D01*
G01Y2038415D02*
Y2038022D01*
G01Y2035266D02*
Y2034872D01*
G01Y2041565D02*
Y2041171D01*
G01Y2047864D02*
Y2047470D01*
G01Y2044714D02*
Y2044321D01*
G01Y2051014D02*
Y2050620D01*
G01Y2057313D02*
Y2056919D01*
G01Y2054163D02*
Y2053770D01*
G01Y2060463D02*
Y2060069D01*
G01X1508208Y2061624D02*
Y2062018D01*
G01Y2056624D02*
Y2057018D01*
G01Y2051624D02*
Y2052018D01*
G01Y2046624D02*
Y2047018D01*
G01Y2041624D02*
Y2042018D01*
G01Y2036624D02*
Y2037018D01*
G01Y2031624D02*
Y2032018D01*
G01X1507941Y2018236D02*
Y2017252D01*
G01Y2021386D02*
Y2020401D01*
G01Y2024535D02*
Y2023551D01*
G01Y2027685D02*
Y2026701D01*
G01X1506209Y2029065D02*
Y2030246D01*
G01X1503727Y2016368D02*
Y2015974D01*
G01Y2019518D02*
Y2019124D01*
G01Y2022667D02*
Y2022274D01*
G01Y2025817D02*
Y2025423D01*
G01Y2028966D02*
Y2028573D01*
G01Y2032116D02*
Y2031722D01*
G01Y2038415D02*
Y2038022D01*
G01Y2035266D02*
Y2034872D01*
G01Y2041565D02*
Y2041171D01*
G01Y2047864D02*
Y2047470D01*
G01Y2044714D02*
Y2044321D01*
G01Y2051014D02*
Y2050620D01*
G01Y2057313D02*
Y2056919D01*
G01Y2054163D02*
Y2053770D01*
G01Y2060463D02*
Y2060069D01*
G01X1503717Y2026701D02*
Y2027685D01*
G01Y2020401D02*
Y2021386D01*
G01Y2023551D02*
Y2024535D01*
G01Y2017252D02*
Y2018236D01*
G01X1503590Y2061624D02*
Y2062018D01*
G01Y2056624D02*
Y2057018D01*
G01Y2051624D02*
Y2052018D01*
G01Y2046624D02*
Y2047018D01*
G01Y2041624D02*
Y2042018D01*
G01Y2036624D02*
Y2037018D01*
G01X1503499Y2031624D02*
Y2032018D01*
G01X1500921Y2035423D02*
Y2066427D01*
G01X1500751Y2030042D02*
Y2035423D01*
G01X1497772Y2077726D02*
Y2070561D01*
G01X1508208Y2031624D02*
X1508130Y2031033D01*
G01X1508208Y2036624D02*
X1508130Y2036033D01*
G01X1508208Y2041624D02*
X1508130Y2041033D01*
G01X1508208Y2046624D02*
X1508130Y2046033D01*
G01X1508208Y2051624D02*
X1508130Y2051033D01*
G01X1508208Y2056624D02*
X1508130Y2056033D01*
G01X1508208Y2061624D02*
X1508130Y2061033D01*
G01X1508648Y2019124D02*
X1508638Y2019026D01*
X1508610Y2018953D01*
X1508572Y2018927D01*
G01X1508648Y2022274D02*
X1508638Y2022175D01*
X1508610Y2022103D01*
X1508572Y2022077D01*
G01X1508648Y2025423D02*
X1508638Y2025325D01*
X1508610Y2025253D01*
X1508572Y2025226D01*
G01X1508648Y2028573D02*
X1508638Y2028474D01*
X1508610Y2028402D01*
X1508572Y2028376D01*
G01X1508648Y2038022D02*
X1508638Y2037923D01*
X1508610Y2037851D01*
X1508572Y2037825D01*
G01X1508648Y2041171D02*
X1508638Y2041073D01*
X1508610Y2041001D01*
X1508572Y2040974D01*
G01X1508648Y2053770D02*
X1508638Y2053671D01*
X1508610Y2053599D01*
X1508572Y2053573D01*
G01X1508648Y2056919D02*
X1508638Y2056821D01*
X1508610Y2056749D01*
X1508572Y2056722D01*
G01X1509332Y2031624D02*
X1509060Y2031033D01*
G01X1509332Y2036624D02*
X1509060Y2036033D01*
G01X1509332Y2041624D02*
X1509060Y2041033D01*
G01X1509332Y2046624D02*
X1509060Y2046033D01*
G01X1509332Y2051624D02*
X1509060Y2051033D01*
G01X1509332Y2056624D02*
X1509060Y2056033D01*
G01X1509332Y2061624D02*
X1509060Y2061033D01*
G01X1497740Y2078876D02*
X1497683Y2078742D01*
X1497677Y2078506D01*
X1497714Y2078177D01*
G01X1497740Y2078876D02*
X1497682Y2078736D01*
X1497677Y2078496D01*
G01X1509749Y2036033D02*
X1510176Y2036624D01*
G01X1509749Y2041033D02*
X1510176Y2041624D01*
G01X1509749Y2046033D02*
X1510176Y2046624D01*
G01X1509749Y2051033D02*
X1510176Y2051624D01*
G01X1509749Y2056033D02*
X1510176Y2056624D01*
G01X1509817Y2031033D02*
X1510241Y2031624D01*
G01X1504004Y2037608D02*
X1503865Y2037412D01*
X1503727Y2037215D01*
X1503590Y2037018D01*
G01X1504004Y2042608D02*
X1503865Y2042412D01*
X1503727Y2042215D01*
X1503590Y2042018D01*
G01X1504004Y2047608D02*
X1503865Y2047412D01*
X1503727Y2047215D01*
X1503590Y2047018D01*
G01X1504004Y2052608D02*
X1503865Y2052412D01*
X1503727Y2052215D01*
X1503590Y2052018D01*
G01X1503904Y2032608D02*
X1503768Y2032412D01*
X1503633Y2032215D01*
X1503499Y2032018D01*
G01X1508572Y2015777D02*
X1508610Y2015804D01*
X1508638Y2015876D01*
X1508648Y2015974D01*
G01X1508572Y2031525D02*
X1508610Y2031552D01*
X1508638Y2031624D01*
X1508648Y2031722D01*
G01X1508572Y2034675D02*
X1508610Y2034702D01*
X1508638Y2034774D01*
X1508648Y2034872D01*
G01X1508572Y2044124D02*
X1508610Y2044150D01*
X1508638Y2044222D01*
X1508648Y2044321D01*
G01X1508572Y2047274D02*
X1508610Y2047300D01*
X1508638Y2047372D01*
X1508648Y2047470D01*
G01X1508572Y2050423D02*
X1508610Y2050450D01*
X1508638Y2050522D01*
X1508648Y2050620D01*
G01X1501709Y2070561D02*
X1499740Y2068592D01*
G01X1509749Y2061033D02*
X1510176Y2061624D01*
G01X1504004Y2057608D02*
X1503865Y2057412D01*
X1503727Y2057215D01*
X1503590Y2057018D01*
G01X1504004Y2062608D02*
X1503865Y2062412D01*
X1503727Y2062215D01*
X1503590Y2062018D01*
G01X1508572Y2059872D02*
X1508610Y2059898D01*
X1508638Y2059970D01*
X1508648Y2060069D01*
G01X1539440Y2015699D02*
X1537558D01*
G01X1533442Y2015581D02*
X1532458D01*
G01X1533442Y2015384D02*
X1532458D01*
G01X1531551Y2015187D02*
X1537576D01*
G01X1531551Y2014006D02*
X1537576D01*
G01X1533442Y2013809D02*
X1532458D01*
G01X1533442Y2013612D02*
X1532458D01*
G01X1539440Y2013494D02*
X1537558D01*
G01X1542605Y2013415D02*
X1549937D01*
G01X1542457D02*
X1530449D01*
G01X1542457Y2012628D02*
X1530449D01*
G01X1549937D02*
X1542605D01*
G01X1533442Y2012431D02*
X1532458D01*
G01X1533442Y2012234D02*
X1532458D01*
G01X1531551Y2012037D02*
X1537576D01*
G01X1549937Y2013415D02*
Y2012628D01*
G01X1548163Y2013415D02*
Y2012628D01*
G01X1547975D02*
Y2013415D01*
G01X1545138Y2012628D02*
Y2013415D01*
G01X1544197D02*
Y2012628D01*
G01X1542605Y2013415D02*
Y2012628D01*
G01X1542457Y2013415D02*
Y2012628D01*
G01X1541519Y2013415D02*
Y2015777D01*
G01X1539791Y2013415D02*
Y2012628D01*
G01X1539440Y2015699D02*
Y2013494D01*
G01X1538139Y2012628D02*
Y2013415D01*
G01X1537984Y2022943D02*
Y2015699D01*
G01X1537576Y2014006D02*
Y2015187D01*
G01X1537558Y2013494D02*
Y2015699D01*
G01X1536156Y2012628D02*
Y2013415D01*
G01X1534427Y2015187D02*
Y2014006D01*
G01X1532793Y2013415D02*
Y2012628D01*
G01X1532458Y2015777D02*
Y2013415D01*
G01X1532417D02*
Y2012628D01*
G01X1532391Y2013415D02*
Y2012628D01*
G01X1532220Y2084360D02*
G03Y2087510I0J1575D01*
G01X1533143Y2075965D02*
G03X1533685Y2076949I-1276J1344D01*
G01X1541472Y2074124D02*
G03I-2165J0D01*
G01X1542653D02*
G03I-3346J0D01*
G01X1542811D02*
G03I-3504J0D01*
G01X1533648Y2075421D02*
G03X1534718Y2077244I-2809J2874D01*
G01X1543835Y2074124D02*
G03I-4528J0D01*
G01X1547119Y2072520D02*
G03X1549334Y2077687I-6937J6032D01*
G01X1546234Y2072446D02*
G03X1548448Y2077687I-7142J6105D01*
G01X1531945Y2061033D02*
G03X1531551Y2060640I0J-394D01*
G01Y2063002D02*
G03X1531945Y2062608I394J0D01*
G01Y2031033D02*
G03X1531551Y2030640I0J-394D01*
G01Y2033002D02*
G03X1531945Y2032608I394J0D01*
G01Y2036033D02*
G03X1531551Y2035640I0J-394D01*
G01Y2038002D02*
G03X1531945Y2037608I394J0D01*
G01Y2041033D02*
G03X1531551Y2040640I0J-394D01*
G01Y2043002D02*
G03X1531945Y2042608I394J0D01*
G01Y2051033D02*
G03X1531551Y2050640I0J-394D01*
G01Y2053002D02*
G03X1531945Y2052608I394J0D01*
G01Y2046033D02*
G03X1531551Y2045640I0J-394D01*
G01Y2048002D02*
G03X1531945Y2047608I394J0D01*
G01Y2056033D02*
G03X1531551Y2055640I0J-394D01*
G01Y2058002D02*
G03X1531945Y2057608I394J0D01*
G01X1527890Y2087510D02*
G03Y2084360I0J-1575D01*
G01X1526672Y2072520D02*
G03X1528886Y2077687I-6938J6031D01*
G01X1525786Y2072446D02*
G03X1528001Y2077687I-7142J6107D01*
G01X1526522Y2064321D02*
X1526174Y2064235D01*
G01X1528177Y2064065D02*
X1527829Y2063980D01*
G01X1532220Y2084360D02*
X1527890D01*
G01X1538244Y2081663D02*
X1521866D01*
G01X1528886Y2077687D02*
X1528000D01*
G01X1534718D02*
X1530806D01*
G01X1549334D02*
X1548448D01*
G01X1530806Y2076949D02*
X1533684D01*
G01X1551709Y2076939D02*
X1528087D01*
G01X1534423Y2073479D02*
X1533611D01*
G01X1528087Y2073159D02*
X1551709D01*
G01X1529624Y2072520D02*
X1526672D01*
G01X1550072D02*
X1547119D01*
G01X1546234Y2071781D02*
X1550072D01*
G01X1525786D02*
X1529624D01*
G01X1551709Y2071191D02*
X1528087D01*
G01Y2068750D02*
X1551709D01*
G01X1536549Y2068258D02*
X1530449D01*
G01X1536549Y2068199D02*
X1530449D01*
G01X1550916Y2067805D02*
X1530449D01*
G01X1531551Y2066624D02*
X1522181D01*
G01X1521866Y2065443D02*
X1528401D01*
G01X1531551Y2065226D02*
X1551709D01*
G01X1531551Y2064852D02*
X1522181D01*
G01X1528526Y2064065D02*
X1528177D01*
G01X1528265Y2063553D02*
X1528439D01*
G01X1534976Y2063396D02*
X1533992D01*
G01X1535567Y2063238D02*
X1544551D01*
G01X1534976Y2063199D02*
X1533992D01*
G01X1534976Y2062805D02*
X1533992D01*
G01X1540075Y2062785D02*
X1532004D01*
G01X1531945Y2062608D02*
X1539110D01*
G01X1526696Y2061676D02*
X1526435D01*
G01X1526348Y2061165D02*
X1526784D01*
G01X1531945Y2061033D02*
X1539110D01*
G01X1534976Y2060837D02*
X1533992D01*
G01X1532004Y2060817D02*
X1540075D01*
G01X1542605Y2060659D02*
X1549937D01*
G01X1542457D02*
X1530449D01*
G01X1528177Y2060482D02*
X1528874D01*
G01X1534976Y2060443D02*
X1533992D01*
G01X1534976Y2060246D02*
X1533992D01*
G01X1525390Y2059970D02*
X1528787D01*
G01X1542457Y2059872D02*
X1530449D01*
G01X1549937D02*
X1542605D01*
G01X1529484Y2059459D02*
X1525390D01*
G01X1534976Y2058396D02*
X1533992D01*
G01X1534976Y2058199D02*
X1533992D01*
G01X1534976Y2057805D02*
X1533992D01*
G01X1531945Y2057608D02*
X1539110D01*
G01X1542605Y2057510D02*
X1549937D01*
G01X1542457D02*
X1530449D01*
G01X1542457Y2056722D02*
X1530449D01*
G01X1549937D02*
X1542605D01*
G01X1531945Y2056033D02*
X1539110D01*
G01X1534976Y2055837D02*
X1533992D01*
G01X1534976Y2055443D02*
X1533992D01*
G01X1534976Y2055246D02*
X1533992D01*
G01X1542605Y2054360D02*
X1549937D01*
G01X1542457D02*
X1530449D01*
G01X1542457Y2053573D02*
X1530449D01*
G01X1549937D02*
X1542605D01*
G01X1534976Y2053396D02*
X1533992D01*
G01X1534976Y2053199D02*
X1533992D01*
G01X1534976Y2052805D02*
X1533992D01*
G01X1531945Y2052608D02*
X1539110D01*
G01X1542605Y2051211D02*
X1549937D01*
G01X1542457D02*
X1530449D01*
G01X1531945Y2051033D02*
X1539110D01*
G01X1534976Y2050837D02*
X1533992D01*
G01X1534976Y2050443D02*
X1533992D01*
G01X1542457Y2050423D02*
X1530449D01*
G01X1549937D02*
X1542605D01*
G01X1534976Y2050246D02*
X1533992D01*
G01X1534976Y2048396D02*
X1533992D01*
G01X1534976Y2048199D02*
X1533992D01*
G01X1542605Y2048061D02*
X1549937D01*
G01X1542457D02*
X1530449D01*
G01X1534976Y2047805D02*
X1533992D01*
G01X1531945Y2047608D02*
X1539110D01*
G01X1542457Y2047274D02*
X1530449D01*
G01X1549937D02*
X1542605D01*
G01X1531945Y2046033D02*
X1539110D01*
G01X1534976Y2045837D02*
X1533992D01*
G01X1534976Y2045443D02*
X1533992D01*
G01X1534976Y2045246D02*
X1533992D01*
G01X1542605Y2044911D02*
X1549937D01*
G01X1542457D02*
X1530449D01*
G01X1542457Y2044124D02*
X1530449D01*
G01X1549937D02*
X1542605D01*
G01X1532712Y2072520D02*
X1532365Y2072589D01*
G01X1534976Y2043396D02*
X1533992D01*
G01X1534976Y2043199D02*
X1533992D01*
G01X1534976Y2042805D02*
X1533992D01*
G01X1531945Y2042608D02*
X1539110D01*
G01X1542605Y2041762D02*
X1549937D01*
G01X1542457D02*
X1530449D01*
G01X1531945Y2041033D02*
X1539110D01*
G01X1542457Y2040974D02*
X1530449D01*
G01X1549937D02*
X1542605D01*
G01X1534976Y2040837D02*
X1533992D01*
G01X1534976Y2040443D02*
X1533992D01*
G01X1534976Y2040246D02*
X1533992D01*
G01X1542605Y2038612D02*
X1549937D01*
G01X1542457D02*
X1530449D01*
G01X1534976Y2038396D02*
X1533992D01*
G01X1534976Y2038199D02*
X1533992D01*
G01X1542457Y2037825D02*
X1530449D01*
G01X1549937D02*
X1542605D01*
G01X1534976Y2037805D02*
X1533992D01*
G01X1531945Y2037608D02*
X1539110D01*
G01X1531945Y2036033D02*
X1539110D01*
G01X1534976Y2035837D02*
X1533992D01*
G01X1542605Y2035463D02*
X1549937D01*
G01X1542457D02*
X1530449D01*
G01X1534976Y2035443D02*
X1533992D01*
G01X1534976Y2035246D02*
X1533992D01*
G01X1542457Y2034675D02*
X1530449D01*
G01X1549937D02*
X1542605D01*
G01X1600921Y2034124D02*
X1561551D01*
G01X1534976Y2033396D02*
X1533992D01*
G01X1534976Y2033199D02*
X1533992D01*
G01X1534976Y2032805D02*
X1533992D01*
G01X1531945Y2032608D02*
X1539110D01*
G01X1542605Y2032313D02*
X1549937D01*
G01X1542457D02*
X1530449D01*
G01X1542457Y2031525D02*
X1530449D01*
G01X1549937D02*
X1542605D01*
G01X1531945Y2031033D02*
X1539110D01*
G01X1534976Y2030837D02*
X1533992D01*
G01X1534976Y2030443D02*
X1533992D01*
G01X1534976Y2030246D02*
X1533992D01*
G01X1542605Y2029163D02*
X1549937D01*
G01X1542457D02*
X1530449D01*
G01X1531551Y2029085D02*
X1530449D01*
G01Y2028966D02*
X1537984D01*
G01X1535567Y2028474D02*
X1533442D01*
G01X1542457Y2028376D02*
X1530449D01*
G01X1549937D02*
X1542605D01*
G01X1533442Y2028179D02*
X1532458D01*
G01X1533442Y2027982D02*
X1532458D01*
G01X1531551Y2027785D02*
X1537576D01*
G01X1531551Y2026604D02*
X1537576D01*
G01X1533442Y2026407D02*
X1532458D01*
G01X1533442Y2026211D02*
X1532458D01*
G01X1542605Y2026014D02*
X1549937D01*
G01X1542457D02*
X1530449D01*
G01X1542457Y2025226D02*
X1530449D01*
G01X1549937D02*
X1542605D01*
G01X1539440Y2025148D02*
X1537558D01*
G01X1533442Y2025029D02*
X1532458D01*
G01X1533442Y2024833D02*
X1532458D01*
G01X1531551Y2024636D02*
X1537576D01*
G01X1531551Y2023455D02*
X1537576D01*
G01X1533442Y2023258D02*
X1532458D01*
G01X1533442Y2023061D02*
X1532458D01*
G01X1539440Y2022943D02*
X1537558D01*
G01X1542605Y2022864D02*
X1549937D01*
G01X1542457D02*
X1530449D01*
G01X1542457Y2022077D02*
X1530449D01*
G01X1549937D02*
X1542605D01*
G01X1533442Y2021880D02*
X1532458D01*
G01X1533442Y2021683D02*
X1532458D01*
G01X1531551Y2021486D02*
X1537576D01*
G01X1531551Y2020305D02*
X1537576D01*
G01X1533442Y2020108D02*
X1532458D01*
G01X1533442Y2019911D02*
X1532458D01*
G01X1542605Y2019714D02*
X1549937D01*
G01X1542457D02*
X1530449D01*
G01X1542457Y2018927D02*
X1530449D01*
G01X1549937D02*
X1542605D01*
G01X1533442Y2018730D02*
X1532458D01*
G01X1533442Y2018533D02*
X1532458D01*
G01X1531551Y2018337D02*
X1537576D01*
G01X1531551Y2017155D02*
X1537576D01*
G01X1533442Y2016959D02*
X1532458D01*
G01X1533442Y2016762D02*
X1532458D01*
G01X1542605Y2016565D02*
X1549937D01*
G01X1542457D02*
X1530449D01*
G01X1542457Y2015777D02*
X1530449D01*
G01X1549937D02*
X1542605D01*
G01X1528874Y2063980D02*
X1528526Y2064065D01*
G01X1528439Y2063553D02*
X1528700Y2063468D01*
G01X1525999Y2061335D02*
X1526348Y2061165D01*
G01X1543482Y2076871D02*
X1543843Y2076635D01*
X1544081Y2076285D01*
X1544167Y2075881D01*
X1544084Y2075479D01*
X1543848Y2075127D01*
X1543484Y2074887D01*
X1543059Y2074802D01*
G01X1542636Y2074886D02*
X1542276Y2075122D01*
X1542038Y2075472D01*
X1541952Y2075876D01*
X1542035Y2076278D01*
X1542271Y2076630D01*
X1542635Y2076870D01*
X1543059Y2076955D01*
G01X1538315Y2076871D02*
X1538675Y2076635D01*
X1538914Y2076285D01*
X1538999Y2075881D01*
X1538917Y2075479D01*
X1538680Y2075127D01*
X1538317Y2074887D01*
X1537892Y2074802D01*
G01X1537469Y2074886D02*
X1537109Y2075122D01*
X1536870Y2075472D01*
X1536785Y2075876D01*
X1536867Y2076278D01*
X1537104Y2076630D01*
X1537467Y2076870D01*
X1537892Y2076955D01*
G01X1526435Y2061676D02*
X1526174Y2061847D01*
G01X1532366Y2072589D02*
X1532086Y2072770D01*
G01X1543408Y2074079D02*
X1543691Y2073901D01*
X1543878Y2073636D01*
X1543945Y2073334D01*
X1543881Y2073033D01*
X1543695Y2072767D01*
X1543410Y2072585D01*
X1543059Y2072520D01*
G01X1542711Y2072585D02*
X1542428Y2072762D01*
X1542241Y2073028D01*
X1542174Y2073329D01*
X1542238Y2073630D01*
X1542424Y2073897D01*
X1542709Y2074078D01*
X1543059Y2074144D01*
G01X1538241Y2074079D02*
X1538524Y2073901D01*
X1538711Y2073636D01*
X1538778Y2073334D01*
X1538713Y2073033D01*
X1538528Y2072767D01*
X1538243Y2072585D01*
X1537892Y2072520D01*
G01X1537543Y2072585D02*
X1537261Y2072762D01*
X1537073Y2073028D01*
X1537006Y2073329D01*
X1537071Y2073630D01*
X1537256Y2073897D01*
X1537542Y2074078D01*
X1537892Y2074144D01*
G01X1528874Y2060482D02*
X1529484Y2059970D01*
G01X1528787D02*
X1528177Y2060482D01*
G01X1529223Y2063638D02*
X1528874Y2063980D01*
G01X1525651Y2061676D02*
X1525999Y2061335D01*
G01X1541862Y2074430D02*
X1541410Y2074871D01*
X1541140Y2075406D01*
X1541070Y2075977D01*
X1541211Y2076541D01*
X1541558Y2077065D01*
X1542085Y2077459D01*
X1542728Y2077662D01*
X1543407Y2077660D01*
X1544047Y2077452D01*
X1544570Y2077055D01*
X1544912Y2076532D01*
X1545050Y2075971D01*
X1544978Y2075403D01*
X1544708Y2074869D01*
G01X1536694Y2074430D02*
X1536243Y2074871D01*
X1535973Y2075406D01*
X1535902Y2075977D01*
X1536044Y2076541D01*
X1536391Y2077065D01*
X1536918Y2077459D01*
X1537561Y2077662D01*
X1538240Y2077660D01*
X1538880Y2077452D01*
X1539403Y2077055D01*
X1539744Y2076532D01*
X1539882Y2075971D01*
X1539811Y2075403D01*
X1539540Y2074869D01*
G01X1532086Y2072769D02*
X1531903Y2073034D01*
X1531839Y2073333D01*
X1531904Y2073630D01*
G01X1544257Y2074430D02*
X1544580Y2074011D01*
X1544742Y2073528D01*
X1544721Y2073023D01*
X1544518Y2072546D01*
X1544151Y2072143D01*
X1543645Y2071875D01*
X1543054Y2071781D01*
X1542464Y2071879D01*
X1541962Y2072147D01*
X1541598Y2072551D01*
X1541397Y2073029D01*
X1541377Y2073534D01*
X1541541Y2074015D01*
X1541862Y2074430D01*
G01X1539090D02*
X1539413Y2074011D01*
X1539575Y2073528D01*
X1539553Y2073023D01*
X1539350Y2072546D01*
X1538984Y2072143D01*
X1538477Y2071875D01*
X1537886Y2071781D01*
X1537297Y2071879D01*
X1536795Y2072147D01*
X1536431Y2072551D01*
X1536229Y2073029D01*
X1536210Y2073534D01*
X1536374Y2074015D01*
X1536694Y2074430D01*
G01X1536804Y2067805D02*
X1536549Y2068199D01*
G01X1528700Y2063468D02*
X1528874Y2063212D01*
G01X1526174Y2061847D02*
X1525999Y2062103D01*
G01X1529397Y2063297D02*
X1529223Y2063638D01*
G01X1525477Y2062018D02*
X1525651Y2061676D01*
G01X1528874Y2063212D02*
X1528961Y2062956D01*
G01X1525390Y2062444D02*
X1525477Y2062018D01*
G01X1529484Y2062956D02*
X1529397Y2063297D01*
G01X1525999Y2062103D02*
X1525912Y2062444D01*
G01X1561551Y2034124D02*
Y2114006D01*
G01X1551709Y2065226D02*
Y2078907D01*
G01X1551391Y2065226D02*
Y2070561D01*
G01X1550916Y2065226D02*
Y2067805D01*
G01X1550072Y2071781D02*
Y2072520D01*
G01X1549937Y2019714D02*
Y2018927D01*
G01Y2016565D02*
Y2015777D01*
G01Y2022864D02*
Y2022077D01*
G01Y2029163D02*
Y2028376D01*
G01Y2026014D02*
Y2025226D01*
G01Y2032313D02*
Y2031525D01*
G01Y2038612D02*
Y2037825D01*
G01Y2035463D02*
Y2034675D01*
G01Y2041762D02*
Y2040974D01*
G01Y2048061D02*
Y2047274D01*
G01Y2044911D02*
Y2044124D01*
G01Y2051211D02*
Y2050423D01*
G01Y2057510D02*
Y2056722D01*
G01Y2054360D02*
Y2053573D01*
G01Y2060659D02*
Y2059872D01*
G01X1548163Y2019714D02*
Y2018927D01*
G01Y2016565D02*
Y2015777D01*
G01Y2022864D02*
Y2022077D01*
G01Y2029163D02*
Y2028376D01*
G01Y2026014D02*
Y2025226D01*
G01Y2032313D02*
Y2031525D01*
G01Y2038612D02*
Y2037825D01*
G01Y2035463D02*
Y2034675D01*
G01Y2041762D02*
Y2040974D01*
G01Y2048061D02*
Y2047274D01*
G01Y2044911D02*
Y2044124D01*
G01Y2051211D02*
Y2050423D01*
G01Y2057510D02*
Y2056722D01*
G01Y2054360D02*
Y2053573D01*
G01Y2060659D02*
Y2059872D01*
G01X1547975D02*
Y2060659D01*
G01Y2056722D02*
Y2057510D01*
G01Y2053573D02*
Y2054360D01*
G01Y2050423D02*
Y2051211D01*
G01Y2047274D02*
Y2048061D01*
G01Y2044124D02*
Y2044911D01*
G01Y2040974D02*
Y2041762D01*
G01Y2037825D02*
Y2038612D01*
G01Y2034675D02*
Y2035463D01*
G01Y2031525D02*
Y2032313D01*
G01Y2028376D02*
Y2029163D01*
G01Y2025226D02*
Y2026014D01*
G01Y2022077D02*
Y2022864D01*
G01Y2018927D02*
Y2019714D01*
G01Y2015777D02*
Y2016565D01*
G01X1546234Y2072446D02*
Y2071781D01*
G01X1545138Y2059872D02*
Y2060659D01*
G01Y2056722D02*
Y2057510D01*
G01Y2053573D02*
Y2054360D01*
G01Y2050423D02*
Y2051211D01*
G01Y2047274D02*
Y2048061D01*
G01Y2044124D02*
Y2044911D01*
G01Y2040974D02*
Y2041762D01*
G01Y2037825D02*
Y2038612D01*
G01Y2034675D02*
Y2035463D01*
G01Y2031525D02*
Y2032313D01*
G01Y2028376D02*
Y2029163D01*
G01Y2025226D02*
Y2026014D01*
G01Y2022077D02*
Y2022864D01*
G01Y2018927D02*
Y2019714D01*
G01Y2015777D02*
Y2016565D01*
G01X1545062Y2070561D02*
Y2067805D01*
G01X1544197Y2019714D02*
Y2018927D01*
G01Y2016565D02*
Y2015777D01*
G01Y2022864D02*
Y2022077D01*
G01Y2029163D02*
Y2028376D01*
G01Y2026014D02*
Y2025226D01*
G01Y2032313D02*
Y2031525D01*
G01Y2038612D02*
Y2037825D01*
G01Y2035463D02*
Y2034675D01*
G01Y2041762D02*
Y2040974D01*
G01Y2048061D02*
Y2047274D01*
G01Y2044911D02*
Y2044124D01*
G01Y2051211D02*
Y2050423D01*
G01Y2057510D02*
Y2056722D01*
G01Y2054360D02*
Y2053573D01*
G01Y2060659D02*
Y2059872D01*
G01X1542605Y2019714D02*
Y2018927D01*
G01Y2016565D02*
Y2015777D01*
G01Y2022864D02*
Y2022077D01*
G01Y2029163D02*
Y2028376D01*
G01Y2026014D02*
Y2025226D01*
G01Y2032313D02*
Y2031525D01*
G01Y2038612D02*
Y2037825D01*
G01Y2035463D02*
Y2034675D01*
G01Y2041762D02*
Y2040974D01*
G01Y2048061D02*
Y2047274D01*
G01Y2044911D02*
Y2044124D01*
G01Y2051211D02*
Y2050423D01*
G01Y2057510D02*
Y2056722D01*
G01Y2054360D02*
Y2053573D01*
G01Y2060659D02*
Y2059872D01*
G01X1542457Y2019714D02*
Y2018927D01*
G01Y2016565D02*
Y2015777D01*
G01Y2022864D02*
Y2022077D01*
G01Y2029163D02*
Y2028376D01*
G01Y2026014D02*
Y2025226D01*
G01Y2032313D02*
Y2031525D01*
G01Y2038612D02*
Y2037825D01*
G01Y2035463D02*
Y2034675D01*
G01Y2041762D02*
Y2040974D01*
G01Y2048061D02*
Y2047274D01*
G01Y2044911D02*
Y2044124D01*
G01Y2051211D02*
Y2050423D01*
G01Y2057510D02*
Y2056722D01*
G01Y2054360D02*
Y2053573D01*
G01Y2060659D02*
Y2059872D01*
G01X1541519Y2060659D02*
Y2063238D01*
G01Y2057510D02*
Y2059872D01*
G01Y2054360D02*
Y2056722D01*
G01Y2051211D02*
Y2053573D01*
G01Y2048061D02*
Y2050423D01*
G01Y2044911D02*
Y2047274D01*
G01Y2041762D02*
Y2044124D01*
G01Y2038612D02*
Y2040974D01*
G01Y2035463D02*
Y2037825D01*
G01Y2032313D02*
Y2034675D01*
G01Y2029163D02*
Y2031525D01*
G01Y2026014D02*
Y2028376D01*
G01Y2022864D02*
Y2025226D01*
G01Y2019714D02*
Y2022077D01*
G01Y2016565D02*
Y2018927D01*
G01X1540075Y2060817D02*
Y2062785D01*
G01X1539791Y2019714D02*
Y2018927D01*
G01Y2016565D02*
Y2015777D01*
G01Y2022864D02*
Y2022077D01*
G01Y2029163D02*
Y2028376D01*
G01Y2026014D02*
Y2025226D01*
G01Y2032313D02*
Y2031525D01*
G01Y2038612D02*
Y2037825D01*
G01Y2035463D02*
Y2034675D01*
G01Y2041762D02*
Y2040974D01*
G01Y2048061D02*
Y2047274D01*
G01Y2044911D02*
Y2044124D01*
G01Y2051211D02*
Y2050423D01*
G01Y2057510D02*
Y2056722D01*
G01Y2054360D02*
Y2053573D01*
G01Y2060659D02*
Y2059872D01*
G01X1539440Y2025148D02*
Y2022943D01*
G01X1539110Y2061033D02*
Y2062608D01*
G01Y2056033D02*
Y2057608D01*
G01Y2051033D02*
Y2052608D01*
G01Y2046033D02*
Y2047608D01*
G01Y2041033D02*
Y2042608D01*
G01Y2036033D02*
Y2037608D01*
G01Y2031033D02*
Y2032608D01*
G01X1538244Y2091840D02*
Y2078907D01*
G01X1538139Y2059872D02*
Y2060659D01*
G01Y2056722D02*
Y2057510D01*
G01Y2053573D02*
Y2054360D01*
G01Y2050423D02*
Y2051211D01*
G01Y2047274D02*
Y2048061D01*
G01Y2044124D02*
Y2044911D01*
G01Y2040974D02*
Y2041762D01*
G01Y2037825D02*
Y2038612D01*
G01Y2034675D02*
Y2035463D01*
G01Y2031525D02*
Y2032313D01*
G01Y2028376D02*
Y2029163D01*
G01Y2025226D02*
Y2026014D01*
G01Y2022077D02*
Y2022864D01*
G01Y2018927D02*
Y2019714D01*
G01Y2015777D02*
Y2016565D01*
G01X1537984Y2028966D02*
Y2025148D01*
G01X1537576Y2026604D02*
Y2027785D01*
G01Y2023455D02*
Y2024636D01*
G01Y2020305D02*
Y2021486D01*
G01Y2017155D02*
Y2018337D01*
G01X1537558Y2022943D02*
Y2025148D01*
G01X1537188Y2070561D02*
Y2067805D01*
G01X1536549Y2068199D02*
Y2068258D01*
G01X1536156Y2059872D02*
Y2060659D01*
G01Y2056722D02*
Y2057510D01*
G01Y2053573D02*
Y2054360D01*
G01Y2050423D02*
Y2051211D01*
G01Y2047274D02*
Y2048061D01*
G01Y2044124D02*
Y2044911D01*
G01Y2040974D02*
Y2041762D01*
G01Y2037825D02*
Y2038612D01*
G01Y2034675D02*
Y2035463D01*
G01Y2031525D02*
Y2032313D01*
G01Y2028376D02*
Y2029163D01*
G01Y2025226D02*
Y2026014D01*
G01Y2022077D02*
Y2022864D01*
G01Y2018927D02*
Y2019714D01*
G01Y2015777D02*
Y2016565D01*
G01X1535961Y2032608D02*
Y2031033D01*
G01Y2037608D02*
Y2036033D01*
G01Y2042608D02*
Y2041033D01*
G01Y2047608D02*
Y2046033D01*
G01Y2052608D02*
Y2051033D01*
G01Y2057608D02*
Y2056033D01*
G01Y2062608D02*
Y2061033D01*
G01X1534976Y2033396D02*
Y2030246D01*
G01Y2038396D02*
Y2035246D01*
G01Y2043396D02*
Y2040246D01*
G01Y2048396D02*
Y2045246D01*
G01Y2053396D02*
Y2050246D01*
G01Y2058396D02*
Y2055246D01*
G01Y2063396D02*
Y2060246D01*
G01X1534718Y2077244D02*
Y2077687D01*
G01X1534427Y2018337D02*
Y2017155D01*
G01Y2024636D02*
Y2023455D01*
G01Y2021486D02*
Y2020305D01*
G01Y2027785D02*
Y2026604D01*
G01X1534423Y2073332D02*
Y2073479D01*
G01X1533992Y2068258D02*
Y2070561D01*
G01Y2033396D02*
Y2030246D01*
G01Y2038396D02*
Y2035246D01*
G01Y2043396D02*
Y2040246D01*
G01Y2048396D02*
Y2045246D01*
G01Y2053396D02*
Y2050246D01*
G01Y2058396D02*
Y2055246D01*
G01Y2063396D02*
Y2060246D01*
G01X1533611Y2073479D02*
Y2073332D01*
G01X1533008Y2032608D02*
Y2031033D01*
G01Y2037608D02*
Y2036033D01*
G01Y2042608D02*
Y2041033D01*
G01Y2047608D02*
Y2046033D01*
G01Y2052608D02*
Y2051033D01*
G01Y2057608D02*
Y2056033D01*
G01Y2062608D02*
Y2061033D01*
G01X1532793Y2019714D02*
Y2018927D01*
G01Y2016565D02*
Y2015777D01*
G01Y2022864D02*
Y2022077D01*
G01Y2029163D02*
Y2028376D01*
G01Y2026014D02*
Y2025226D01*
G01Y2032313D02*
Y2031525D01*
G01Y2038612D02*
Y2037825D01*
G01Y2035463D02*
Y2034675D01*
G01Y2041762D02*
Y2040974D01*
G01Y2048061D02*
Y2047274D01*
G01Y2044911D02*
Y2044124D01*
G01Y2051211D02*
Y2050423D01*
G01Y2057510D02*
Y2056722D01*
G01Y2054360D02*
Y2053573D01*
G01Y2060659D02*
Y2059872D01*
G01X1532458Y2018927D02*
Y2016565D01*
G01Y2025226D02*
Y2022864D01*
G01Y2022077D02*
Y2019714D01*
G01Y2028376D02*
Y2026014D01*
G01X1532417Y2019714D02*
Y2018927D01*
G01Y2016565D02*
Y2015777D01*
G01Y2022864D02*
Y2022077D01*
G01Y2029163D02*
Y2028376D01*
G01Y2026014D02*
Y2025226D01*
G01Y2032313D02*
Y2031525D01*
G01Y2038612D02*
Y2037825D01*
G01Y2035463D02*
Y2034675D01*
G01Y2041762D02*
Y2040974D01*
G01Y2048061D02*
Y2047274D01*
G01Y2044911D02*
Y2044124D01*
G01Y2051211D02*
Y2050423D01*
G01Y2057510D02*
Y2056722D01*
G01Y2054360D02*
Y2053573D01*
G01Y2060659D02*
Y2059872D01*
G01X1532391Y2019714D02*
Y2018927D01*
G01Y2016565D02*
Y2015777D01*
G01Y2022864D02*
Y2022077D01*
G01Y2029163D02*
Y2028376D01*
G01Y2026014D02*
Y2025226D01*
G01Y2032313D02*
Y2031525D01*
G01Y2038612D02*
Y2037825D01*
G01Y2035463D02*
Y2034675D01*
G01Y2041762D02*
Y2040974D01*
G01Y2048061D02*
Y2047274D01*
G01Y2044911D02*
Y2044124D01*
G01Y2051211D02*
Y2050423D01*
G01Y2057510D02*
Y2056722D01*
G01Y2054360D02*
Y2053573D01*
G01Y2060659D02*
Y2059872D01*
G01X1532004Y2062785D02*
Y2060817D01*
G01X1530806Y2077687D02*
Y2076949D01*
G01X1529624Y2071781D02*
Y2072520D01*
G01X1529484Y2062529D02*
Y2062956D01*
G01Y2059970D02*
Y2059459D01*
G01X1528961Y2062956D02*
Y2062444D01*
G01X1528526Y2061932D02*
Y2061421D01*
G01X1528087Y2068750D02*
Y2071191D01*
G01Y2076939D02*
Y2073159D01*
G01X1527742Y2062444D02*
Y2062956D01*
G01X1527219D02*
Y2062444D01*
G01X1526522Y2063809D02*
Y2064321D01*
G01X1526433Y2049025D02*
Y2065443D01*
G01Y2031427D02*
Y2046663D01*
G01X1525912Y2062444D02*
Y2063127D01*
G01X1525786Y2072446D02*
Y2071781D01*
G01X1525390Y2059459D02*
Y2059970D01*
G01Y2063127D02*
Y2062444D01*
G01X1524149Y2078907D02*
Y2070561D01*
G01X1522181Y2066624D02*
Y2064852D01*
G01X1521866Y2065443D02*
Y2091840D01*
G01X1533543Y2073027D02*
X1533611Y2073332D01*
G01X1529397Y2062103D02*
X1529484Y2062529D01*
G01X1527655Y2062018D02*
X1527742Y2062444D01*
G01X1525477Y2063553D02*
X1525390Y2063127D01*
G01X1534423Y2073332D02*
X1534336Y2072855D01*
X1534088Y2072412D01*
X1533700Y2072061D01*
X1533193Y2071841D01*
X1532616Y2071785D01*
X1532052Y2071907D01*
X1531576Y2072189D01*
X1531237Y2072594D01*
X1531057Y2073051D01*
X1531042Y2073531D01*
X1531199Y2074001D01*
X1531514Y2074418D01*
G01X1528961Y2062444D02*
X1528874Y2062188D01*
G01X1527742Y2062956D02*
X1527829Y2063212D01*
G01X1527219Y2062444D02*
X1527132Y2062103D01*
G01X1527306Y2063297D02*
X1527219Y2062956D01*
G01X1525912Y2063127D02*
X1525999Y2063468D01*
G01X1527480Y2061676D02*
X1527655Y2062018D01*
G01X1527480Y2063638D02*
X1527306Y2063297D01*
G01X1541862Y2074430D02*
X1541539Y2074011D01*
X1541376Y2073528D01*
X1541398Y2073023D01*
X1541601Y2072546D01*
X1541968Y2072143D01*
X1542474Y2071875D01*
X1543065Y2071781D01*
X1543654Y2071879D01*
X1544157Y2072147D01*
X1544521Y2072551D01*
X1544722Y2073029D01*
X1544741Y2073534D01*
X1544578Y2074015D01*
X1544257Y2074430D01*
G01X1536694D02*
X1536372Y2074011D01*
X1536209Y2073528D01*
X1536231Y2073023D01*
X1536434Y2072546D01*
X1536801Y2072143D01*
X1537307Y2071875D01*
X1537898Y2071781D01*
X1538487Y2071879D01*
X1538989Y2072147D01*
X1539354Y2072551D01*
X1539555Y2073029D01*
X1539574Y2073534D01*
X1539410Y2074015D01*
X1539090Y2074430D01*
G01X1529136Y2061762D02*
X1529397Y2062103D01*
G01X1531514Y2074418D02*
X1531177Y2073957D01*
X1531031Y2073438D01*
X1531092Y2072920D01*
X1531343Y2072437D01*
X1531779Y2072042D01*
X1532352Y2071819D01*
X1532987Y2071800D01*
X1533571Y2071986D01*
X1534026Y2072339D01*
X1534319Y2072811D01*
X1534423Y2073332D01*
G01X1533354Y2072760D02*
X1533544Y2073028D01*
G01X1532086Y2073893D02*
X1531903Y2073628D01*
X1531839Y2073330D01*
X1531904Y2073033D01*
G01X1527132Y2062103D02*
X1526958Y2061847D01*
G01X1527829Y2063212D02*
X1528003Y2063468D01*
G01X1525738Y2063980D02*
X1525477Y2063553D01*
G01X1528526Y2061421D02*
X1528787Y2061506D01*
G01X1528003Y2063468D02*
X1528265Y2063553D01*
G01X1526261Y2063724D02*
X1526522Y2063809D01*
G01X1528700Y2062018D02*
X1528526Y2061932D01*
G01X1526784Y2061165D02*
X1527132Y2061335D01*
G01X1543408Y2072585D02*
X1543691Y2072762D01*
X1543878Y2073028D01*
X1543945Y2073329D01*
X1543881Y2073630D01*
X1543695Y2073897D01*
X1543410Y2074078D01*
X1543059Y2074144D01*
G01X1542711Y2074079D02*
X1542428Y2073901D01*
X1542241Y2073636D01*
X1542174Y2073334D01*
X1542238Y2073033D01*
X1542424Y2072767D01*
X1542709Y2072585D01*
X1543059Y2072520D01*
G01X1526958Y2061847D02*
X1526696Y2061676D01*
G01X1543482Y2074886D02*
X1543843Y2075122D01*
X1544081Y2075472D01*
X1544167Y2075876D01*
X1544084Y2076278D01*
X1543848Y2076630D01*
X1543484Y2076870D01*
X1543059Y2076955D01*
G01X1528787Y2061506D02*
X1529136Y2061762D01*
G01X1533143Y2075965D02*
X1531514Y2074418D01*
G01X1544257Y2074430D02*
X1544709Y2074871D01*
X1544979Y2075406D01*
X1545049Y2075977D01*
X1544908Y2076541D01*
X1544561Y2077065D01*
X1544034Y2077459D01*
X1543391Y2077662D01*
X1542712Y2077660D01*
X1542072Y2077452D01*
X1541549Y2077055D01*
X1541207Y2076532D01*
X1541069Y2075971D01*
X1541141Y2075403D01*
X1541411Y2074869D01*
G01X1539090Y2074430D02*
X1539542Y2074871D01*
X1539812Y2075406D01*
X1539882Y2075977D01*
X1539740Y2076541D01*
X1539394Y2077065D01*
X1538866Y2077459D01*
X1538224Y2077662D01*
X1537544Y2077660D01*
X1536904Y2077452D01*
X1536381Y2077055D01*
X1536040Y2076532D01*
X1535902Y2075971D01*
X1535974Y2075403D01*
X1536244Y2074869D01*
G01X1533648Y2075421D02*
X1532086Y2073893D01*
G01X1528874Y2062188D02*
X1528700Y2062018D01*
G01X1527132Y2061335D02*
X1527480Y2061676D01*
G01X1527829Y2063980D02*
X1527480Y2063638D01*
G01X1525999Y2063468D02*
X1526261Y2063724D01*
G01X1526174Y2064235D02*
X1525738Y2063980D01*
G01X1533354Y2072760D02*
X1533067Y2072582D01*
X1532713Y2072520D01*
G01X1538241Y2072585D02*
X1538524Y2072762D01*
X1538711Y2073028D01*
X1538778Y2073329D01*
X1538713Y2073630D01*
X1538528Y2073897D01*
X1538243Y2074078D01*
X1537892Y2074144D01*
G01X1537543Y2074079D02*
X1537261Y2073901D01*
X1537073Y2073636D01*
X1537006Y2073334D01*
X1537071Y2073033D01*
X1537256Y2072767D01*
X1537542Y2072585D01*
X1537892Y2072520D01*
G01X1542636Y2076871D02*
X1542276Y2076635D01*
X1542038Y2076285D01*
X1541952Y2075881D01*
X1542035Y2075479D01*
X1542271Y2075127D01*
X1542635Y2074887D01*
X1543059Y2074802D01*
G01X1538315Y2074886D02*
X1538675Y2075122D01*
X1538914Y2075472D01*
X1538999Y2075876D01*
X1538917Y2076278D01*
X1538680Y2076630D01*
X1538317Y2076870D01*
X1537892Y2076955D01*
G01X1537469Y2076871D02*
X1537109Y2076635D01*
X1536870Y2076285D01*
X1536785Y2075881D01*
X1536867Y2075479D01*
X1537104Y2075127D01*
X1537467Y2074887D01*
X1537892Y2074802D01*
G01X1527890Y2087510D02*
X1532220D01*
G01X1527264Y2086722D02*
X1532846D01*
G01Y2085148D02*
X1527264D01*
G01X1532846D02*
Y2086722D01*
G01X1532811D02*
Y2085148D01*
G01X1532787Y2086722D02*
Y2085148D01*
G01X1531464D02*
Y2086722D01*
G01X1531094D02*
Y2085148D01*
G01X1529016D02*
Y2086722D01*
G01X1528646D02*
Y2085148D01*
G01X1527324D02*
Y2086722D01*
G01X1527299Y2085148D02*
Y2086722D01*
G01X1527264D02*
Y2085148D01*
G01X1533205Y2103140D02*
G03Y2101959I0J-591D01*
G01Y2105896D02*
G03Y2104714I0J-591D01*
G01X1526905Y2101959D02*
G03Y2103140I0J590D01*
G01Y2104714D02*
G03Y2105896I0J591D01*
G01X1565270Y2156149D02*
X1557229D01*
G01X1561551Y2114006D02*
X1524149D01*
G01X1533205Y2106486D02*
X1526905D01*
G01X1531630Y2106191D02*
X1534779D01*
G01X1528480D02*
X1525331D01*
G01Y2104222D02*
X1528480D01*
G01X1534779D02*
X1531630D01*
G01X1525331Y2103632D02*
X1528480D01*
G01X1534779D02*
X1531630D01*
G01X1526916Y2102888D02*
X1527010D01*
G01Y2102140D02*
X1526916D01*
G01X1531630Y2101663D02*
X1534779D01*
G01X1528480D02*
X1525331D01*
G01X1526905Y2101368D02*
X1533205D01*
G01X1538244Y2091840D02*
X1521866D01*
G01X1557229Y2156149D02*
Y2157790D01*
G01X1534779Y2101663D02*
Y2103632D01*
G01Y2106191D02*
Y2104222D01*
G01X1533205Y2105896D02*
Y2106486D01*
G01Y2103140D02*
Y2104714D01*
G01Y2101368D02*
Y2101959D01*
G01X1532220Y2101368D02*
Y2106486D01*
G01X1532024D02*
Y2101368D01*
G01X1531630Y2104222D02*
Y2106191D01*
G01Y2103632D02*
Y2101663D01*
G01X1528480Y2104222D02*
Y2106191D01*
G01Y2103632D02*
Y2101663D01*
G01X1528087Y2106486D02*
Y2101368D01*
G01X1527890D02*
Y2106486D01*
G01X1527010Y2102888D02*
Y2102140D01*
G01X1526916D02*
Y2102760D01*
G01X1526905Y2101959D02*
Y2101368D01*
G01Y2104714D02*
Y2103140D01*
G01Y2106486D02*
Y2105896D01*
G01X1526823Y2102649D02*
Y2102776D01*
G01X1525331Y2101663D02*
Y2103632D01*
G01Y2106191D02*
Y2104222D01*
G01X1524149Y2114006D02*
Y2256565D01*
G01X1526916Y2102760D02*
X1526823Y2102649D01*
G01Y2102776D02*
X1526916Y2102888D01*
G01X1566946Y2156805D02*
X1565270Y2156149D01*
G01X1494622Y2182667D02*
Y2196447D01*
G01Y2182667D02*
Y2196447D01*
G01Y2182667D02*
Y2196447D01*
G01X1565270Y2161399D02*
X1557229D01*
G01Y2157790D02*
X1565270D01*
G01X1565940Y2161070D02*
X1565270Y2161399D01*
G01X1566611Y2161727D02*
X1567616Y2160742D01*
G01X1566275D02*
X1565940Y2161070D01*
G01X1566611Y2160086D02*
X1566275Y2160742D01*
G01X1557229Y2161399D02*
Y2163039D01*
G01X1566275Y2158446D02*
X1566611Y2159102D01*
G01X1565270Y2157790D02*
X1565940Y2158118D01*
G01D02*
X1566275Y2158446D01*
G01X1557229Y2207986D02*
X1572977D01*
G01X1564600Y2206018D02*
X1557229D01*
G01Y2196832D02*
X1564600D01*
G01X1572977Y2194863D02*
X1557229D01*
G01X1572977Y2182724D02*
X1564265D01*
G01X1565940Y2181084D02*
X1571301D01*
G01X1562590Y2172553D02*
X1561920D01*
G01X1561585Y2170913D02*
X1562925D01*
G01X1557229Y2168288D02*
X1567951D01*
G01X1565605Y2166648D02*
X1557229D01*
G01Y2163039D02*
X1565270D01*
G01X1561920Y2172553D02*
X1560914Y2172881D01*
G01X1559909Y2171569D02*
X1561585Y2170913D01*
G01X1562925Y2185349D02*
X1561920Y2186005D01*
G01X1558569Y2172553D02*
X1559909Y2171569D01*
G01X1560914Y2172881D02*
X1559909Y2173538D01*
G01X1566275Y2165992D02*
X1565605Y2166648D01*
G01X1559909Y2173538D02*
X1559239Y2174522D01*
G01X1564265Y2180427D02*
X1565270Y2179115D01*
G01X1566946Y2179443D02*
X1565940Y2181084D01*
G01X1557564Y2174194D02*
X1558569Y2172553D01*
G01X1567616Y2185349D02*
X1565270Y2189942D01*
G01Y2192238D02*
X1568621Y2186005D01*
G01X1566611Y2165007D02*
X1566275Y2165992D01*
G01X1557229Y2175834D02*
X1557564Y2174194D01*
G01X1565270Y2179115D02*
X1565605Y2177803D01*
G01X1559239Y2174522D02*
X1558904Y2175834D01*
G01X1565605Y2177803D02*
Y2175834D01*
G01X1564600Y2196832D02*
Y2206018D01*
G01X1564265Y2182724D02*
Y2180427D01*
G01X1561249Y2180756D02*
Y2182724D01*
G01X1558904Y2175834D02*
Y2177803D01*
G01X1557229Y2206018D02*
Y2207986D01*
G01Y2194863D02*
Y2196832D01*
G01Y2166648D02*
Y2168288D01*
G01Y2177803D02*
Y2175834D01*
G01X1557564Y2179443D02*
X1557229Y2177803D01*
G01X1565605Y2175834D02*
X1565270Y2174522D01*
G01X1558904Y2177803D02*
X1559239Y2179115D01*
G01X1565940Y2172553D02*
X1566946Y2174194D01*
G01X1558569Y2181084D02*
X1557564Y2179443D01*
G01X1561920Y2186005D02*
X1565270Y2192238D01*
G01X1566275Y2163695D02*
X1566611Y2164351D01*
G01X1565270Y2189942D02*
X1562925Y2185349D01*
G01X1565270Y2174522D02*
X1564600Y2173538D01*
G01X1559239Y2179115D02*
X1559909Y2180099D01*
G01X1563595Y2172881D02*
X1562590Y2172553D01*
G01X1565270Y2163039D02*
X1565940Y2163367D01*
G01X1564600Y2173538D02*
X1563595Y2172881D01*
G01X1564600Y2171569D02*
X1565940Y2172553D01*
G01X1559909Y2182068D02*
X1558569Y2181084D01*
G01X1567616Y2162711D02*
X1566611Y2161727D01*
G01X1565940Y2163367D02*
X1566275Y2163695D01*
G01X1562925Y2170913D02*
X1564600Y2171569D01*
G01X1559909Y2180099D02*
X1561249Y2180756D01*
G01Y2182724D02*
X1559909Y2182068D01*
G01X1600921Y2256565D02*
X1524149D01*
G01Y2260502D02*
Y2300777D01*
G01X1513323Y2309006D02*
X1521984D01*
G01Y2316801D02*
X1518375Y2317288D01*
X1516210Y2317776D01*
X1514766Y2318263D01*
X1513323Y2318750D01*
Y2314852D01*
G01X1521984Y2332392D02*
X1521262Y2331417D01*
X1520541Y2330930D01*
X1519097Y2330443D01*
X1516210D01*
X1514766Y2330930D01*
X1514044Y2331417D01*
X1513323Y2332392D01*
X1514044Y2333366D01*
X1514766Y2333853D01*
X1516210Y2334340D01*
X1519097D01*
X1520541Y2333853D01*
X1521262Y2333366D01*
X1521984Y2332392D01*
G01Y2340187D02*
X1521262Y2339213D01*
X1520541Y2338725D01*
X1519097Y2338238D01*
X1516210D01*
X1514766Y2338725D01*
X1514044Y2339213D01*
X1513323Y2340187D01*
X1514044Y2341161D01*
X1514766Y2341649D01*
X1516210Y2342136D01*
X1519097D01*
X1520541Y2341649D01*
X1521262Y2341161D01*
X1521984Y2340187D01*
G01Y2324596D02*
Y2324109D01*
X1521262D01*
X1521984Y2324596D01*
G01X1494330Y2437400D02*
Y2418463D01*
G01X1584583Y188814D02*
X1586026Y189788D01*
X1586748D01*
G01X1583861Y186865D02*
Y187839D01*
G01X1580974Y185891D02*
X1580252Y186865D01*
Y187839D01*
X1580974Y188814D01*
X1581695Y189301D01*
X1582417D01*
X1583139Y188814D01*
X1583861Y187839D01*
X1584583Y188814D01*
G01X1586748Y189788D02*
X1588191Y188814D01*
X1588913Y187839D01*
Y186865D01*
X1588191Y185891D01*
X1587470Y185403D01*
G01X1623559Y197096D02*
Y194173D01*
X1627168Y193686D01*
X1626446Y194660D01*
Y195635D01*
X1627168Y196609D01*
X1627890Y197096D01*
X1629333Y197584D01*
X1630777Y197096D01*
X1631499Y196609D01*
X1632220Y195635D01*
Y194660D01*
X1631499Y193686D01*
X1630777Y193199D01*
G01X1632220Y188814D02*
X1623559D01*
X1630055Y185403D01*
Y189788D01*
G01X1588913Y196609D02*
X1580252D01*
X1586748Y193199D01*
Y197584D01*
G01X1575331Y277549D02*
G03X1606827I15748J0D01*
G01X1588913Y210738D02*
X1588191Y209764D01*
X1587470Y209276D01*
X1586026Y208789D01*
X1583139D01*
X1581695Y209276D01*
X1580974Y209764D01*
X1580252Y210738D01*
X1580974Y211713D01*
X1581695Y212200D01*
X1583139Y212687D01*
X1586026D01*
X1587470Y212200D01*
X1588191Y211713D01*
X1588913Y210738D01*
G01Y218533D02*
X1588191Y217559D01*
X1587470Y217072D01*
X1586026Y216585D01*
X1583139D01*
X1581695Y217072D01*
X1580974Y217559D01*
X1580252Y218533D01*
X1580974Y219508D01*
X1581695Y219995D01*
X1583139Y220482D01*
X1586026D01*
X1587470Y219995D01*
X1588191Y219508D01*
X1588913Y218533D01*
G01X1632220Y210738D02*
X1631499Y209764D01*
X1630777Y209276D01*
X1629333Y208789D01*
X1626446D01*
X1625003Y209276D01*
X1624281Y209764D01*
X1623559Y210738D01*
X1624281Y211713D01*
X1625003Y212200D01*
X1626446Y212687D01*
X1629333D01*
X1630777Y212200D01*
X1631499Y211713D01*
X1632220Y210738D01*
G01Y218533D02*
X1631499Y217559D01*
X1630777Y217072D01*
X1629333Y216585D01*
X1626446D01*
X1625003Y217072D01*
X1624281Y217559D01*
X1623559Y218533D01*
X1624281Y219508D01*
X1625003Y219995D01*
X1626446Y220482D01*
X1629333D01*
X1630777Y219995D01*
X1631499Y219508D01*
X1632220Y218533D01*
G01Y202943D02*
Y202456D01*
X1631499D01*
X1632220Y202943D01*
G01X1588913D02*
Y202456D01*
X1588191D01*
X1588913Y202943D01*
G01X1634386Y311676D02*
Y226762D01*
G01X1591079Y279518D02*
Y226762D01*
G01X1596984Y291329D02*
G03X1585173I-5905J0D01*
G01X1596984D02*
G03X1585173I-5905J0D01*
G01X1598953D02*
G03X1583205I-7874J0D01*
G01X1604858D02*
G03X1577299I-13780J0D01*
G01X1606827D02*
G03X1575331I-15748J0D01*
G01X1606827D02*
G03X1575331I-15748J0D01*
G01X1582024D02*
G03I-985J0D01*
G01X1587043Y300023D02*
G03I-984J0D01*
G01X1583369Y296348D02*
G03I-985J0D01*
G01X1584531Y285500D02*
G03X1585173Y288179I-5264J2678D01*
G01X1584531Y285500D02*
X1578480Y273612D01*
G01X1585173Y288966D02*
Y291329D01*
G01D02*
Y288179D01*
G01X1583205Y291329D02*
Y288966D01*
G01X1577299Y291329D02*
Y288966D01*
G01X1575331Y273612D02*
Y291329D01*
G01Y277549D02*
Y291329D01*
G01X1577299Y288966D02*
X1585173D01*
G01X1606827Y273612D02*
X1575331D01*
G01X1596984Y288179D02*
G03X1597627Y285500I5905J1D01*
G01X1600757Y296348D02*
G03I-984J0D01*
G01X1597083Y300023D02*
G03I-985J0D01*
G01X1602102Y291329D02*
G03I-984J0D01*
G01X1634386Y441597D02*
Y315613D01*
G01X1606827Y277549D02*
Y291329D01*
G01D02*
Y273612D01*
G01X1604858Y288966D02*
Y291329D01*
G01X1598953Y288966D02*
Y291329D01*
G01X1596984Y288179D02*
Y291329D01*
G01D02*
Y288966D01*
G01X1603677Y273612D02*
X1597627Y285500D01*
G01X1596984Y288966D02*
X1604858D01*
G01X2490685Y273612D02*
X1603677D01*
G01X1595016Y291329D02*
X1658461D01*
G01X1587053Y390986D02*
X1586048Y390657D01*
G01X1586383Y389017D02*
X1588058Y389673D01*
G01X1583367Y398203D02*
X1584707Y398860D01*
G01Y400828D02*
X1583367Y400172D01*
G01X1588058Y391642D02*
X1587053Y390986D01*
G01X1583367Y400172D02*
X1582027Y399188D01*
G01X1582697Y397219D02*
X1583367Y398203D01*
G01X1582027Y399188D02*
X1581022Y397547D01*
G01X1585378Y404109D02*
X1588728Y410342D01*
G01Y408046D02*
X1586383Y403453D01*
G01X1582362Y395907D02*
X1582697Y397219D01*
G01X1581022Y397547D02*
X1580687Y395907D01*
G01X1584707Y398860D02*
Y400828D01*
G01X1582362Y393938D02*
Y395907D01*
G01X1580687Y384752D02*
Y386392D01*
G01Y379503D02*
Y381143D01*
G01Y374253D02*
Y375894D01*
G01Y395907D02*
Y393938D01*
G01D02*
X1581022Y392298D01*
G01X1582697Y392626D02*
X1582362Y393938D01*
G01X1581022Y392298D02*
X1582027Y390657D01*
G01X1583367Y391642D02*
X1582697Y392626D01*
G01X1586048Y390657D02*
X1585378D01*
G01X1585043Y389017D02*
X1586383D01*
G01X1580687Y386392D02*
X1591409D01*
G01X1589063Y384752D02*
X1580687D01*
G01Y381143D02*
X1588728D01*
G01Y379503D02*
X1580687D01*
G01Y375894D02*
X1588728D01*
G01Y374253D02*
X1580687D01*
G01X1582027Y390657D02*
X1583367Y389673D01*
G01X1586383Y403453D02*
X1585378Y404109D01*
G01X1584372Y390986D02*
X1583367Y391642D01*
G01Y389673D02*
X1585043Y389017D01*
G01X1585378Y390657D02*
X1584372Y390986D01*
G01X1590404Y374909D02*
X1588728Y374253D01*
G01Y375894D02*
X1589398Y376222D01*
G01X1588728Y381143D02*
X1589398Y381471D01*
G01X1592079Y404109D02*
X1591074Y403453D01*
G01X1588058Y389673D02*
X1589398Y390657D01*
G01X1591074Y375566D02*
X1590404Y374909D01*
G01X1589398Y376222D02*
X1589733Y376550D01*
G01X1591074Y380815D02*
X1590069Y379831D01*
G01X1589398Y381471D02*
X1589733Y381799D01*
G01X1588728Y392626D02*
X1588058Y391642D01*
G01X1589398Y390657D02*
X1590404Y392298D01*
G01X1589733Y376550D02*
X1590069Y377206D01*
G01X1589733Y381799D02*
X1590069Y382455D01*
G01X1591409Y376550D02*
X1591074Y375566D01*
G01X1591409Y381799D02*
X1591074Y380815D01*
G01X1589063Y393938D02*
X1588728Y392626D01*
G01X1590404Y392298D02*
X1590739Y393938D01*
G01X1596435Y389673D02*
Y400828D01*
G01X1594759Y399188D02*
Y389673D01*
G01X1591409Y377862D02*
Y376550D01*
G01Y383111D02*
Y381799D01*
G01Y386392D02*
Y384752D01*
G01X1590739Y393938D02*
Y395907D01*
G01X1590069Y382455D02*
Y383111D01*
G01Y377206D02*
Y378190D01*
G01X1589063Y395907D02*
Y393938D01*
G01X1587723Y400828D02*
Y398531D01*
G01X1590739Y395907D02*
X1590404Y397547D01*
G01X1588728Y397219D02*
X1589063Y395907D01*
G01X1591074Y384096D02*
X1591409Y383111D01*
G01X1590069D02*
X1589733Y384096D01*
G01X1591074Y378846D02*
X1591409Y377862D01*
G01X1591074Y403453D02*
X1588728Y408046D01*
G01X1590069Y378190D02*
X1589733Y378846D01*
G01X1588728Y410342D02*
X1592079Y404109D01*
G01X1590404Y397547D02*
X1589398Y399188D01*
G01X1587723Y398531D02*
X1588728Y397219D01*
G01X1590404Y384752D02*
X1591074Y384096D01*
G01X1589733D02*
X1589063Y384752D01*
G01X1590069Y379831D02*
X1591074Y378846D01*
G01X1589733D02*
X1589398Y379174D01*
G01X1596435Y400828D02*
X1587723D01*
G01X1589398Y399188D02*
X1594759D01*
G01Y389673D02*
X1596435D01*
G01X1591409Y384752D02*
X1590404D01*
G01X1589398Y379174D02*
X1588728Y379503D01*
G01X1626590Y483317D02*
G03X1626984Y483711I0J394D01*
G01Y481348D02*
G03X1626590Y481742I-394J0D01*
G01X1638323Y606348D02*
Y473711D01*
G01X1632102Y490325D02*
Y473907D01*
G01X1630134D02*
Y606151D01*
G01X1628087Y608966D02*
Y471092D01*
G01X1626984Y471545D02*
Y608514D01*
G01X1626145Y481840D02*
Y482628D01*
G01X1626118Y481840D02*
Y482628D01*
G01X1625742Y481840D02*
Y482628D01*
G01X1625527Y483317D02*
Y481742D01*
G01X1624543Y484104D02*
Y480955D01*
G01X1623559Y484104D02*
Y480955D01*
G01X1622968Y471545D02*
Y608514D01*
G01X1622575Y483317D02*
Y481742D01*
G01X1622514Y474124D02*
Y605738D01*
G01X1622380Y482628D02*
Y481840D01*
G01X1620396Y482628D02*
Y481840D01*
G01X1619425Y483317D02*
Y481742D01*
G01X1618745Y481840D02*
Y482628D01*
G01X1617016Y481840D02*
Y479478D01*
G01Y484990D02*
Y482628D01*
G01X1616078Y481840D02*
Y482628D01*
G01X1615931Y481840D02*
Y482628D01*
G01X1614338Y481840D02*
Y482628D01*
G01X1613984Y608514D02*
Y471545D01*
G01X1613397Y482628D02*
Y481840D01*
G01X1610560Y482628D02*
Y481840D01*
G01X1610372D02*
Y482628D01*
G01X1608598Y481840D02*
Y482628D01*
G01X1599147Y538054D02*
Y441597D01*
G01X1624543Y484104D02*
X1623559D01*
G01X1624543Y483907D02*
X1623559D01*
G01X1624543Y483514D02*
X1623559D01*
G01X1619425Y483317D02*
X1626590D01*
G01X1615931Y482628D02*
X1608598D01*
G01X1628087D02*
X1616078D01*
G01Y481840D02*
X1628087D01*
G01X1608598D02*
X1615931D01*
G01X1619425Y481742D02*
X1626590D01*
G01X1624543Y481545D02*
X1623559D01*
G01X1580687Y424122D02*
Y426091D01*
G01Y412967D02*
Y414936D01*
G01Y426091D02*
X1596435D01*
G01X1588058Y424122D02*
X1580687D01*
G01Y414936D02*
X1588058D01*
G01X1596435Y412967D02*
X1580687D01*
G01X1624887Y463929D02*
G03X1623817Y462106I2809J-2874D01*
G01X1631864Y466831D02*
G03X1629649Y461663I6937J-6032D01*
G01X1632749Y466905D02*
G03X1630535Y461663I7143J-6105D01*
G01X1626590Y478317D02*
G03X1626984Y478711I0J394D01*
G01Y476348D02*
G03X1626590Y476742I-394J0D01*
G01X1625392Y463385D02*
G03X1624851Y462401I1277J-1343D01*
G01X1621394Y465226D02*
G03I-2166J0D01*
G01X1622575D02*
G03I-3347J0D01*
G01X1622732D02*
G03I-3504J0D01*
G01X1623756D02*
G03I-4528J0D01*
G01X1611416Y466831D02*
G03X1609201Y461663I6937J-6032D01*
G01X1612301Y466905D02*
G03X1610087Y461663I7143J-6105D01*
G01X1631630Y434636D02*
G03Y433455I0J-590D01*
G01X1625331D02*
G03Y434636I0J591D01*
G01Y436211D02*
G03Y437392I0J591D01*
G01X1631630D02*
G03Y436211I0J-590D01*
G01X1630646Y451840D02*
G03Y454990I0J1575D01*
G01X1626315D02*
G03Y451840I0J-1575D01*
G01X1632274Y475627D02*
X1632013Y475541D01*
G01X1630532Y475882D02*
X1630271Y475797D01*
G01X1630009Y477930D02*
X1629748Y477844D01*
G01X1631752Y478186D02*
X1631403Y478015D01*
G01X1629835Y477333D02*
X1630009Y477418D01*
G01X1632362Y475115D02*
X1632797Y475371D01*
G01X1625181Y466590D02*
X1625469Y466768D01*
X1625823Y466831D01*
G01X1620992Y465272D02*
X1621275Y465449D01*
X1621462Y465715D01*
X1621529Y466016D01*
X1621464Y466317D01*
X1621279Y466584D01*
X1620994Y466765D01*
X1620643Y466831D01*
G01X1620294Y466766D02*
X1620012Y466588D01*
X1619824Y466323D01*
X1619757Y466021D01*
X1619822Y465720D01*
X1620007Y465454D01*
X1620293Y465272D01*
X1620643Y465207D01*
G01X1615825Y465272D02*
X1616107Y465449D01*
X1616294Y465715D01*
X1616361Y466016D01*
X1616297Y466317D01*
X1616112Y466584D01*
X1615826Y466765D01*
X1615476Y466831D01*
G01X1615127Y466766D02*
X1614844Y466588D01*
X1614657Y466323D01*
X1614590Y466021D01*
X1614654Y465720D01*
X1614840Y465454D01*
X1615125Y465272D01*
X1615476Y465207D01*
G01X1631577Y477503D02*
X1631839Y477674D01*
G01X1621066Y462479D02*
X1621426Y462715D01*
X1621665Y463065D01*
X1621750Y463469D01*
X1621668Y463871D01*
X1621431Y464224D01*
X1621068Y464464D01*
X1620643Y464548D01*
G01X1620220Y464464D02*
X1619860Y464228D01*
X1619621Y463878D01*
X1619536Y463475D01*
X1619618Y463072D01*
X1619855Y462720D01*
X1620218Y462480D01*
X1620643Y462395D01*
G01X1615899Y462479D02*
X1616259Y462715D01*
X1616498Y463065D01*
X1616583Y463469D01*
X1616500Y463871D01*
X1616264Y464224D01*
X1615901Y464464D01*
X1615476Y464548D01*
G01X1615053Y464464D02*
X1614692Y464228D01*
X1614454Y463878D01*
X1614369Y463475D01*
X1614451Y463072D01*
X1614688Y462720D01*
X1615051Y462480D01*
X1615476Y462395D01*
G01X1629748Y477844D02*
X1629400Y477588D01*
G01X1627021Y464932D02*
X1625392Y463385D01*
G01X1619445Y464920D02*
X1618994Y464480D01*
X1618724Y463944D01*
X1618653Y463374D01*
X1618795Y462809D01*
X1619142Y462285D01*
X1619669Y461891D01*
X1620312Y461688D01*
X1620991Y461691D01*
X1621631Y461898D01*
X1622154Y462295D01*
X1622495Y462818D01*
X1622633Y463379D01*
X1622562Y463947D01*
X1622291Y464481D01*
G01X1614278Y464920D02*
X1613826Y464480D01*
X1613556Y463944D01*
X1613486Y463374D01*
X1613628Y462809D01*
X1613974Y462285D01*
X1614502Y461891D01*
X1615144Y461688D01*
X1615824Y461691D01*
X1616464Y461898D01*
X1616986Y462295D01*
X1617328Y462818D01*
X1617466Y463379D01*
X1617394Y463947D01*
X1617124Y464481D01*
G01X1626450Y465457D02*
X1624887Y463929D01*
G01X1632536Y475882D02*
X1632274Y475627D01*
G01X1630706Y475371D02*
X1631055Y475712D01*
G01X1631403Y478015D02*
X1631055Y477674D01*
G01X1629661Y477162D02*
X1629835Y477333D01*
G01X1625341Y434256D02*
X1625248Y434145D01*
G01Y434272D02*
X1625341Y434384D01*
G01X1621841Y464920D02*
X1622164Y465339D01*
X1622326Y465823D01*
X1622304Y466327D01*
X1622101Y466804D01*
X1621735Y467208D01*
X1621228Y467475D01*
X1620637Y467569D01*
X1620048Y467472D01*
X1619546Y467203D01*
X1619182Y466799D01*
X1618980Y466321D01*
X1618961Y465816D01*
X1619125Y465335D01*
X1619445Y464920D01*
G01X1616674D02*
X1616996Y465339D01*
X1617159Y465823D01*
X1617137Y466327D01*
X1616934Y466804D01*
X1616567Y467208D01*
X1616061Y467475D01*
X1615470Y467569D01*
X1614881Y467472D01*
X1614378Y467203D01*
X1614014Y466799D01*
X1613813Y466321D01*
X1613794Y465816D01*
X1613958Y465335D01*
X1614278Y464920D01*
G01X1629400Y477588D02*
X1629138Y477247D01*
G01X1627021Y464932D02*
X1627358Y465393D01*
X1627504Y465912D01*
X1627444Y466430D01*
X1627193Y466913D01*
X1626756Y467308D01*
X1626183Y467531D01*
X1625548Y467550D01*
X1624964Y467364D01*
X1624509Y467011D01*
X1624216Y466540D01*
X1624113Y466019D01*
G01X1625182Y466590D02*
X1624992Y466323D01*
G01X1626450Y465457D02*
X1626633Y465722D01*
X1626696Y466020D01*
X1626631Y466317D01*
G01X1630706Y476138D02*
X1630532Y475882D01*
G01X1631403Y477247D02*
X1631577Y477503D01*
G01X1632797Y475371D02*
X1633058Y475797D01*
G01X1631055Y475712D02*
X1631229Y476053D01*
G01X1631055Y477674D02*
X1630881Y477333D01*
G01X1630793Y476394D02*
X1630706Y476138D01*
G01X1629574Y476906D02*
X1629661Y477162D01*
G01X1632623Y476224D02*
X1632536Y475882D01*
G01X1631229Y476053D02*
X1631316Y476394D01*
G01Y476906D02*
X1631403Y477247D01*
G01X1624992Y466323D02*
X1624925Y466019D01*
G01X1633058Y475797D02*
X1633146Y476224D01*
G01X1630881Y477333D02*
X1630793Y476906D01*
G01X1629138Y477247D02*
X1629051Y476821D01*
G01X1624113Y466019D02*
X1624199Y466495D01*
X1624447Y466938D01*
X1624835Y467290D01*
X1625342Y467509D01*
X1625919Y467566D01*
X1626483Y467444D01*
X1626959Y467161D01*
X1627298Y466757D01*
X1627478Y466300D01*
X1627493Y465819D01*
X1627336Y465349D01*
X1627021Y464932D01*
G01X1636669Y447510D02*
Y473907D01*
G01X1636354Y474498D02*
Y472726D01*
G01X1634386Y460443D02*
Y468789D01*
G01X1633205Y433159D02*
Y435128D01*
G01Y437687D02*
Y435718D01*
G01X1633146Y476224D02*
Y476906D01*
G01Y479892D02*
Y479380D01*
G01X1632749Y466904D02*
Y467569D01*
G01X1632623Y476906D02*
Y476224D01*
G01X1632013Y475541D02*
Y475029D01*
G01X1631630Y434636D02*
Y436211D01*
G01Y437392D02*
Y437982D01*
G01Y432864D02*
Y433455D01*
G01X1631316Y476394D02*
Y476906D01*
G01X1631271Y452628D02*
Y454203D01*
G01X1631236D02*
Y452628D01*
G01X1631212Y454203D02*
Y452628D01*
G01X1630793Y476906D02*
Y476394D01*
G01X1630646Y432864D02*
Y437982D01*
G01X1630449D02*
Y432864D01*
G01Y466191D02*
Y462411D01*
G01Y470600D02*
Y468159D01*
G01X1630055Y435718D02*
Y437687D01*
G01Y435128D02*
Y433159D01*
G01X1630009Y477418D02*
Y477930D01*
G01X1629889Y452628D02*
Y454203D01*
G01X1629574Y476394D02*
Y476906D01*
G01X1629519Y454203D02*
Y452628D01*
G01X1629051Y479380D02*
Y479892D01*
G01Y476821D02*
Y476394D01*
G01X1628911Y467569D02*
Y466831D01*
G01X1627730Y461663D02*
Y462401D01*
G01X1627442Y452628D02*
Y454203D01*
G01X1627072D02*
Y452628D01*
G01X1626905Y435718D02*
Y437687D01*
G01Y435128D02*
Y433159D01*
G01X1626531Y476565D02*
Y478533D01*
G01X1626512Y437982D02*
Y432864D01*
G01X1626315D02*
Y437982D01*
G01X1626145Y478691D02*
Y479478D01*
G01X1626118Y478691D02*
Y479478D01*
G01X1625748Y452628D02*
Y454203D01*
G01X1625742Y478691D02*
Y479478D01*
G01X1625724Y452628D02*
Y454203D01*
G01X1625689D02*
Y452628D01*
G01X1625527Y478317D02*
Y476742D01*
G01X1625435Y434384D02*
Y433636D01*
G01X1625341D02*
Y434256D01*
G01X1625331Y433455D02*
Y432864D01*
G01Y436211D02*
Y434636D01*
G01Y437982D02*
Y437392D01*
G01X1625248Y434145D02*
Y434272D01*
G01X1624925Y465871D02*
Y466019D01*
G01X1624543Y471092D02*
Y468789D01*
G01Y479104D02*
Y475955D01*
G01X1624113Y466019D02*
Y465871D01*
G01X1623817Y462106D02*
Y461663D01*
G01X1623756Y433159D02*
Y435128D01*
G01Y437687D02*
Y435718D01*
G01X1623559Y479104D02*
Y475955D01*
G01X1622575Y478317D02*
Y476742D01*
G01X1622380Y479478D02*
Y478691D01*
G01X1621987Y471151D02*
Y471092D01*
G01X1621348Y468789D02*
Y471545D01*
G01X1620396Y479478D02*
Y478691D01*
G01X1620291Y460443D02*
Y447510D01*
G01X1619425Y478317D02*
Y476742D01*
G01X1618745Y478691D02*
Y479478D01*
G01X1618461Y478533D02*
Y476565D01*
G01X1617016Y478691D02*
Y476112D01*
G01X1616078Y478691D02*
Y479478D01*
G01X1615931Y478691D02*
Y479478D01*
G01X1614338Y478691D02*
Y479478D01*
G01X1613474Y468789D02*
Y471545D01*
G01X1613397Y479478D02*
Y478691D01*
G01X1612302Y466904D02*
Y467569D01*
G01X1610560Y479478D02*
Y478691D01*
G01X1610372D02*
Y479478D01*
G01X1608598Y478691D02*
Y479478D01*
G01X1608463Y467569D02*
Y466831D01*
G01X1607619Y474124D02*
Y471545D01*
G01X1607144Y474124D02*
Y468789D01*
G01X1606827Y474124D02*
Y460443D01*
G01X1596435Y414936D02*
Y412967D01*
G01Y426091D02*
Y424122D01*
G01X1590069D02*
Y414936D01*
G01X1588058D02*
Y424122D01*
G01X1633146Y476906D02*
X1633058Y477333D01*
G01X1632536Y477247D02*
X1632623Y476906D01*
G01X1629051Y476394D02*
X1629138Y476053D01*
G01X1629661Y476138D02*
X1629574Y476394D01*
G01X1633058Y477333D02*
X1632884Y477674D01*
G01X1629138Y476053D02*
X1629312Y475712D01*
G01X1621731Y471545D02*
X1621987Y471151D01*
G01X1632362Y477503D02*
X1632536Y477247D01*
G01X1629835Y475882D02*
X1629661Y476138D01*
G01X1626449Y466581D02*
X1626632Y466316D01*
X1626696Y466017D01*
X1626632Y465721D01*
G01X1630358Y475285D02*
X1630706Y475371D01*
G01X1632013Y475029D02*
X1632362Y475115D01*
G01X1619445Y464920D02*
X1619123Y465339D01*
X1618960Y465823D01*
X1618982Y466327D01*
X1619185Y466804D01*
X1619552Y467208D01*
X1620058Y467475D01*
X1620649Y467569D01*
X1621238Y467472D01*
X1621740Y467203D01*
X1622105Y466799D01*
X1622306Y466321D01*
X1622325Y465816D01*
X1622161Y465335D01*
X1621841Y464920D01*
G01X1614278D02*
X1613955Y465339D01*
X1613793Y465823D01*
X1613815Y466327D01*
X1614017Y466804D01*
X1614384Y467208D01*
X1614890Y467475D01*
X1615482Y467569D01*
X1616071Y467472D01*
X1616573Y467203D01*
X1616937Y466799D01*
X1617139Y466321D01*
X1617158Y465816D01*
X1616994Y465335D01*
X1616674Y464920D01*
G01X1632884Y477674D02*
X1632536Y478015D01*
G01X1629312Y475712D02*
X1629661Y475371D01*
G01X1621841Y464920D02*
X1622293Y464480D01*
X1622563Y463944D01*
X1622633Y463374D01*
X1622491Y462809D01*
X1622145Y462285D01*
X1621617Y461891D01*
X1620975Y461688D01*
X1620295Y461691D01*
X1619655Y461898D01*
X1619132Y462295D01*
X1618791Y462818D01*
X1618653Y463379D01*
X1618725Y463947D01*
X1618995Y464481D01*
G01X1616674Y464920D02*
X1617125Y464480D01*
X1617395Y463944D01*
X1617466Y463374D01*
X1617324Y462809D01*
X1616977Y462285D01*
X1616450Y461891D01*
X1615807Y461688D01*
X1615128Y461691D01*
X1614488Y461898D01*
X1613965Y462295D01*
X1613624Y462818D01*
X1613486Y463379D01*
X1613557Y463947D01*
X1613828Y464481D01*
G01X1629748Y479380D02*
X1630358Y478868D01*
G01X1629661D02*
X1629051Y479380D01*
G01X1624543Y481151D02*
X1623559D01*
G01X1624543Y480955D02*
X1623559D01*
G01X1629051Y479892D02*
X1633146D01*
G01X1615931Y479478D02*
X1608598D01*
G01X1628087D02*
X1616078D01*
G01X1633146Y479380D02*
X1629748D01*
G01X1624543Y479104D02*
X1623559D01*
G01X1624543Y478907D02*
X1623559D01*
G01X1630358Y478868D02*
X1629661D01*
G01X1616078Y478691D02*
X1628087D01*
G01X1608598D02*
X1615931D01*
G01X1626531Y478533D02*
X1618461D01*
G01X1624543Y478514D02*
X1623559D01*
G01X1619425Y478317D02*
X1626590D01*
G01X1632187Y478186D02*
X1631752D01*
G01X1631839Y477674D02*
X1632100D01*
G01X1619425Y476742D02*
X1626590D01*
G01X1618461Y476565D02*
X1626531D01*
G01X1624543Y476545D02*
X1623559D01*
G01X1624543Y476151D02*
X1623559D01*
G01X1622968Y476112D02*
X1613984D01*
G01X1624543Y475955D02*
X1623559D01*
G01X1630271Y475797D02*
X1630096D01*
G01X1630009Y475285D02*
X1630358D01*
G01X1626984Y474498D02*
X1636354D01*
G01X1626984Y474124D02*
X1606827D01*
G01X1636669Y473907D02*
X1630134D01*
G01X1656827Y473711D02*
X1638323D01*
G01X1628087Y473317D02*
X1658795D01*
G01X1626984Y472726D02*
X1636354D01*
G01X1607619Y471545D02*
X1628087D01*
G01X1621987Y471151D02*
X1628087D01*
G01Y471092D02*
X1621987D01*
G01X1630449Y470600D02*
X1606827D01*
G01X1656827Y468789D02*
X1606827D01*
G01Y468159D02*
X1630449D01*
G01X1612302Y467569D02*
X1608463D01*
G01X1632749D02*
X1628911D01*
G01Y466831D02*
X1631864D01*
G01X1608463D02*
X1611416D01*
G01X1630449Y466191D02*
X1606827D01*
G01X1624113Y465871D02*
X1624925D01*
G01X1630449Y462411D02*
X1606827D01*
G01X1627730Y462401D02*
X1624851D01*
G01X1629649Y461663D02*
X1630535D01*
G01X1623817D02*
X1627730D01*
G01X1609201D02*
X1610087D01*
G01X1634386Y461624D02*
X1660764D01*
G01Y460443D02*
X1606827D01*
G01X1636669Y457687D02*
X1620291D01*
G01X1626315Y454990D02*
X1630646D01*
G01X1625689Y454203D02*
X1631271D01*
G01Y452628D02*
X1625689D01*
G01X1630646Y451840D02*
X1626315D01*
G01X1636669Y447510D02*
X1620291D01*
G01X1599147Y441597D02*
X1634386D01*
G01X1631630Y437982D02*
X1625331D01*
G01X1630055Y437687D02*
X1633205D01*
G01X1626905D02*
X1623756D01*
G01Y435718D02*
X1626905D01*
G01X1633205D02*
X1630055D01*
G01X1623756Y435128D02*
X1626905D01*
G01X1633205D02*
X1630055D01*
G01X1625341Y434384D02*
X1625435D01*
G01Y433636D02*
X1625341D01*
G01X1630055Y433159D02*
X1633205D01*
G01X1626905D02*
X1623756D01*
G01X1625331Y432864D02*
X1631630D01*
G01X1621066Y464464D02*
X1621426Y464228D01*
X1621665Y463878D01*
X1621750Y463475D01*
X1621668Y463072D01*
X1621431Y462720D01*
X1621068Y462480D01*
X1620643Y462395D01*
G01X1620220Y462479D02*
X1619860Y462715D01*
X1619621Y463065D01*
X1619536Y463469D01*
X1619618Y463871D01*
X1619855Y464224D01*
X1620218Y464464D01*
X1620643Y464548D01*
G01X1615899Y464464D02*
X1616259Y464228D01*
X1616498Y463878D01*
X1616583Y463475D01*
X1616500Y463072D01*
X1616264Y462720D01*
X1615901Y462480D01*
X1615476Y462395D01*
G01X1615053Y462479D02*
X1614692Y462715D01*
X1614454Y463065D01*
X1614369Y463469D01*
X1614451Y463871D01*
X1614688Y464224D01*
X1615051Y464464D01*
X1615476Y464548D01*
G01X1632100Y477674D02*
X1632362Y477503D01*
G01X1626170Y466762D02*
X1626450Y466581D01*
G01X1620992Y466766D02*
X1621275Y466588D01*
X1621462Y466323D01*
X1621529Y466021D01*
X1621464Y465720D01*
X1621279Y465454D01*
X1620994Y465272D01*
X1620643Y465207D01*
G01X1620294Y465272D02*
X1620012Y465449D01*
X1619824Y465715D01*
X1619757Y466016D01*
X1619822Y466317D01*
X1620007Y466584D01*
X1620293Y466765D01*
X1620643Y466831D01*
G01X1615825Y466766D02*
X1616107Y466588D01*
X1616294Y466323D01*
X1616361Y466021D01*
X1616297Y465720D01*
X1616112Y465454D01*
X1615826Y465272D01*
X1615476Y465207D01*
G01X1615127Y465272D02*
X1614844Y465449D01*
X1614657Y465715D01*
X1614590Y466016D01*
X1614654Y466317D01*
X1614840Y466584D01*
X1615125Y466765D01*
X1615476Y466831D01*
G01X1632536Y478015D02*
X1632187Y478186D01*
G01X1630096Y475797D02*
X1629835Y475882D01*
G01X1629661Y475371D02*
X1630009Y475285D01*
G01X1625823Y466831D02*
X1626170Y466761D01*
G01X1596435Y424122D02*
X1590069D01*
G01Y414936D02*
X1596435D01*
G01X1638323Y441597D02*
X1666889D01*
G01X1626145Y484990D02*
Y485777D01*
G01X1626118Y484990D02*
Y485777D01*
G01X1625742Y484990D02*
Y485777D01*
G01X1622380D02*
Y484990D01*
G01X1620396Y485777D02*
Y484990D01*
G01X1618745D02*
Y485777D01*
G01X1616078Y484990D02*
Y485777D01*
G01X1615931Y484990D02*
Y485777D01*
G01X1614338Y484990D02*
Y485777D01*
G01X1613397D02*
Y484990D01*
G01X1610560Y485777D02*
Y484990D01*
G01X1610372D02*
Y485777D01*
G01X1608598Y484990D02*
Y485777D01*
G01X1616078Y484990D02*
X1628087D01*
G01X1608598D02*
X1615931D01*
G01X1626590Y553317D02*
G03X1626984Y553711I0J394D01*
G01Y551348D02*
G03X1626590Y551742I-394J0D01*
G01X1626984Y556348D02*
G03X1626590Y556742I-394J0D01*
G01Y538317D02*
G03X1626984Y538711I0J394D01*
G01Y536348D02*
G03X1626590Y536742I-394J0D01*
G01Y543317D02*
G03X1626984Y543711I0J394D01*
G01Y541348D02*
G03X1626590Y541742I-394J0D01*
G01Y508317D02*
G03X1626984Y508711I0J394D01*
G01Y506348D02*
G03X1626590Y506742I-394J0D01*
G01Y503317D02*
G03X1626984Y503711I0J394D01*
G01X1626590Y533317D02*
G03X1626984Y533711I0J394D01*
G01Y531348D02*
G03X1626590Y531742I-394J0D01*
G01X1626984Y501348D02*
G03X1626590Y501742I-394J0D01*
G01Y498317D02*
G03X1626984Y498711I0J394D01*
G01Y496348D02*
G03X1626590Y496742I-394J0D01*
G01Y488317D02*
G03X1626984Y488711I0J394D01*
G01Y486348D02*
G03X1626590Y486742I-394J0D01*
G01Y493317D02*
G03X1626984Y493711I0J394D01*
G01Y491348D02*
G03X1626590Y491742I-394J0D01*
G01X1632102Y550837D02*
Y567372D01*
G01Y532136D02*
Y548474D01*
G01Y507923D02*
Y492687D01*
G01Y529774D02*
Y510285D01*
G01X1626905Y529675D02*
Y510384D01*
G01X1626590D02*
Y529675D01*
G01X1626512Y549104D02*
Y545955D01*
G01X1626145Y551132D02*
Y551919D01*
G01Y554281D02*
Y555069D01*
G01Y547982D02*
Y548770D01*
G01Y541683D02*
Y542470D01*
G01Y544833D02*
Y545620D01*
G01Y538533D02*
Y539321D01*
G01Y532234D02*
Y533022D01*
G01Y535384D02*
Y536171D01*
G01Y529085D02*
Y529872D01*
G01Y522785D02*
Y523573D01*
G01Y525935D02*
Y526722D01*
G01Y519636D02*
Y520423D01*
G01Y513337D02*
Y514124D01*
G01Y516486D02*
Y517274D01*
G01Y510187D02*
Y510974D01*
G01Y503888D02*
Y504675D01*
G01Y507037D02*
Y507825D01*
G01Y500738D02*
Y501525D01*
G01Y494439D02*
Y495226D01*
G01Y497588D02*
Y498376D01*
G01Y491289D02*
Y492077D01*
G01Y488140D02*
Y488927D01*
G01X1626118Y551132D02*
Y551919D01*
G01Y554281D02*
Y555069D01*
G01Y547982D02*
Y548770D01*
G01Y541683D02*
Y542470D01*
G01Y544833D02*
Y545620D01*
G01Y538533D02*
Y539321D01*
G01Y532234D02*
Y533022D01*
G01Y535384D02*
Y536171D01*
G01Y529085D02*
Y529872D01*
G01Y522785D02*
Y523573D01*
G01Y525935D02*
Y526722D01*
G01Y519636D02*
Y520423D01*
G01Y513337D02*
Y514124D01*
G01Y516486D02*
Y517274D01*
G01Y510187D02*
Y510974D01*
G01Y503888D02*
Y504675D01*
G01Y507037D02*
Y507825D01*
G01Y500738D02*
Y501525D01*
G01Y494439D02*
Y495226D01*
G01Y497588D02*
Y498376D01*
G01Y491289D02*
Y492077D01*
G01Y488140D02*
Y488927D01*
G01X1626077Y513337D02*
Y510974D01*
G01Y516486D02*
Y514124D01*
G01Y519636D02*
Y517274D01*
G01Y522785D02*
Y520423D01*
G01Y525935D02*
Y523573D01*
G01Y529085D02*
Y526722D01*
G01X1625803Y529675D02*
Y510384D01*
G01X1625742Y551132D02*
Y551919D01*
G01Y554281D02*
Y555069D01*
G01Y547982D02*
Y548770D01*
G01Y541683D02*
Y542470D01*
G01Y544833D02*
Y545620D01*
G01Y538533D02*
Y539321D01*
G01Y532234D02*
Y533022D01*
G01Y535384D02*
Y536171D01*
G01Y529085D02*
Y529872D01*
G01Y522785D02*
Y523573D01*
G01Y525935D02*
Y526722D01*
G01Y519636D02*
Y520423D01*
G01Y513337D02*
Y514124D01*
G01Y516486D02*
Y517274D01*
G01Y510187D02*
Y510974D01*
G01Y503888D02*
Y504675D01*
G01Y507037D02*
Y507825D01*
G01Y500738D02*
Y501525D01*
G01Y494439D02*
Y495226D01*
G01Y497588D02*
Y498376D01*
G01Y491289D02*
Y492077D01*
G01Y488140D02*
Y488927D01*
G01X1625527Y488317D02*
Y486742D01*
G01Y493317D02*
Y491742D01*
G01Y498317D02*
Y496742D01*
G01Y503317D02*
Y501742D01*
G01Y508317D02*
Y506742D01*
G01Y533317D02*
Y531742D01*
G01Y538317D02*
Y536742D01*
G01Y543317D02*
Y541742D01*
G01Y549104D02*
Y545955D01*
G01Y553317D02*
Y551742D01*
G01Y558317D02*
Y556742D01*
G01X1625303Y529675D02*
Y510384D01*
G01X1625093Y510876D02*
Y529183D01*
G01X1624543Y489104D02*
Y485955D01*
G01Y494104D02*
Y490955D01*
G01Y499104D02*
Y495955D01*
G01Y504104D02*
Y500955D01*
G01Y509104D02*
Y505955D01*
G01Y534104D02*
Y530955D01*
G01Y539104D02*
Y535955D01*
G01Y544104D02*
Y540955D01*
G01Y548317D02*
Y546742D01*
G01Y554104D02*
Y550955D01*
G01Y559104D02*
Y555955D01*
G01X1624386Y510384D02*
Y529675D01*
G01X1624109Y512746D02*
Y511565D01*
G01Y515896D02*
Y514714D01*
G01Y519045D02*
Y517864D01*
G01Y522195D02*
Y521014D01*
G01Y525344D02*
Y524163D01*
G01Y528494D02*
Y527313D01*
G01X1623559Y489104D02*
Y485955D01*
G01Y494104D02*
Y490955D01*
G01Y499104D02*
Y495955D01*
G01Y504104D02*
Y500955D01*
G01Y509104D02*
Y505955D01*
G01Y534104D02*
Y530955D01*
G01Y539104D02*
Y535955D01*
G01Y544104D02*
Y540955D01*
G01Y554104D02*
Y550955D01*
G01Y559104D02*
Y555955D01*
G01X1622575Y488317D02*
Y486742D01*
G01Y493317D02*
Y491742D01*
G01Y498317D02*
Y496742D01*
G01Y503317D02*
Y501742D01*
G01Y508317D02*
Y506742D01*
G01Y533317D02*
Y531742D01*
G01Y538317D02*
Y536742D01*
G01Y543317D02*
Y541742D01*
G01Y553317D02*
Y551742D01*
G01Y558317D02*
Y556742D01*
G01X1622380Y488927D02*
Y488140D01*
G01Y492077D02*
Y491289D01*
G01Y495226D02*
Y494439D01*
G01Y498376D02*
Y497588D01*
G01Y501525D02*
Y500738D01*
G01Y504675D02*
Y503888D01*
G01Y507825D02*
Y507037D01*
G01Y510974D02*
Y510187D01*
G01Y514124D02*
Y513337D01*
G01Y517274D02*
Y516486D01*
G01Y520423D02*
Y519636D01*
G01Y523573D02*
Y522785D01*
G01Y526722D02*
Y525935D01*
G01Y529872D02*
Y529085D01*
G01Y533022D02*
Y532234D01*
G01Y536171D02*
Y535384D01*
G01Y539321D02*
Y538533D01*
G01Y542470D02*
Y541683D01*
G01Y545620D02*
Y544833D01*
G01Y548770D02*
Y547982D01*
G01Y551919D02*
Y551132D01*
G01Y555069D02*
Y554281D01*
G01X1621394Y548317D02*
Y546742D01*
G01X1621030Y510384D02*
Y529675D01*
G01X1620978Y516407D02*
Y514203D01*
G01Y525856D02*
Y523651D01*
G01X1620959Y512746D02*
Y511565D01*
G01Y515896D02*
Y514714D01*
G01Y519045D02*
Y517864D01*
G01Y522195D02*
Y521014D01*
G01Y525344D02*
Y524163D01*
G01Y528494D02*
Y527313D01*
G01X1620552Y525856D02*
Y529675D01*
G01Y516407D02*
Y523651D01*
G01Y510384D02*
Y514203D01*
G01X1620396Y488927D02*
Y488140D01*
G01Y492077D02*
Y491289D01*
G01Y495226D02*
Y494439D01*
G01Y498376D02*
Y497588D01*
G01Y501525D02*
Y500738D01*
G01Y504675D02*
Y503888D01*
G01Y507825D02*
Y507037D01*
G01Y510974D02*
Y510187D01*
G01Y514124D02*
Y513337D01*
G01Y517274D02*
Y516486D01*
G01Y520423D02*
Y519636D01*
G01Y523573D02*
Y522785D01*
G01Y526722D02*
Y525935D01*
G01Y529872D02*
Y529085D01*
G01Y533022D02*
Y532234D01*
G01Y536171D02*
Y535384D01*
G01Y539321D02*
Y538533D01*
G01Y542470D02*
Y541683D01*
G01Y545620D02*
Y544833D01*
G01Y548770D02*
Y547982D01*
G01Y551919D02*
Y551132D01*
G01Y555069D02*
Y554281D01*
G01X1619425Y488317D02*
Y486742D01*
G01Y493317D02*
Y491742D01*
G01Y498317D02*
Y496742D01*
G01Y503317D02*
Y501742D01*
G01Y508317D02*
Y506742D01*
G01Y533317D02*
Y531742D01*
G01Y538317D02*
Y536742D01*
G01Y543317D02*
Y541742D01*
G01Y553317D02*
Y551742D01*
G01Y558317D02*
Y556742D01*
G01X1619095Y523651D02*
Y525856D01*
G01Y514203D02*
Y516407D01*
G01X1618745Y551132D02*
Y551919D01*
G01Y554281D02*
Y555069D01*
G01Y547982D02*
Y548770D01*
G01Y541683D02*
Y542470D01*
G01Y544833D02*
Y545620D01*
G01Y538533D02*
Y539321D01*
G01Y532234D02*
Y533022D01*
G01Y535384D02*
Y536171D01*
G01Y529085D02*
Y529872D01*
G01Y522785D02*
Y523573D01*
G01Y525935D02*
Y526722D01*
G01Y519636D02*
Y520423D01*
G01Y513337D02*
Y514124D01*
G01Y516486D02*
Y517274D01*
G01Y510187D02*
Y510974D01*
G01Y503888D02*
Y504675D01*
G01Y507037D02*
Y507825D01*
G01Y500738D02*
Y501525D01*
G01Y494439D02*
Y495226D01*
G01Y497588D02*
Y498376D01*
G01Y491289D02*
Y492077D01*
G01Y488140D02*
Y488927D01*
G01X1617016Y488140D02*
Y485777D01*
G01Y491289D02*
Y488927D01*
G01Y494439D02*
Y492077D01*
G01Y497588D02*
Y495226D01*
G01Y500738D02*
Y498376D01*
G01Y503888D02*
Y501525D01*
G01Y507037D02*
Y504675D01*
G01Y510187D02*
Y507825D01*
G01Y513337D02*
Y510974D01*
G01Y516486D02*
Y514124D01*
G01Y519636D02*
Y517274D01*
G01Y522785D02*
Y520423D01*
G01Y525935D02*
Y523573D01*
G01Y529085D02*
Y526722D01*
G01Y532234D02*
Y529872D01*
G01Y535384D02*
Y533022D01*
G01Y538533D02*
Y536171D01*
G01Y541683D02*
Y539321D01*
G01Y544833D02*
Y542470D01*
G01Y547982D02*
Y545620D01*
G01Y551132D02*
Y548770D01*
G01Y554281D02*
Y551919D01*
G01Y557431D02*
Y555069D01*
G01X1616078Y551132D02*
Y551919D01*
G01Y554281D02*
Y555069D01*
G01Y547982D02*
Y548770D01*
G01Y541683D02*
Y542470D01*
G01Y544833D02*
Y545620D01*
G01Y538533D02*
Y539321D01*
G01Y532234D02*
Y533022D01*
G01Y535384D02*
Y536171D01*
G01Y529085D02*
Y529872D01*
G01Y522785D02*
Y523573D01*
G01Y525935D02*
Y526722D01*
G01Y519636D02*
Y520423D01*
G01Y513337D02*
Y514124D01*
G01Y516486D02*
Y517274D01*
G01Y510187D02*
Y510974D01*
G01Y503888D02*
Y504675D01*
G01Y507037D02*
Y507825D01*
G01Y500738D02*
Y501525D01*
G01Y494439D02*
Y495226D01*
G01Y497588D02*
Y498376D01*
G01Y491289D02*
Y492077D01*
G01Y488140D02*
Y488927D01*
G01X1615931Y551132D02*
Y551919D01*
G01Y554281D02*
Y555069D01*
G01Y547982D02*
Y548770D01*
G01Y541683D02*
Y542470D01*
G01Y544833D02*
Y545620D01*
G01Y538533D02*
Y539321D01*
G01Y532234D02*
Y533022D01*
G01Y535384D02*
Y536171D01*
G01Y529085D02*
Y529872D01*
G01Y522785D02*
Y523573D01*
G01Y525935D02*
Y526722D01*
G01Y519636D02*
Y520423D01*
G01Y513337D02*
Y514124D01*
G01Y516486D02*
Y517274D01*
G01Y510187D02*
Y510974D01*
G01Y503888D02*
Y504675D01*
G01Y507037D02*
Y507825D01*
G01Y500738D02*
Y501525D01*
G01Y494439D02*
Y495226D01*
G01Y497588D02*
Y498376D01*
G01Y491289D02*
Y492077D01*
G01Y488140D02*
Y488927D01*
G01X1614338Y551132D02*
Y551919D01*
G01Y554281D02*
Y555069D01*
G01Y547982D02*
Y548770D01*
G01Y541683D02*
Y542470D01*
G01Y544833D02*
Y545620D01*
G01Y538533D02*
Y539321D01*
G01Y532234D02*
Y533022D01*
G01Y535384D02*
Y536171D01*
G01Y529085D02*
Y529872D01*
G01Y522785D02*
Y523573D01*
G01Y525935D02*
Y526722D01*
G01Y519636D02*
Y520423D01*
G01Y513337D02*
Y514124D01*
G01Y516486D02*
Y517274D01*
G01Y510187D02*
Y510974D01*
G01Y503888D02*
Y504675D01*
G01Y507037D02*
Y507825D01*
G01Y500738D02*
Y501525D01*
G01Y494439D02*
Y495226D01*
G01Y497588D02*
Y498376D01*
G01Y491289D02*
Y492077D01*
G01Y488140D02*
Y488927D01*
G01X1613397D02*
Y488140D01*
G01Y492077D02*
Y491289D01*
G01Y495226D02*
Y494439D01*
G01Y498376D02*
Y497588D01*
G01Y501525D02*
Y500738D01*
G01Y504675D02*
Y503888D01*
G01Y507825D02*
Y507037D01*
G01Y510974D02*
Y510187D01*
G01Y514124D02*
Y513337D01*
G01Y517274D02*
Y516486D01*
G01Y520423D02*
Y519636D01*
G01Y523573D02*
Y522785D01*
G01Y526722D02*
Y525935D01*
G01Y529872D02*
Y529085D01*
G01Y533022D02*
Y532234D01*
G01Y536171D02*
Y535384D01*
G01Y539321D02*
Y538533D01*
G01Y542470D02*
Y541683D01*
G01Y545620D02*
Y544833D01*
G01Y548770D02*
Y547982D01*
G01Y551919D02*
Y551132D01*
G01Y555069D02*
Y554281D01*
G01X1610560Y488927D02*
Y488140D01*
G01Y492077D02*
Y491289D01*
G01Y495226D02*
Y494439D01*
G01Y498376D02*
Y497588D01*
G01Y501525D02*
Y500738D01*
G01Y504675D02*
Y503888D01*
G01Y507825D02*
Y507037D01*
G01Y510974D02*
Y510187D01*
G01Y514124D02*
Y513337D01*
G01Y517274D02*
Y516486D01*
G01Y520423D02*
Y519636D01*
G01Y523573D02*
Y522785D01*
G01Y526722D02*
Y525935D01*
G01Y529872D02*
Y529085D01*
G01Y533022D02*
Y532234D01*
G01Y536171D02*
Y535384D01*
G01Y539321D02*
Y538533D01*
G01Y542470D02*
Y541683D01*
G01Y545620D02*
Y544833D01*
G01Y548770D02*
Y547982D01*
G01Y551919D02*
Y551132D01*
G01Y555069D02*
Y554281D01*
G01X1610372Y551132D02*
Y551919D01*
G01Y554281D02*
Y555069D01*
G01Y547982D02*
Y548770D01*
G01Y541683D02*
Y542470D01*
G01Y544833D02*
Y545620D01*
G01Y538533D02*
Y539321D01*
G01Y532234D02*
Y533022D01*
G01Y535384D02*
Y536171D01*
G01Y529085D02*
Y529872D01*
G01Y522785D02*
Y523573D01*
G01Y525935D02*
Y526722D01*
G01Y519636D02*
Y520423D01*
G01Y513337D02*
Y514124D01*
G01Y516486D02*
Y517274D01*
G01Y510187D02*
Y510974D01*
G01Y503888D02*
Y504675D01*
G01Y507037D02*
Y507825D01*
G01Y500738D02*
Y501525D01*
G01Y494439D02*
Y495226D01*
G01Y497588D02*
Y498376D01*
G01Y491289D02*
Y492077D01*
G01Y488140D02*
Y488927D01*
G01X1608598Y551132D02*
Y551919D01*
G01Y554281D02*
Y555069D01*
G01Y547982D02*
Y548770D01*
G01Y541683D02*
Y542470D01*
G01Y544833D02*
Y545620D01*
G01Y538533D02*
Y539321D01*
G01Y532234D02*
Y533022D01*
G01Y535384D02*
Y536171D01*
G01Y529085D02*
Y529872D01*
G01Y522785D02*
Y523573D01*
G01Y525935D02*
Y526722D01*
G01Y519636D02*
Y520423D01*
G01Y513337D02*
Y514124D01*
G01Y516486D02*
Y517274D01*
G01Y510187D02*
Y510974D01*
G01Y503888D02*
Y504675D01*
G01Y507037D02*
Y507825D01*
G01Y500738D02*
Y501525D01*
G01Y494439D02*
Y495226D01*
G01Y497588D02*
Y498376D01*
G01Y491289D02*
Y492077D01*
G01Y488140D02*
Y488927D01*
G01X1619425Y556742D02*
X1626590D01*
G01X1624543Y556545D02*
X1623559D01*
G01X1624543Y556151D02*
X1623559D01*
G01X1624543Y555955D02*
X1623559D01*
G01X1615931Y555069D02*
X1608598D01*
G01X1628087D02*
X1616078D01*
G01Y554281D02*
X1628087D01*
G01X1608598D02*
X1615931D01*
G01X1624543Y554104D02*
X1623559D01*
G01X1624543Y553907D02*
X1623559D01*
G01X1624543Y553514D02*
X1623559D01*
G01X1619425Y553317D02*
X1626590D01*
G01X1615931Y551919D02*
X1608598D01*
G01X1628087D02*
X1616078D01*
G01X1619425Y551742D02*
X1626590D01*
G01X1624543Y551545D02*
X1623559D01*
G01X1624543Y551151D02*
X1623559D01*
G01X1616078Y551132D02*
X1628087D01*
G01X1608598D02*
X1615931D01*
G01X1624543Y550955D02*
X1623559D01*
G01X1656827Y550837D02*
X1630134D01*
G01X1626984Y549734D02*
X1628087D01*
G01X1626512Y549104D02*
X1625527D01*
G01X1626512Y548907D02*
X1625527D01*
G01X1615931Y548770D02*
X1608598D01*
G01X1628087D02*
X1616078D01*
G01X1626512Y548514D02*
X1625527D01*
G01X1656827Y548474D02*
X1630134D01*
G01X1626984Y548317D02*
X1621394D01*
G01X1616078Y547982D02*
X1628087D01*
G01X1608598D02*
X1615931D01*
G01X1626984Y546742D02*
X1621394D01*
G01X1626512Y546545D02*
X1625527D01*
G01X1626512Y546151D02*
X1625527D01*
G01X1626512Y545955D02*
X1625527D01*
G01X1615931Y545620D02*
X1608598D01*
G01X1628087D02*
X1616078D01*
G01X1628087Y545325D02*
X1626984D01*
G01X1616078Y544833D02*
X1628087D01*
G01X1608598D02*
X1615931D01*
G01X1624543Y544104D02*
X1623559D01*
G01X1624543Y543907D02*
X1623559D01*
G01X1624543Y543514D02*
X1623559D01*
G01X1619425Y543317D02*
X1626590D01*
G01X1615931Y542470D02*
X1608598D01*
G01X1628087D02*
X1616078D01*
G01X1619425Y541742D02*
X1626590D01*
G01X1616078Y541683D02*
X1628087D01*
G01X1608598D02*
X1615931D01*
G01X1624543Y541545D02*
X1623559D01*
G01X1624543Y541151D02*
X1623559D01*
G01X1624543Y540955D02*
X1623559D01*
G01X1615931Y539321D02*
X1608598D01*
G01X1628087D02*
X1616078D01*
G01X1624543Y539104D02*
X1623559D01*
G01X1624543Y538907D02*
X1623559D01*
G01X1616078Y538533D02*
X1628087D01*
G01X1608598D02*
X1615931D01*
G01X1624543Y538514D02*
X1623559D01*
G01X1619425Y538317D02*
X1626590D01*
G01X1619425Y536742D02*
X1626590D01*
G01X1624543Y536545D02*
X1623559D01*
G01X1657784Y536230D02*
X1638323D01*
G01X1615931Y536171D02*
X1608598D01*
G01X1628087D02*
X1616078D01*
G01X1624543Y536151D02*
X1623559D01*
G01X1624543Y535955D02*
X1623559D01*
G01X1616078Y535384D02*
X1628087D01*
G01X1608598D02*
X1615931D01*
G01X1624543Y534104D02*
X1623559D01*
G01X1624543Y533907D02*
X1623559D01*
G01X1624543Y533514D02*
X1623559D01*
G01X1619425Y533317D02*
X1626590D01*
G01X1615931Y533022D02*
X1608598D01*
G01X1628087D02*
X1616078D01*
G01Y532234D02*
X1628087D01*
G01X1608598D02*
X1615931D01*
G01X1656827Y532136D02*
X1630134D01*
G01X1619425Y531742D02*
X1626590D01*
G01X1624543Y531545D02*
X1623559D01*
G01X1624543Y531151D02*
X1623559D01*
G01X1624543Y530955D02*
X1623559D01*
G01X1615931Y529872D02*
X1608598D01*
G01X1628087D02*
X1616078D01*
G01X1638323Y529793D02*
X1656827D01*
G01X1628087D02*
X1626984D01*
G01X1652326Y529774D02*
X1630134D01*
G01X1628087Y529675D02*
X1620552D01*
G01X1625093Y529183D02*
X1622968D01*
G01X1616078Y529085D02*
X1628087D01*
G01X1608598D02*
X1615931D01*
G01X1626077Y528888D02*
X1625093D01*
G01X1626077Y528691D02*
X1625093D01*
G01X1626984Y528494D02*
X1620959D01*
G01X1626984Y527313D02*
X1620959D01*
G01X1626077Y527116D02*
X1625093D01*
G01X1626077Y526919D02*
X1625093D01*
G01X1615931Y526722D02*
X1608598D01*
G01X1628087D02*
X1616078D01*
G01Y525935D02*
X1628087D01*
G01X1608598D02*
X1615931D01*
G01X1620978Y525856D02*
X1619095D01*
G01X1626077Y525738D02*
X1625093D01*
G01X1626077Y525541D02*
X1625093D01*
G01X1626984Y525344D02*
X1620959D01*
G01X1626984Y524163D02*
X1620959D01*
G01X1626077Y523966D02*
X1625093D01*
G01X1626077Y523770D02*
X1625093D01*
G01X1619095Y523651D02*
X1620978D01*
G01X1615931Y523573D02*
X1608598D01*
G01X1628087D02*
X1616078D01*
G01Y522785D02*
X1628087D01*
G01X1608598D02*
X1615931D01*
G01X1626077Y522588D02*
X1625093D01*
G01X1626077Y522392D02*
X1625093D01*
G01X1626984Y522195D02*
X1620959D01*
G01X1626984Y521014D02*
X1620959D01*
G01X1626077Y520817D02*
X1625093D01*
G01X1626077Y520620D02*
X1625093D01*
G01X1615931Y520423D02*
X1608598D01*
G01X1628087D02*
X1616078D01*
G01Y519636D02*
X1628087D01*
G01X1608598D02*
X1615931D01*
G01X1626077Y519439D02*
X1625093D01*
G01X1626077Y519242D02*
X1625093D01*
G01X1626984Y519045D02*
X1620959D01*
G01X1626984Y517864D02*
X1620959D01*
G01X1626077Y517667D02*
X1625093D01*
G01X1626077Y517470D02*
X1625093D01*
G01X1615931Y517274D02*
X1608598D01*
G01X1628087D02*
X1616078D01*
G01Y516486D02*
X1628087D01*
G01X1608598D02*
X1615931D01*
G01X1620978Y516407D02*
X1619095D01*
G01X1626077Y516289D02*
X1625093D01*
G01X1626077Y516092D02*
X1625093D01*
G01X1626984Y515896D02*
X1620959D01*
G01X1626984Y514714D02*
X1620959D01*
G01X1626077Y514518D02*
X1625093D01*
G01X1626077Y514321D02*
X1625093D01*
G01X1619095Y514203D02*
X1620978D01*
G01X1615931Y514124D02*
X1608598D01*
G01X1628087D02*
X1616078D01*
G01Y513337D02*
X1628087D01*
G01X1608598D02*
X1615931D01*
G01X1626077Y513140D02*
X1625093D01*
G01X1626077Y512943D02*
X1625093D01*
G01X1626984Y512746D02*
X1620959D01*
G01X1626984Y511565D02*
X1620959D01*
G01X1626077Y511368D02*
X1625093D01*
G01X1626077Y511171D02*
X1625093D01*
G01X1615931Y510974D02*
X1608598D01*
G01X1628087D02*
X1616078D01*
G01X1625093Y510876D02*
X1622968D01*
G01X1620552Y510384D02*
X1628087D01*
G01X1652326Y510285D02*
X1630134D01*
G01X1628087Y510266D02*
X1626984D01*
G01X1656827D02*
X1638323D01*
G01X1616078Y510187D02*
X1628087D01*
G01X1608598D02*
X1615931D01*
G01X1624543Y509104D02*
X1623559D01*
G01X1624543Y508907D02*
X1623559D01*
G01X1624543Y508514D02*
X1623559D01*
G01X1619425Y508317D02*
X1626590D01*
G01X1656827Y507923D02*
X1630134D01*
G01X1615931Y507825D02*
X1608598D01*
G01X1628087D02*
X1616078D01*
G01Y507037D02*
X1628087D01*
G01X1608598D02*
X1615931D01*
G01X1619425Y506742D02*
X1626590D01*
G01X1624543Y506545D02*
X1623559D01*
G01X1624543Y506151D02*
X1623559D01*
G01X1624543Y505955D02*
X1623559D01*
G01X1615931Y504675D02*
X1608598D01*
G01X1628087D02*
X1616078D01*
G01X1624543Y504104D02*
X1623559D01*
G01X1657784Y503927D02*
X1638323D01*
G01X1624543Y503907D02*
X1623559D01*
G01X1616078Y503888D02*
X1628087D01*
G01X1608598D02*
X1615931D01*
G01X1624543Y503514D02*
X1623559D01*
G01X1619425Y503317D02*
X1626590D01*
G01X1619425Y501742D02*
X1626590D01*
G01X1624543Y501545D02*
X1623559D01*
G01X1615931Y501525D02*
X1608598D01*
G01X1628087D02*
X1616078D01*
G01X1624543Y501151D02*
X1623559D01*
G01X1624543Y500955D02*
X1623559D01*
G01X1616078Y500738D02*
X1628087D01*
G01X1608598D02*
X1615931D01*
G01X1624543Y499104D02*
X1623559D01*
G01X1624543Y498907D02*
X1623559D01*
G01X1624543Y498514D02*
X1623559D01*
G01X1615931Y498376D02*
X1608598D01*
G01X1628087D02*
X1616078D01*
G01X1619425Y498317D02*
X1626590D01*
G01X1616078Y497588D02*
X1628087D01*
G01X1608598D02*
X1615931D01*
G01X1619425Y496742D02*
X1626590D01*
G01X1624543Y496545D02*
X1623559D01*
G01X1624543Y496151D02*
X1623559D01*
G01X1624543Y495955D02*
X1623559D01*
G01X1615931Y495226D02*
X1608598D01*
G01X1628087D02*
X1616078D01*
G01Y494439D02*
X1628087D01*
G01X1608598D02*
X1615931D01*
G01X1624543Y494104D02*
X1623559D01*
G01X1624543Y493907D02*
X1623559D01*
G01X1624543Y493514D02*
X1623559D01*
G01X1619425Y493317D02*
X1626590D01*
G01X1656827Y492687D02*
X1630134D01*
G01X1615931Y492077D02*
X1608598D01*
G01X1628087D02*
X1616078D01*
G01X1619425Y491742D02*
X1626590D01*
G01X1624543Y491545D02*
X1623559D01*
G01X1616078Y491289D02*
X1628087D01*
G01X1608598D02*
X1615931D01*
G01X1624543Y491151D02*
X1623559D01*
G01X1624543Y490955D02*
X1623559D01*
G01X1656827Y490325D02*
X1630134D01*
G01X1624543Y489104D02*
X1623559D01*
G01X1615931Y488927D02*
X1608598D01*
G01X1628087D02*
X1616078D01*
G01X1624543Y488907D02*
X1623559D01*
G01X1624543Y488514D02*
X1623559D01*
G01X1619425Y488317D02*
X1626590D01*
G01X1616078Y488140D02*
X1628087D01*
G01X1608598D02*
X1615931D01*
G01X1619425Y486742D02*
X1626590D01*
G01X1624543Y486545D02*
X1623559D01*
G01X1624543Y486151D02*
X1623559D01*
G01X1624543Y485955D02*
X1623559D01*
G01X1615931Y485777D02*
X1608598D01*
G01X1628087D02*
X1616078D01*
G01X1626145Y557431D02*
Y558218D01*
G01X1626118Y557431D02*
Y558218D01*
G01X1625742Y557431D02*
Y558218D01*
G01X1622380D02*
Y557431D01*
G01X1620396Y558218D02*
Y557431D01*
G01X1618745D02*
Y558218D01*
G01X1616078Y557431D02*
Y558218D01*
G01X1615931Y557431D02*
Y558218D01*
G01X1614338Y557431D02*
Y558218D01*
G01X1613397D02*
Y557431D01*
G01X1610560Y558218D02*
Y557431D01*
G01X1610372D02*
Y558218D01*
G01X1608598Y557431D02*
Y558218D01*
G01X1616078Y557431D02*
X1628087D01*
G01X1608598D02*
X1615931D01*
G01X1629774Y615689D02*
G03X1631205I716J0D01*
G01X1626884D02*
G03X1628315I716J0D01*
G01X1630646Y625069D02*
G03Y628218I0J1575D01*
G01X1625786Y614614D02*
G03X1628421Y614759I1247J1352D01*
G01D02*
G03X1631202Y614764I1388J1207D01*
G01X1625492Y615285D02*
G03X1625786Y614614I913J0D01*
G01X1626315Y628218D02*
G03Y625069I0J-1574D01*
G01X1621812Y617105D02*
G03Y615421I2237J-842D01*
G01X1626590Y603317D02*
G03X1626984Y603711I0J394D01*
G01Y601348D02*
G03X1626590Y601742I-394J0D01*
G01Y593317D02*
G03X1626984Y593711I0J394D01*
G01Y591348D02*
G03X1626590Y591742I-394J0D01*
G01Y598317D02*
G03X1626984Y598711I0J394D01*
G01Y596348D02*
G03X1626590Y596742I-394J0D01*
G01X1623285Y617105D02*
G03X1621812I-736J-277D01*
G01Y615421D02*
G03X1623285I737J277D01*
G01X1624558Y617440D02*
G03X1624036Y618005I-1351J-724D01*
G01X1620990Y618004D02*
G03X1620470Y617438I833J-1287D01*
G01Y615126D02*
G03X1620991Y614561I1351J723D01*
G01X1624038D02*
G03X1624558Y615127I-833J1287D01*
G01X1623285Y615421D02*
G03Y617105I-2236J842D01*
G01X1624558Y615127D02*
G03Y617440I-2162J1157D01*
G01X1620470Y617438D02*
G03Y615126I2163J-1156D01*
G01X1624037Y618005D02*
G03X1620990Y618004I-1523J-2362D01*
G01X1620991Y614561D02*
G03X1624038I1524J2362D01*
G01X1626590Y563317D02*
G03X1626984Y563711I0J394D01*
G01Y561348D02*
G03X1626590Y561742I-394J0D01*
G01Y568317D02*
G03X1626984Y568711I0J394D01*
G01Y566348D02*
G03X1626590Y566742I-394J0D01*
G01Y583317D02*
G03X1626984Y583711I0J394D01*
G01Y581348D02*
G03X1626590Y581742I-394J0D01*
G01Y578317D02*
G03X1626984Y578711I0J394D01*
G01Y576348D02*
G03X1626590Y576742I-394J0D01*
G01Y573317D02*
G03X1626984Y573711I0J394D01*
G01Y571348D02*
G03X1626590Y571742I-394J0D01*
G01Y558317D02*
G03X1626984Y558711I0J394D01*
G01X1621394Y614833D02*
G03I-2166J0D01*
G01X1617274Y617549D02*
G03Y612116I1954J-2717D01*
G01X1621183D02*
G03Y617549I-1955J2717D01*
G01X1622732Y614833D02*
G03I-3504J0D01*
G01X1621532Y610935D02*
G03Y618730I-2304J3897D01*
G01X1616925D02*
G03Y610935I2303J-3898D01*
G01X1615312Y617423D02*
G03X1614721Y617058I-10J-646D01*
G01X1616085Y616615D02*
G03X1615312Y617423I-791J17D01*
G01X1614060Y618127D02*
G03X1613217Y617058I704J-1422D01*
G01X1613426Y615172D02*
G03X1614660Y614199I1735J931D01*
G01X1616303Y614242D02*
G03X1617467Y615381I-730J1910D01*
G01X1617381Y617397D02*
G03X1615642Y618414I-1807J-1094D01*
G01X1614660Y614199D02*
G03X1616303Y614242I757J2475D01*
G01X1617641Y616537D02*
G03X1617380Y617399I-2971J-429D01*
G01X1613087Y616615D02*
G03X1613426Y615172I3015J-53D01*
G01X1617641Y616041D02*
G03Y616538I-3524J249D01*
G01X1617468Y615381D02*
G03X1617641Y616041I-4020J1406D01*
G01X1614660Y615789D02*
G03X1616085I713J-82D01*
G01X1615646Y618414D02*
G03X1614060Y618127I-263J-3073D01*
G01X1609888Y616059D02*
X1608593Y614207D01*
G01X1610665Y615194D02*
X1609975Y614207D01*
G01X1613061Y618214D02*
X1611618Y616067D01*
G01X1621987Y608907D02*
X1621731Y608514D01*
G01X1611653Y618214D02*
X1610862Y616937D01*
G01X1617274Y612116D02*
X1617256Y612060D01*
X1617204Y611895D01*
X1617125Y611637D01*
X1617029Y611309D01*
X1616925Y610935D01*
G01X1621532Y618730D02*
X1621429Y618361D01*
X1621332Y618032D01*
X1621252Y617769D01*
X1621200Y617604D01*
X1621183Y617549D01*
G01X1636669Y606151D02*
Y632549D01*
G01X1636354Y607333D02*
Y605561D01*
G01X1634386Y619616D02*
Y611270D01*
G01X1632645Y618214D02*
Y614207D01*
G01X1632102Y588632D02*
Y606151D01*
G01Y569734D02*
Y586270D01*
G01X1631271Y625856D02*
Y627431D01*
G01X1631236D02*
Y625856D01*
G01X1631212Y627431D02*
Y625856D01*
G01X1631205Y615689D02*
Y618214D01*
G01X1631202Y614764D02*
Y614207D01*
G01X1630449Y611900D02*
Y609498D01*
G01Y617648D02*
Y613868D01*
G01X1629889Y625856D02*
Y627431D01*
G01X1629774Y618214D02*
Y615689D01*
G01X1629519Y627431D02*
Y625856D01*
G01X1628315Y615689D02*
Y618214D01*
G01X1627442Y625856D02*
Y627431D01*
G01X1627072D02*
Y625856D01*
G01X1626884Y618214D02*
Y615689D01*
G01X1626512Y589104D02*
Y585955D01*
G01X1626145Y598376D02*
Y599163D01*
G01Y601525D02*
Y602313D01*
G01Y595226D02*
Y596014D01*
G01Y588927D02*
Y589714D01*
G01Y592077D02*
Y592864D01*
G01Y585777D02*
Y586565D01*
G01Y579478D02*
Y580266D01*
G01Y582628D02*
Y583415D01*
G01Y576329D02*
Y577116D01*
G01Y570029D02*
Y570817D01*
G01Y573179D02*
Y573966D01*
G01Y566880D02*
Y567667D01*
G01Y560581D02*
Y561368D01*
G01Y563730D02*
Y564518D01*
G01X1626118Y598376D02*
Y599163D01*
G01Y601525D02*
Y602313D01*
G01Y595226D02*
Y596014D01*
G01Y588927D02*
Y589714D01*
G01Y592077D02*
Y592864D01*
G01Y585777D02*
Y586565D01*
G01Y579478D02*
Y580266D01*
G01Y582628D02*
Y583415D01*
G01Y576329D02*
Y577116D01*
G01Y570029D02*
Y570817D01*
G01Y573179D02*
Y573966D01*
G01Y566880D02*
Y567667D01*
G01Y560581D02*
Y561368D01*
G01Y563730D02*
Y564518D01*
G01X1625748Y625856D02*
Y627431D01*
G01X1625742Y598376D02*
Y599163D01*
G01Y601525D02*
Y602313D01*
G01Y595226D02*
Y596014D01*
G01Y588927D02*
Y589714D01*
G01Y592077D02*
Y592864D01*
G01Y585777D02*
Y586565D01*
G01Y579478D02*
Y580266D01*
G01Y582628D02*
Y583415D01*
G01Y576329D02*
Y577116D01*
G01Y570029D02*
Y570817D01*
G01Y573179D02*
Y573966D01*
G01Y566880D02*
Y567667D01*
G01Y560581D02*
Y561368D01*
G01Y563730D02*
Y564518D01*
G01X1625724Y625856D02*
Y627431D01*
G01X1625689D02*
Y625856D01*
G01X1625527Y563317D02*
Y561742D01*
G01Y568317D02*
Y566742D01*
G01Y573317D02*
Y571742D01*
G01Y578317D02*
Y576742D01*
G01Y583317D02*
Y581742D01*
G01Y589104D02*
Y585955D01*
G01Y593317D02*
Y591742D01*
G01Y598317D02*
Y596742D01*
G01Y603317D02*
Y601742D01*
G01X1625492Y618214D02*
Y615285D01*
G01X1624543Y564104D02*
Y560955D01*
G01Y569104D02*
Y565955D01*
G01Y574104D02*
Y570955D01*
G01Y579104D02*
Y575955D01*
G01Y584104D02*
Y580955D01*
G01Y588317D02*
Y586742D01*
G01Y594104D02*
Y590955D01*
G01Y599104D02*
Y595955D01*
G01Y604104D02*
Y600955D01*
G01Y611270D02*
Y608966D01*
G01X1623559Y564104D02*
Y560955D01*
G01Y569104D02*
Y565955D01*
G01Y574104D02*
Y570955D01*
G01Y579104D02*
Y575955D01*
G01Y584104D02*
Y580955D01*
G01Y594104D02*
Y590955D01*
G01Y599104D02*
Y595955D01*
G01Y604104D02*
Y600955D01*
G01X1622575Y563317D02*
Y561742D01*
G01Y568317D02*
Y566742D01*
G01Y573317D02*
Y571742D01*
G01Y578317D02*
Y576742D01*
G01Y583317D02*
Y581742D01*
G01Y593317D02*
Y591742D01*
G01Y598317D02*
Y596742D01*
G01Y603317D02*
Y601742D01*
G01X1622380Y561368D02*
Y560581D01*
G01Y564518D02*
Y563730D01*
G01Y567667D02*
Y566880D01*
G01Y570817D02*
Y570029D01*
G01Y573966D02*
Y573179D01*
G01Y577116D02*
Y576329D01*
G01Y580266D02*
Y579478D01*
G01Y583415D02*
Y582628D01*
G01Y586565D02*
Y585777D01*
G01Y589714D02*
Y588927D01*
G01Y592864D02*
Y592077D01*
G01Y596014D02*
Y595226D01*
G01Y599163D02*
Y598376D01*
G01Y602313D02*
Y601525D01*
G01X1621987Y608966D02*
Y608907D01*
G01X1621394Y588317D02*
Y586742D01*
G01X1621348Y608514D02*
Y611270D01*
G01X1620396Y561368D02*
Y560581D01*
G01Y564518D02*
Y563730D01*
G01Y567667D02*
Y566880D01*
G01Y570817D02*
Y570029D01*
G01Y573966D02*
Y573179D01*
G01Y577116D02*
Y576329D01*
G01Y580266D02*
Y579478D01*
G01Y583415D02*
Y582628D01*
G01Y586565D02*
Y585777D01*
G01Y589714D02*
Y588927D01*
G01Y592864D02*
Y592077D01*
G01Y596014D02*
Y595226D01*
G01Y599163D02*
Y598376D01*
G01Y602313D02*
Y601525D01*
G01X1620291Y632549D02*
Y619616D01*
G01X1619693Y618214D02*
Y612460D01*
G01X1619425Y563317D02*
Y561742D01*
G01Y568317D02*
Y566742D01*
G01Y573317D02*
Y571742D01*
G01Y578317D02*
Y576742D01*
G01Y583317D02*
Y581742D01*
G01Y593317D02*
Y591742D01*
G01Y598317D02*
Y596742D01*
G01Y603317D02*
Y601742D01*
G01X1618745Y598376D02*
Y599163D01*
G01Y601525D02*
Y602313D01*
G01Y595226D02*
Y596014D01*
G01Y588927D02*
Y589714D01*
G01Y592077D02*
Y592864D01*
G01Y585777D02*
Y586565D01*
G01Y579478D02*
Y580266D01*
G01Y582628D02*
Y583415D01*
G01Y576329D02*
Y577116D01*
G01Y570029D02*
Y570817D01*
G01Y573179D02*
Y573966D01*
G01Y566880D02*
Y567667D01*
G01Y560581D02*
Y561368D01*
G01Y563730D02*
Y564518D01*
G01X1618232Y618214D02*
Y612460D01*
G01X1617016Y560581D02*
Y558218D01*
G01Y563730D02*
Y561368D01*
G01Y566880D02*
Y564518D01*
G01Y570029D02*
Y567667D01*
G01Y573179D02*
Y570817D01*
G01Y576329D02*
Y573966D01*
G01Y579478D02*
Y577116D01*
G01Y582628D02*
Y580266D01*
G01Y585777D02*
Y583415D01*
G01Y588927D02*
Y586565D01*
G01Y592077D02*
Y589714D01*
G01Y595226D02*
Y592864D01*
G01Y598376D02*
Y596014D01*
G01Y601525D02*
Y599163D01*
G01Y603986D02*
Y602313D01*
G01X1616078Y598376D02*
Y599163D01*
G01Y601525D02*
Y602313D01*
G01Y595226D02*
Y596014D01*
G01Y588927D02*
Y589714D01*
G01Y592077D02*
Y592864D01*
G01Y585777D02*
Y586565D01*
G01Y579478D02*
Y580266D01*
G01Y582628D02*
Y583415D01*
G01Y576329D02*
Y577116D01*
G01Y570029D02*
Y570817D01*
G01Y573179D02*
Y573966D01*
G01Y566880D02*
Y567667D01*
G01Y560581D02*
Y561368D01*
G01Y563730D02*
Y564518D01*
G01X1615931Y598376D02*
Y599163D01*
G01Y601525D02*
Y602313D01*
G01Y595226D02*
Y596014D01*
G01Y588927D02*
Y589714D01*
G01Y592077D02*
Y592864D01*
G01Y585777D02*
Y586565D01*
G01Y579478D02*
Y580266D01*
G01Y582628D02*
Y583415D01*
G01Y576329D02*
Y577116D01*
G01Y570029D02*
Y570817D01*
G01Y573179D02*
Y573966D01*
G01Y566880D02*
Y567667D01*
G01Y560581D02*
Y561368D01*
G01Y563730D02*
Y564518D01*
G01X1614338Y598376D02*
Y599163D01*
G01Y601525D02*
Y602313D01*
G01Y595226D02*
Y596014D01*
G01Y588927D02*
Y589714D01*
G01Y592077D02*
Y592864D01*
G01Y585777D02*
Y586565D01*
G01Y579478D02*
Y580266D01*
G01Y582628D02*
Y583415D01*
G01Y576329D02*
Y577116D01*
G01Y570029D02*
Y570817D01*
G01Y573179D02*
Y573966D01*
G01Y566880D02*
Y567667D01*
G01Y560581D02*
Y561368D01*
G01Y563730D02*
Y564518D01*
G01X1613474Y608514D02*
Y611270D01*
G01X1613397Y561368D02*
Y560581D01*
G01Y564518D02*
Y563730D01*
G01Y567667D02*
Y566880D01*
G01Y570817D02*
Y570029D01*
G01Y573966D02*
Y573179D01*
G01Y577116D02*
Y576329D01*
G01Y580266D02*
Y579478D01*
G01Y583415D02*
Y582628D01*
G01Y586565D02*
Y585777D01*
G01Y589714D02*
Y588927D01*
G01Y592864D02*
Y592077D01*
G01Y596014D02*
Y595226D01*
G01Y599163D02*
Y598376D01*
G01Y602313D02*
Y601525D01*
G01X1610560Y561368D02*
Y560581D01*
G01Y564518D02*
Y563730D01*
G01Y567667D02*
Y566880D01*
G01Y570817D02*
Y570029D01*
G01Y573966D02*
Y573179D01*
G01Y577116D02*
Y576329D01*
G01Y580266D02*
Y579478D01*
G01Y583415D02*
Y582628D01*
G01Y586565D02*
Y585777D01*
G01Y589714D02*
Y588927D01*
G01Y592864D02*
Y592077D01*
G01Y596014D02*
Y595226D01*
G01Y599163D02*
Y598376D01*
G01Y602313D02*
Y601525D01*
G01X1610372Y598376D02*
Y599163D01*
G01Y601525D02*
Y602313D01*
G01Y595226D02*
Y596014D01*
G01Y588927D02*
Y589714D01*
G01Y592077D02*
Y592864D01*
G01Y585777D02*
Y586565D01*
G01Y579478D02*
Y580266D01*
G01Y582628D02*
Y583415D01*
G01Y576329D02*
Y577116D01*
G01Y570029D02*
Y570817D01*
G01Y573179D02*
Y573966D01*
G01Y566880D02*
Y567667D01*
G01Y560581D02*
Y561368D01*
G01Y563730D02*
Y564518D01*
G01X1608598Y598376D02*
Y599163D01*
G01Y601525D02*
Y602313D01*
G01Y595226D02*
Y596014D01*
G01Y588927D02*
Y589714D01*
G01Y592077D02*
Y592864D01*
G01Y585777D02*
Y586565D01*
G01Y579478D02*
Y580266D01*
G01Y582628D02*
Y583415D01*
G01Y576329D02*
Y577116D01*
G01Y570029D02*
Y570817D01*
G01Y573179D02*
Y573966D01*
G01Y566880D02*
Y567667D01*
G01Y560581D02*
Y561368D01*
G01Y563730D02*
Y564518D01*
G01X1607619Y608514D02*
Y605738D01*
G01X1607144Y611270D02*
Y605738D01*
G01X1606827Y619616D02*
Y605738D01*
G01X1621183Y612116D02*
X1621200Y612060D01*
X1621253Y611895D01*
X1621332Y611636D01*
X1621427Y611309D01*
X1621532Y610935D01*
G01X1617274Y617549D02*
X1617256Y617605D01*
X1617204Y617771D01*
X1617125Y618029D01*
X1617029Y618356D01*
X1616925Y618730D01*
G01X1610117Y618214D02*
X1610862Y616937D01*
G01X1608567Y618214D02*
X1609888Y616059D01*
G01X1610665Y615194D02*
X1611270Y614207D01*
G01X1611618Y616067D02*
X1612887Y614207D01*
G01X1626315Y628218D02*
X1630646D01*
G01X1625689Y627431D02*
X1631271D01*
G01Y625856D02*
X1625689D01*
G01X1630646Y625069D02*
X1626315D01*
G01X1636669Y622372D02*
X1620291D01*
G01X1606827Y619616D02*
X1660764D01*
G01X1621532Y618730D02*
X1616925D01*
G01X1660764Y618435D02*
X1634386D01*
G01X1610117Y618214D02*
X1608567D01*
G01X1613061D02*
X1611653D01*
G01X1619693D02*
X1618232D01*
G01X1629774D02*
X1628315D01*
G01X1626884D02*
X1625492D01*
G01X1632645D02*
X1631205D01*
G01X1630449Y617648D02*
X1606827D01*
G01X1617274Y617549D02*
X1621183D01*
G01X1614721Y617058D02*
X1613217D01*
G01X1616087Y616615D02*
X1613087D01*
G01X1616086Y615789D02*
X1614660D01*
G01X1609975Y614207D02*
X1608593D01*
G01X1612887D02*
X1611270D01*
G01X1632645D02*
X1631202D01*
G01X1630449Y613868D02*
X1606827D01*
G01X1619693Y612460D02*
X1618232D01*
G01X1621183Y612116D02*
X1617274D01*
G01X1630449Y611900D02*
X1606827D01*
G01X1656827Y611270D02*
X1606827D01*
G01X1616925Y610935D02*
X1621532D01*
G01X1606827Y609498D02*
X1630449D01*
G01X1621987Y608966D02*
X1628087D01*
G01X1621987Y608907D02*
X1628087D01*
G01X1607619Y608514D02*
X1628087D01*
G01X1626984Y607333D02*
X1636354D01*
G01X1658795Y606742D02*
X1628087D01*
G01X1656827Y606348D02*
X1638323D01*
G01X1636669Y606151D02*
X1630134D01*
G01X1606827Y605738D02*
X1626984D01*
G01Y605561D02*
X1636354D01*
G01X1624543Y604104D02*
X1623559D01*
G01X1622968Y603986D02*
X1613984D01*
G01X1624543Y603907D02*
X1623559D01*
G01X1624543Y603514D02*
X1623559D01*
G01X1619425Y603317D02*
X1626590D01*
G01X1615931Y602313D02*
X1608598D01*
G01X1628087D02*
X1616078D01*
G01X1619425Y601742D02*
X1626590D01*
G01X1624543Y601545D02*
X1623559D01*
G01X1616078Y601525D02*
X1628087D01*
G01X1608598D02*
X1615931D01*
G01X1624543Y601151D02*
X1623559D01*
G01X1624543Y600955D02*
X1623559D01*
G01X1615931Y599163D02*
X1608598D01*
G01X1628087D02*
X1616078D01*
G01X1624543Y599104D02*
X1623559D01*
G01X1624543Y598907D02*
X1623559D01*
G01X1624543Y598514D02*
X1623559D01*
G01X1616078Y598376D02*
X1628087D01*
G01X1608598D02*
X1615931D01*
G01X1619425Y598317D02*
X1626590D01*
G01X1619425Y596742D02*
X1626590D01*
G01X1624543Y596545D02*
X1623559D01*
G01X1624543Y596151D02*
X1623559D01*
G01X1615931Y596014D02*
X1608598D01*
G01X1628087D02*
X1616078D01*
G01X1624543Y595955D02*
X1623559D01*
G01X1616078Y595226D02*
X1628087D01*
G01X1608598D02*
X1615931D01*
G01X1624543Y594104D02*
X1623559D01*
G01X1624543Y593907D02*
X1623559D01*
G01X1624543Y593514D02*
X1623559D01*
G01X1619425Y593317D02*
X1626590D01*
G01X1615931Y592864D02*
X1608598D01*
G01X1628087D02*
X1616078D01*
G01Y592077D02*
X1628087D01*
G01X1608598D02*
X1615931D01*
G01X1619425Y591742D02*
X1626590D01*
G01X1624543Y591545D02*
X1623559D01*
G01X1624543Y591151D02*
X1623559D01*
G01X1624543Y590955D02*
X1623559D01*
G01X1628087Y589734D02*
X1626984D01*
G01X1615931Y589714D02*
X1608598D01*
G01X1628087D02*
X1616078D01*
G01X1626512Y589104D02*
X1625527D01*
G01X1616078Y588927D02*
X1628087D01*
G01X1608598D02*
X1615931D01*
G01X1626512Y588907D02*
X1625527D01*
G01X1656827Y588632D02*
X1630134D01*
G01X1626512Y588514D02*
X1625527D01*
G01X1626984Y588317D02*
X1621394D01*
G01X1626984Y586742D02*
X1621394D01*
G01X1615931Y586565D02*
X1608598D01*
G01X1628087D02*
X1616078D01*
G01X1626512Y586545D02*
X1625527D01*
G01X1656827Y586270D02*
X1630134D01*
G01X1626512Y586151D02*
X1625527D01*
G01X1626512Y585955D02*
X1625527D01*
G01X1616078Y585777D02*
X1628087D01*
G01X1608598D02*
X1615931D01*
G01X1628087Y585325D02*
X1626984D01*
G01X1624543Y584104D02*
X1623559D01*
G01X1624543Y583907D02*
X1623559D01*
G01X1624543Y583514D02*
X1623559D01*
G01X1615931Y583415D02*
X1608598D01*
G01X1628087D02*
X1616078D01*
G01X1619425Y583317D02*
X1626590D01*
G01X1616078Y582628D02*
X1628087D01*
G01X1608598D02*
X1615931D01*
G01X1619425Y581742D02*
X1626590D01*
G01X1624543Y581545D02*
X1623559D01*
G01X1624543Y581151D02*
X1623559D01*
G01X1624543Y580955D02*
X1623559D01*
G01X1615931Y580266D02*
X1608598D01*
G01X1628087D02*
X1616078D01*
G01Y579478D02*
X1628087D01*
G01X1608598D02*
X1615931D01*
G01X1624543Y579104D02*
X1623559D01*
G01X1624543Y578907D02*
X1623559D01*
G01X1624543Y578514D02*
X1623559D01*
G01X1619425Y578317D02*
X1626590D01*
G01X1615931Y577116D02*
X1608598D01*
G01X1628087D02*
X1616078D01*
G01X1619425Y576742D02*
X1626590D01*
G01X1624543Y576545D02*
X1623559D01*
G01X1616078Y576329D02*
X1628087D01*
G01X1608598D02*
X1615931D01*
G01X1624543Y576151D02*
X1623559D01*
G01X1624543Y575955D02*
X1623559D01*
G01X1624543Y574104D02*
X1623559D01*
G01X1615931Y573966D02*
X1608598D01*
G01X1628087D02*
X1616078D01*
G01X1624543Y573907D02*
X1623559D01*
G01X1624543Y573514D02*
X1623559D01*
G01X1619425Y573317D02*
X1626590D01*
G01X1616078Y573179D02*
X1628087D01*
G01X1608598D02*
X1615931D01*
G01X1619425Y571742D02*
X1626590D01*
G01X1624543Y571545D02*
X1623559D01*
G01X1624543Y571151D02*
X1623559D01*
G01X1624543Y570955D02*
X1623559D01*
G01X1615931Y570817D02*
X1608598D01*
G01X1628087D02*
X1616078D01*
G01Y570029D02*
X1628087D01*
G01X1608598D02*
X1615931D01*
G01X1656827Y569734D02*
X1630134D01*
G01X1624543Y569104D02*
X1623559D01*
G01X1624543Y568907D02*
X1623559D01*
G01X1624543Y568514D02*
X1623559D01*
G01X1619425Y568317D02*
X1626590D01*
G01X1615931Y567667D02*
X1608598D01*
G01X1628087D02*
X1616078D01*
G01X1656827Y567372D02*
X1630134D01*
G01X1616078Y566880D02*
X1628087D01*
G01X1608598D02*
X1615931D01*
G01X1619425Y566742D02*
X1626590D01*
G01X1624543Y566545D02*
X1623559D01*
G01X1624543Y566151D02*
X1623559D01*
G01X1624543Y565955D02*
X1623559D01*
G01X1615931Y564518D02*
X1608598D01*
G01X1628087D02*
X1616078D01*
G01X1624543Y564104D02*
X1623559D01*
G01X1624543Y563907D02*
X1623559D01*
G01X1616078Y563730D02*
X1628087D01*
G01X1608598D02*
X1615931D01*
G01X1624543Y563514D02*
X1623559D01*
G01X1619425Y563317D02*
X1626590D01*
G01X1619425Y561742D02*
X1626590D01*
G01X1624543Y561545D02*
X1623559D01*
G01X1615931Y561368D02*
X1608598D01*
G01X1628087D02*
X1616078D01*
G01X1624543Y561151D02*
X1623559D01*
G01X1624543Y560955D02*
X1623559D01*
G01X1616078Y560581D02*
X1628087D01*
G01X1608598D02*
X1615931D01*
G01X1624543Y559104D02*
X1623559D01*
G01X1624543Y558907D02*
X1623559D01*
G01X1624543Y558514D02*
X1623559D01*
G01X1619425Y558317D02*
X1626590D01*
G01X1615931Y558218D02*
X1608598D01*
G01X1628087D02*
X1616078D01*
G01X1636669Y632549D02*
X1620291D01*
G01X1631630Y840148D02*
G03Y838966I0J-591D01*
G01Y842903D02*
G03Y841722I0J-591D01*
G01X1627102Y820856D02*
G03I-590J0D01*
G01X1625331Y838966D02*
G03Y840148I0J591D01*
G01Y841722D02*
G03Y842903I0J591D01*
G01X1620306Y821044D02*
X1620212Y820932D01*
G01Y821060D02*
X1620306Y821171D01*
G01X1625341Y839768D02*
X1625248Y839657D01*
G01Y839784D02*
X1625341Y839896D01*
G01X1637912Y813573D02*
Y812588D01*
G01Y816132D02*
Y815148D01*
G01Y818691D02*
Y817707D01*
G01Y821250D02*
Y820266D01*
G01X1637831Y813573D02*
Y812588D01*
G01Y816132D02*
Y815148D01*
G01Y818691D02*
Y817707D01*
G01Y821250D02*
Y820266D01*
G01X1636436Y813573D02*
Y812588D01*
G01Y816132D02*
Y815148D01*
G01Y818691D02*
Y817707D01*
G01Y821250D02*
Y820266D01*
G01X1636354Y813573D02*
Y812588D01*
G01Y816132D02*
Y815148D01*
G01Y818691D02*
Y817707D01*
G01Y821250D02*
Y820266D01*
G01X1636157Y810817D02*
Y823022D01*
G01X1633205Y838671D02*
Y840640D01*
G01Y843199D02*
Y841230D01*
G01X1631630Y840148D02*
Y841722D01*
G01Y842903D02*
Y843494D01*
G01Y838376D02*
Y838966D01*
G01X1630646Y838376D02*
Y843494D01*
G01X1630449D02*
Y838376D01*
G01X1630055Y841230D02*
Y843199D01*
G01Y840640D02*
Y838671D01*
G01X1626905Y841230D02*
Y843199D01*
G01Y840640D02*
Y838671D01*
G01X1626512Y843494D02*
Y838376D01*
G01X1626315D02*
Y843494D01*
G01X1625435Y839896D02*
Y839148D01*
G01X1625341D02*
Y839768D01*
G01X1625331Y838966D02*
Y838376D01*
G01Y841722D02*
Y840148D01*
G01Y843494D02*
Y842903D01*
G01X1625248Y839657D02*
Y839784D01*
G01X1624740Y823022D02*
Y810817D01*
G01X1624543Y813573D02*
Y812588D01*
G01Y816132D02*
Y815148D01*
G01Y818691D02*
Y817707D01*
G01Y821250D02*
Y820266D01*
G01X1624462Y813573D02*
Y812588D01*
G01Y816132D02*
Y815148D01*
G01Y818691D02*
Y817707D01*
G01Y821250D02*
Y820266D01*
G01X1623756Y838671D02*
Y840640D01*
G01Y843199D02*
Y841230D01*
G01X1623067Y813573D02*
Y812588D01*
G01Y816132D02*
Y815148D01*
G01Y818691D02*
Y817707D01*
G01Y821250D02*
Y820266D01*
G01X1622985Y813573D02*
Y812588D01*
G01Y816132D02*
Y815148D01*
G01Y818691D02*
Y817707D01*
G01Y821250D02*
Y820266D01*
G01X1621098Y813573D02*
Y812588D01*
G01Y816132D02*
Y815148D01*
G01Y818691D02*
Y817707D01*
G01Y821250D02*
Y820266D01*
G01X1620399Y821171D02*
Y820423D01*
G01X1620306D02*
Y821044D01*
G01X1620212Y820932D02*
Y821060D01*
G01X1617161Y826959D02*
Y806880D01*
G01X1631630Y843494D02*
X1625331D01*
G01X1630055Y843199D02*
X1633205D01*
G01X1626905D02*
X1623756D01*
G01Y841230D02*
X1626905D01*
G01X1633205D02*
X1630055D01*
G01X1623756Y840640D02*
X1626905D01*
G01X1633205D02*
X1630055D01*
G01X1625341Y839896D02*
X1625435D01*
G01Y839148D02*
X1625341D01*
G01X1630055Y838671D02*
X1633205D01*
G01X1626905D02*
X1623756D01*
G01X1625331Y838376D02*
X1631630D01*
G01X1643736Y826959D02*
X1617161D01*
G01X1636157Y823022D02*
X1624740D01*
G01Y821250D02*
X1621098D01*
G01X1639799D02*
X1636157D01*
G01X1620306Y821171D02*
X1620399D01*
G01Y820423D02*
X1620306D01*
G01X1624740Y820266D02*
X1621098D01*
G01X1639799D02*
X1636157D01*
G01X1624740Y818691D02*
X1621098D01*
G01X1639799D02*
X1636157D01*
G01X1624740Y817707D02*
X1621098D01*
G01X1639799D02*
X1636157D01*
G01X1624740Y816132D02*
X1621098D01*
G01X1639799D02*
X1636157D01*
G01X1624740Y815148D02*
X1621098D01*
G01X1639799D02*
X1636157D01*
G01X1624740Y813573D02*
X1621098D01*
G01X1639799D02*
X1636157D01*
G01X1624740Y812588D02*
X1621098D01*
G01X1639799D02*
X1636157D01*
G01X1624740Y810817D02*
X1636157D01*
G01X1617161Y806880D02*
X1643736D01*
G01X1630646Y857352D02*
G03Y860502I0J1575D01*
G01X1624887Y869441D02*
G03X1623817Y867618I2809J-2874D01*
G01X1631864Y872342D02*
G03X1629649Y867175I6937J-6032D01*
G01X1632749Y872416D02*
G03X1630535Y867175I7142J-6105D01*
G01X1626590Y883829D02*
G03X1626984Y884222I0J394D01*
G01Y881860D02*
G03X1626590Y882254I-394J0D01*
G01Y913829D02*
G03X1626984Y914222I0J394D01*
G01Y911860D02*
G03X1626590Y912254I-394J0D01*
G01Y908829D02*
G03X1626984Y909222I0J394D01*
G01Y906860D02*
G03X1626590Y907254I-394J0D01*
G01Y903829D02*
G03X1626984Y904222I0J394D01*
G01Y901860D02*
G03X1626590Y902254I-394J0D01*
G01Y893829D02*
G03X1626984Y894222I0J394D01*
G01Y891860D02*
G03X1626590Y892254I-394J0D01*
G01Y898829D02*
G03X1626984Y899222I0J394D01*
G01Y896860D02*
G03X1626590Y897254I-394J0D01*
G01Y888829D02*
G03X1626984Y889222I0J394D01*
G01Y886860D02*
G03X1626590Y887254I-394J0D01*
G01X1625392Y868897D02*
G03X1624851Y867913I1277J-1343D01*
G01X1626315Y860502D02*
G03Y857352I0J-1575D01*
G01X1621394Y870738D02*
G03I-2166J0D01*
G01X1622575D02*
G03I-3347J0D01*
G01X1622732D02*
G03I-3504J0D01*
G01X1623756D02*
G03I-4528J0D01*
G01X1611416Y872342D02*
G03X1609201Y867175I6937J-6032D01*
G01X1612301Y872416D02*
G03X1610087Y867175I7143J-6105D01*
G01X1632274Y881138D02*
X1632013Y881053D01*
G01X1630532Y881394D02*
X1630271Y881309D01*
G01X1630009Y883442D02*
X1629748Y883356D01*
G01X1631752Y883697D02*
X1631403Y883527D01*
G01X1629835Y882844D02*
X1630009Y882930D01*
G01X1632362Y880627D02*
X1632797Y880882D01*
G01X1625181Y872102D02*
X1625469Y872280D01*
X1625823Y872342D01*
G01X1620992Y870783D02*
X1621275Y870961D01*
X1621462Y871226D01*
X1621529Y871528D01*
X1621464Y871829D01*
X1621279Y872095D01*
X1620994Y872277D01*
X1620643Y872342D01*
G01X1620294Y872277D02*
X1620012Y872100D01*
X1619824Y871834D01*
X1619757Y871533D01*
X1619822Y871232D01*
X1620007Y870965D01*
X1620293Y870784D01*
X1620643Y870718D01*
G01X1615825Y870783D02*
X1616107Y870961D01*
X1616294Y871226D01*
X1616361Y871528D01*
X1616297Y871829D01*
X1616112Y872095D01*
X1615826Y872277D01*
X1615476Y872342D01*
G01X1615127Y872277D02*
X1614844Y872100D01*
X1614657Y871834D01*
X1614590Y871533D01*
X1614654Y871232D01*
X1614840Y870965D01*
X1615125Y870784D01*
X1615476Y870718D01*
G01X1631577Y883015D02*
X1631839Y883186D01*
G01X1621066Y867991D02*
X1621426Y868227D01*
X1621665Y868577D01*
X1621750Y868981D01*
X1621668Y869383D01*
X1621431Y869735D01*
X1621068Y869975D01*
X1620643Y870060D01*
G01X1620220Y869976D02*
X1619860Y869740D01*
X1619621Y869390D01*
X1619536Y868986D01*
X1619618Y868584D01*
X1619855Y868232D01*
X1620218Y867992D01*
X1620643Y867907D01*
G01X1615899Y867991D02*
X1616259Y868227D01*
X1616498Y868577D01*
X1616583Y868981D01*
X1616500Y869383D01*
X1616264Y869735D01*
X1615901Y869975D01*
X1615476Y870060D01*
G01X1615053Y869976D02*
X1614692Y869740D01*
X1614454Y869390D01*
X1614369Y868986D01*
X1614451Y868584D01*
X1614688Y868232D01*
X1615051Y867992D01*
X1615476Y867907D01*
G01X1629748Y883356D02*
X1629400Y883100D01*
G01X1627021Y870444D02*
X1625392Y868897D01*
G01X1619445Y870432D02*
X1618994Y869991D01*
X1618724Y869456D01*
X1618653Y868885D01*
X1618795Y868321D01*
X1619142Y867797D01*
X1619669Y867403D01*
X1620312Y867200D01*
X1620991Y867202D01*
X1621631Y867410D01*
X1622154Y867807D01*
X1622495Y868330D01*
X1622633Y868891D01*
X1622562Y869459D01*
X1622291Y869993D01*
G01X1614278Y870432D02*
X1613826Y869991D01*
X1613556Y869456D01*
X1613486Y868885D01*
X1613628Y868321D01*
X1613974Y867797D01*
X1614502Y867403D01*
X1615144Y867200D01*
X1615824Y867202D01*
X1616464Y867410D01*
X1616986Y867807D01*
X1617328Y868330D01*
X1617466Y868891D01*
X1617394Y869459D01*
X1617124Y869993D01*
G01X1626450Y870969D02*
X1624887Y869441D01*
G01X1632536Y881394D02*
X1632274Y881138D01*
G01X1630706Y880882D02*
X1631055Y881224D01*
G01X1631403Y883527D02*
X1631055Y883186D01*
G01X1629661Y882674D02*
X1629835Y882844D01*
G01X1621841Y870432D02*
X1622164Y870851D01*
X1622326Y871334D01*
X1622304Y871839D01*
X1622101Y872316D01*
X1621735Y872719D01*
X1621228Y872987D01*
X1620637Y873081D01*
X1620048Y872984D01*
X1619546Y872715D01*
X1619182Y872311D01*
X1618980Y871833D01*
X1618961Y871328D01*
X1619125Y870847D01*
X1619445Y870432D01*
G01X1616674D02*
X1616996Y870851D01*
X1617159Y871334D01*
X1617137Y871839D01*
X1616934Y872316D01*
X1616567Y872719D01*
X1616061Y872987D01*
X1615470Y873081D01*
X1614881Y872984D01*
X1614378Y872715D01*
X1614014Y872311D01*
X1613813Y871833D01*
X1613794Y871328D01*
X1613958Y870847D01*
X1614278Y870432D01*
G01X1629400Y883100D02*
X1629138Y882759D01*
G01X1627021Y870444D02*
X1627358Y870905D01*
X1627504Y871424D01*
X1627444Y871942D01*
X1627193Y872425D01*
X1626756Y872820D01*
X1626183Y873043D01*
X1625548Y873062D01*
X1624964Y872876D01*
X1624509Y872523D01*
X1624216Y872051D01*
X1624113Y871530D01*
G01X1625182Y872102D02*
X1624992Y871834D01*
G01X1626450Y870969D02*
X1626633Y871234D01*
X1626696Y871532D01*
X1626631Y871829D01*
G01X1630706Y881650D02*
X1630532Y881394D01*
G01X1631403Y882759D02*
X1631577Y883015D01*
G01X1632797Y880882D02*
X1633058Y881309D01*
G01X1631055Y881224D02*
X1631229Y881565D01*
G01X1631055Y883186D02*
X1630881Y882844D01*
G01X1630793Y881906D02*
X1630706Y881650D01*
G01X1629574Y882418D02*
X1629661Y882674D01*
G01X1630358Y880797D02*
X1630706Y880882D01*
G01X1632013Y880541D02*
X1632362Y880627D01*
G01X1632623Y881735D02*
X1632536Y881394D01*
G01X1631229Y881565D02*
X1631316Y881906D01*
G01Y882418D02*
X1631403Y882759D01*
G01X1624992Y871835D02*
X1624925Y871530D01*
G01X1633058Y881309D02*
X1633146Y881735D01*
G01X1630881Y882844D02*
X1630793Y882418D01*
G01X1629138Y882759D02*
X1629051Y882333D01*
G01X1624113Y871530D02*
X1624199Y872007D01*
X1624447Y872450D01*
X1624835Y872801D01*
X1625342Y873021D01*
X1625919Y873077D01*
X1626483Y872955D01*
X1626959Y872673D01*
X1627298Y872268D01*
X1627478Y871811D01*
X1627493Y871331D01*
X1627336Y870861D01*
X1627021Y870444D01*
G01X1626984Y920226D02*
X1620959D01*
G01X1626077Y920029D02*
X1625093D01*
G01X1626077Y919833D02*
X1625093D01*
G01X1619095Y919714D02*
X1620978D01*
G01X1615931Y919636D02*
X1608598D01*
G01X1628087D02*
X1616078D01*
G01Y918848D02*
X1628087D01*
G01X1608598D02*
X1615931D01*
G01X1626077Y918651D02*
X1625093D01*
G01X1626077Y918455D02*
X1625093D01*
G01X1626984Y918258D02*
X1620959D01*
G01X1626984Y917077D02*
X1620959D01*
G01X1626077Y916880D02*
X1625093D01*
G01X1626077Y916683D02*
X1625093D01*
G01X1615931Y916486D02*
X1608598D01*
G01X1628087D02*
X1616078D01*
G01X1625093Y916388D02*
X1622968D01*
G01X1620552Y915896D02*
X1628087D01*
G01X1652326Y915797D02*
X1630134D01*
G01X1628087Y915777D02*
X1626984D01*
G01X1656827D02*
X1638323D01*
G01X1616078Y915699D02*
X1628087D01*
G01X1608598D02*
X1615931D01*
G01X1624543Y914616D02*
X1623559D01*
G01X1624543Y914419D02*
X1623559D01*
G01X1624543Y914025D02*
X1623559D01*
G01X1619425Y913829D02*
X1626590D01*
G01X1656827Y913435D02*
X1630134D01*
G01X1615931Y913337D02*
X1608598D01*
G01X1628087D02*
X1616078D01*
G01Y912549D02*
X1628087D01*
G01X1608598D02*
X1615931D01*
G01X1619425Y912254D02*
X1626590D01*
G01X1624543Y912057D02*
X1623559D01*
G01X1624543Y911663D02*
X1623559D01*
G01X1624543Y911466D02*
X1623559D01*
G01X1615931Y910187D02*
X1608598D01*
G01X1628087D02*
X1616078D01*
G01X1624543Y909616D02*
X1623559D01*
G01X1657784Y909439D02*
X1638323D01*
G01X1624543Y909419D02*
X1623559D01*
G01X1616078Y909400D02*
X1628087D01*
G01X1608598D02*
X1615931D01*
G01X1624543Y909025D02*
X1623559D01*
G01X1619425Y908829D02*
X1626590D01*
G01X1619425Y907254D02*
X1626590D01*
G01X1624543Y907057D02*
X1623559D01*
G01X1615931Y907037D02*
X1608598D01*
G01X1628087D02*
X1616078D01*
G01X1624543Y906663D02*
X1623559D01*
G01X1624543Y906466D02*
X1623559D01*
G01X1616078Y906250D02*
X1628087D01*
G01X1608598D02*
X1615931D01*
G01X1624543Y904616D02*
X1623559D01*
G01X1624543Y904419D02*
X1623559D01*
G01X1624543Y904025D02*
X1623559D01*
G01X1615931Y903888D02*
X1608598D01*
G01X1628087D02*
X1616078D01*
G01X1619425Y903829D02*
X1626590D01*
G01X1616078Y903100D02*
X1628087D01*
G01X1608598D02*
X1615931D01*
G01X1619425Y902254D02*
X1626590D01*
G01X1624543Y902057D02*
X1623559D01*
G01X1624543Y901663D02*
X1623559D01*
G01X1624543Y901466D02*
X1623559D01*
G01X1615931Y900738D02*
X1608598D01*
G01X1628087D02*
X1616078D01*
G01Y899951D02*
X1628087D01*
G01X1608598D02*
X1615931D01*
G01X1624543Y899616D02*
X1623559D01*
G01X1624543Y899419D02*
X1623559D01*
G01X1624543Y899025D02*
X1623559D01*
G01X1619425Y898829D02*
X1626590D01*
G01X1656827Y898199D02*
X1630134D01*
G01X1615931Y897588D02*
X1608598D01*
G01X1628087D02*
X1616078D01*
G01X1619425Y897254D02*
X1626590D01*
G01X1624543Y897057D02*
X1623559D01*
G01X1616078Y896801D02*
X1628087D01*
G01X1608598D02*
X1615931D01*
G01X1624543Y896663D02*
X1623559D01*
G01X1624543Y896466D02*
X1623559D01*
G01X1656827Y895837D02*
X1630134D01*
G01X1624543Y894616D02*
X1623559D01*
G01X1615931Y894439D02*
X1608598D01*
G01X1628087D02*
X1616078D01*
G01X1624543Y894419D02*
X1623559D01*
G01X1624543Y894025D02*
X1623559D01*
G01X1619425Y893829D02*
X1626590D01*
G01X1616078Y893651D02*
X1628087D01*
G01X1608598D02*
X1615931D01*
G01X1619425Y892254D02*
X1626590D01*
G01X1624543Y892057D02*
X1623559D01*
G01X1624543Y891663D02*
X1623559D01*
G01X1624543Y891466D02*
X1623559D01*
G01X1615931Y891289D02*
X1608598D01*
G01X1628087D02*
X1616078D01*
G01Y890502D02*
X1628087D01*
G01X1608598D02*
X1615931D01*
G01X1624543Y889616D02*
X1623559D01*
G01X1624543Y889419D02*
X1623559D01*
G01X1638323Y1011860D02*
Y879222D01*
G01X1636669Y853022D02*
Y879419D01*
G01X1636354Y880010D02*
Y878238D01*
G01X1634386Y865955D02*
Y874301D01*
G01X1633146Y881735D02*
Y882418D01*
G01Y885403D02*
Y884892D01*
G01X1632749Y872416D02*
Y873081D01*
G01X1632623Y882418D02*
Y881735D01*
G01X1632102Y895837D02*
Y879419D01*
G01Y913435D02*
Y898199D01*
G01Y935285D02*
Y915797D01*
G01X1632013Y881053D02*
Y880541D01*
G01X1631316Y881906D02*
Y882418D01*
G01X1631271Y858140D02*
Y859714D01*
G01X1631236D02*
Y858140D01*
G01X1631212Y859714D02*
Y858140D01*
G01X1630793Y882418D02*
Y881906D01*
G01X1630449Y871703D02*
Y867923D01*
G01Y876112D02*
Y873671D01*
G01X1630134Y879419D02*
Y1011663D01*
G01X1630009Y882930D02*
Y883442D01*
G01X1629889Y858140D02*
Y859714D01*
G01X1629574Y881906D02*
Y882418D01*
G01X1629519Y859714D02*
Y858140D01*
G01X1629051Y884892D02*
Y885403D01*
G01Y882333D02*
Y881906D01*
G01X1628911Y873081D02*
Y872342D01*
G01X1628087Y1014478D02*
Y876604D01*
G01X1627730Y867175D02*
Y867913D01*
G01X1627442Y858140D02*
Y859714D01*
G01X1627072D02*
Y858140D01*
G01X1626984Y877057D02*
Y1014025D01*
G01X1626905Y935187D02*
Y915896D01*
G01X1626590D02*
Y935187D01*
G01X1626531Y882077D02*
Y884045D01*
G01X1626145Y915699D02*
Y916486D01*
G01Y918848D02*
Y919636D01*
G01Y912549D02*
Y913337D01*
G01Y906250D02*
Y907037D01*
G01Y909400D02*
Y910187D01*
G01Y903100D02*
Y903888D01*
G01Y896801D02*
Y897588D01*
G01Y899951D02*
Y900738D01*
G01Y893651D02*
Y894439D01*
G01Y890502D02*
Y891289D01*
G01Y884203D02*
Y884990D01*
G01Y887352D02*
Y888140D01*
G01X1626118Y915699D02*
Y916486D01*
G01Y918848D02*
Y919636D01*
G01Y912549D02*
Y913337D01*
G01Y906250D02*
Y907037D01*
G01Y909400D02*
Y910187D01*
G01Y903100D02*
Y903888D01*
G01Y896801D02*
Y897588D01*
G01Y899951D02*
Y900738D01*
G01Y893651D02*
Y894439D01*
G01Y890502D02*
Y891289D01*
G01Y884203D02*
Y884990D01*
G01Y887352D02*
Y888140D01*
G01X1626077Y918848D02*
Y916486D01*
G01Y921998D02*
Y919636D01*
G01X1625803Y935187D02*
Y915896D01*
G01X1625748Y858140D02*
Y859714D01*
G01X1625742Y915699D02*
Y916486D01*
G01Y918848D02*
Y919636D01*
G01Y912549D02*
Y913337D01*
G01Y906250D02*
Y907037D01*
G01Y909400D02*
Y910187D01*
G01Y903100D02*
Y903888D01*
G01Y896801D02*
Y897588D01*
G01Y899951D02*
Y900738D01*
G01Y893651D02*
Y894439D01*
G01Y890502D02*
Y891289D01*
G01Y884203D02*
Y884990D01*
G01Y887352D02*
Y888140D01*
G01X1625724Y858140D02*
Y859714D01*
G01X1625689D02*
Y858140D01*
G01X1625527Y883829D02*
Y882254D01*
G01Y888829D02*
Y887254D01*
G01Y893829D02*
Y892254D01*
G01Y898829D02*
Y897254D01*
G01Y903829D02*
Y902254D01*
G01Y908829D02*
Y907254D01*
G01Y913829D02*
Y912254D01*
G01X1625303Y935187D02*
Y915896D01*
G01X1625093Y916388D02*
Y934695D01*
G01X1624925Y871383D02*
Y871530D01*
G01X1624543Y876604D02*
Y874301D01*
G01Y884616D02*
Y881466D01*
G01Y889616D02*
Y886466D01*
G01Y894616D02*
Y891466D01*
G01Y899616D02*
Y896466D01*
G01Y904616D02*
Y901466D01*
G01Y909616D02*
Y906466D01*
G01Y914616D02*
Y911466D01*
G01X1624386Y915896D02*
Y935187D01*
G01X1624113Y871530D02*
Y871383D01*
G01X1624109Y918258D02*
Y917077D01*
G01Y921407D02*
Y920226D01*
G01X1623817Y867618D02*
Y867175D01*
G01X1623559Y884616D02*
Y881466D01*
G01Y889616D02*
Y886466D01*
G01Y894616D02*
Y891466D01*
G01Y899616D02*
Y896466D01*
G01Y904616D02*
Y901466D01*
G01Y909616D02*
Y906466D01*
G01Y914616D02*
Y911466D01*
G01X1622968Y877057D02*
Y1014025D01*
G01X1622575Y883829D02*
Y882254D01*
G01Y888829D02*
Y887254D01*
G01Y893829D02*
Y892254D01*
G01Y898829D02*
Y897254D01*
G01Y903829D02*
Y902254D01*
G01Y908829D02*
Y907254D01*
G01Y913829D02*
Y912254D01*
G01X1622514Y879636D02*
Y1011250D01*
G01X1622380Y884990D02*
Y884203D01*
G01Y888140D02*
Y887352D01*
G01Y891289D02*
Y890502D01*
G01Y894439D02*
Y893651D01*
G01Y897588D02*
Y896801D01*
G01Y900738D02*
Y899951D01*
G01Y903888D02*
Y903100D01*
G01Y907037D02*
Y906250D01*
G01Y910187D02*
Y909400D01*
G01Y913337D02*
Y912549D01*
G01Y916486D02*
Y915699D01*
G01Y919636D02*
Y918848D01*
G01X1621987Y876663D02*
Y876604D01*
G01X1621348Y874301D02*
Y877057D01*
G01X1621030Y915896D02*
Y935187D01*
G01X1620978Y921919D02*
Y919714D01*
G01X1620959Y918258D02*
Y917077D01*
G01Y921407D02*
Y920226D01*
G01X1620552Y915896D02*
Y919714D01*
G01X1620396Y884990D02*
Y884203D01*
G01Y888140D02*
Y887352D01*
G01Y891289D02*
Y890502D01*
G01Y894439D02*
Y893651D01*
G01Y897588D02*
Y896801D01*
G01Y900738D02*
Y899951D01*
G01Y903888D02*
Y903100D01*
G01Y907037D02*
Y906250D01*
G01Y910187D02*
Y909400D01*
G01Y913337D02*
Y912549D01*
G01Y916486D02*
Y915699D01*
G01Y919636D02*
Y918848D01*
G01X1620291Y865955D02*
Y853022D01*
G01X1619425Y883829D02*
Y882254D01*
G01Y888829D02*
Y887254D01*
G01Y893829D02*
Y892254D01*
G01Y898829D02*
Y897254D01*
G01Y903829D02*
Y902254D01*
G01Y908829D02*
Y907254D01*
G01Y913829D02*
Y912254D01*
G01X1619095Y919714D02*
Y921919D01*
G01X1618745Y915699D02*
Y916486D01*
G01Y918848D02*
Y919636D01*
G01Y912549D02*
Y913337D01*
G01Y906250D02*
Y907037D01*
G01Y909400D02*
Y910187D01*
G01Y903100D02*
Y903888D01*
G01Y896801D02*
Y897588D01*
G01Y899951D02*
Y900738D01*
G01Y893651D02*
Y894439D01*
G01Y890502D02*
Y891289D01*
G01Y884203D02*
Y884990D01*
G01Y887352D02*
Y888140D01*
G01X1618461Y884045D02*
Y882077D01*
G01X1617016Y887352D02*
Y884990D01*
G01Y884203D02*
Y881624D01*
G01Y890502D02*
Y888140D01*
G01Y893651D02*
Y891289D01*
G01Y896801D02*
Y894439D01*
G01Y899951D02*
Y897588D01*
G01Y903100D02*
Y900738D01*
G01Y906250D02*
Y903888D01*
G01Y909400D02*
Y907037D01*
G01Y912549D02*
Y910187D01*
G01Y915699D02*
Y913337D01*
G01Y918848D02*
Y916486D01*
G01Y921998D02*
Y919636D01*
G01X1616078Y915699D02*
Y916486D01*
G01Y918848D02*
Y919636D01*
G01Y912549D02*
Y913337D01*
G01Y906250D02*
Y907037D01*
G01Y909400D02*
Y910187D01*
G01Y903100D02*
Y903888D01*
G01Y896801D02*
Y897588D01*
G01Y899951D02*
Y900738D01*
G01Y893651D02*
Y894439D01*
G01Y890502D02*
Y891289D01*
G01Y884203D02*
Y884990D01*
G01Y887352D02*
Y888140D01*
G01X1615931Y915699D02*
Y916486D01*
G01Y918848D02*
Y919636D01*
G01Y912549D02*
Y913337D01*
G01Y906250D02*
Y907037D01*
G01Y909400D02*
Y910187D01*
G01Y903100D02*
Y903888D01*
G01Y896801D02*
Y897588D01*
G01Y899951D02*
Y900738D01*
G01Y893651D02*
Y894439D01*
G01Y890502D02*
Y891289D01*
G01Y884203D02*
Y884990D01*
G01Y887352D02*
Y888140D01*
G01X1614338Y915699D02*
Y916486D01*
G01Y918848D02*
Y919636D01*
G01Y912549D02*
Y913337D01*
G01Y906250D02*
Y907037D01*
G01Y909400D02*
Y910187D01*
G01Y903100D02*
Y903888D01*
G01Y896801D02*
Y897588D01*
G01Y899951D02*
Y900738D01*
G01Y893651D02*
Y894439D01*
G01Y890502D02*
Y891289D01*
G01Y884203D02*
Y884990D01*
G01Y887352D02*
Y888140D01*
G01X1613984Y1014025D02*
Y877057D01*
G01X1613474Y874301D02*
Y877057D01*
G01X1613397Y884990D02*
Y884203D01*
G01Y888140D02*
Y887352D01*
G01Y891289D02*
Y890502D01*
G01Y894439D02*
Y893651D01*
G01Y897588D02*
Y896801D01*
G01Y900738D02*
Y899951D01*
G01Y903888D02*
Y903100D01*
G01Y907037D02*
Y906250D01*
G01Y910187D02*
Y909400D01*
G01Y913337D02*
Y912549D01*
G01Y916486D02*
Y915699D01*
G01Y919636D02*
Y918848D01*
G01X1612302Y872416D02*
Y873081D01*
G01X1610560Y884990D02*
Y884203D01*
G01Y888140D02*
Y887352D01*
G01Y891289D02*
Y890502D01*
G01Y894439D02*
Y893651D01*
G01Y897588D02*
Y896801D01*
G01Y900738D02*
Y899951D01*
G01Y903888D02*
Y903100D01*
G01Y907037D02*
Y906250D01*
G01Y910187D02*
Y909400D01*
G01Y913337D02*
Y912549D01*
G01Y916486D02*
Y915699D01*
G01Y919636D02*
Y918848D01*
G01X1610372Y915699D02*
Y916486D01*
G01Y918848D02*
Y919636D01*
G01Y912549D02*
Y913337D01*
G01Y906250D02*
Y907037D01*
G01Y909400D02*
Y910187D01*
G01Y903100D02*
Y903888D01*
G01Y896801D02*
Y897588D01*
G01Y899951D02*
Y900738D01*
G01Y893651D02*
Y894439D01*
G01Y890502D02*
Y891289D01*
G01Y884203D02*
Y884990D01*
G01Y887352D02*
Y888140D01*
G01X1608598Y915699D02*
Y916486D01*
G01Y918848D02*
Y919636D01*
G01Y912549D02*
Y913337D01*
G01Y906250D02*
Y907037D01*
G01Y909400D02*
Y910187D01*
G01Y903100D02*
Y903888D01*
G01Y896801D02*
Y897588D01*
G01Y899951D02*
Y900738D01*
G01Y893651D02*
Y894439D01*
G01Y890502D02*
Y891289D01*
G01Y884203D02*
Y884990D01*
G01Y887352D02*
Y888140D01*
G01X1608463Y873081D02*
Y872342D01*
G01X1607619Y879636D02*
Y877057D01*
G01X1607144Y879636D02*
Y874301D01*
G01X1606827Y879636D02*
Y865955D01*
G01X1633146Y882418D02*
X1633058Y882844D01*
G01X1632536Y882759D02*
X1632623Y882418D01*
G01X1629051Y881906D02*
X1629138Y881565D01*
G01X1629661Y881650D02*
X1629574Y881906D01*
G01X1625823Y872342D02*
X1626170Y872273D01*
G01X1624543Y889025D02*
X1623559D01*
G01X1619425Y888829D02*
X1626590D01*
G01X1615931Y888140D02*
X1608598D01*
G01X1628087D02*
X1616078D01*
G01Y887352D02*
X1628087D01*
G01X1608598D02*
X1615931D01*
G01X1619425Y887254D02*
X1626590D01*
G01X1624543Y887057D02*
X1623559D01*
G01X1624543Y886663D02*
X1623559D01*
G01X1624543Y886466D02*
X1623559D01*
G01X1629051Y885403D02*
X1633146D01*
G01X1615931Y884990D02*
X1608598D01*
G01X1628087D02*
X1616078D01*
G01X1633146Y884892D02*
X1629748D01*
G01X1624543Y884616D02*
X1623559D01*
G01X1624543Y884419D02*
X1623559D01*
G01X1630358Y884380D02*
X1629661D01*
G01X1616078Y884203D02*
X1628087D01*
G01X1608598D02*
X1615931D01*
G01X1626531Y884045D02*
X1618461D01*
G01X1624543Y884025D02*
X1623559D01*
G01X1619425Y883829D02*
X1626590D01*
G01X1632187Y883697D02*
X1631752D01*
G01X1631839Y883186D02*
X1632100D01*
G01X1619425Y882254D02*
X1626590D01*
G01X1618461Y882077D02*
X1626531D01*
G01X1624543Y882057D02*
X1623559D01*
G01X1624543Y881663D02*
X1623559D01*
G01X1622968Y881624D02*
X1613984D01*
G01X1624543Y881466D02*
X1623559D01*
G01X1630271Y881309D02*
X1630096D01*
G01X1630009Y880797D02*
X1630358D01*
G01X1626984Y880010D02*
X1636354D01*
G01X1626984Y879636D02*
X1606827D01*
G01X1636669Y879419D02*
X1630134D01*
G01X1656827Y879222D02*
X1638323D01*
G01X1628087Y878829D02*
X1658795D01*
G01X1626984Y878238D02*
X1636354D01*
G01X1607619Y877057D02*
X1628087D01*
G01X1621987Y876663D02*
X1628087D01*
G01Y876604D02*
X1621987D01*
G01X1630449Y876112D02*
X1606827D01*
G01X1656827Y874301D02*
X1606827D01*
G01Y873671D02*
X1630449D01*
G01X1612302Y873081D02*
X1608463D01*
G01X1632749D02*
X1628911D01*
G01Y872342D02*
X1631864D01*
G01X1608463D02*
X1611416D01*
G01X1630449Y871703D02*
X1606827D01*
G01X1624113Y871383D02*
X1624925D01*
G01X1630449Y867923D02*
X1606827D01*
G01X1627730Y867913D02*
X1624851D01*
G01X1629649Y867175D02*
X1630535D01*
G01X1623817D02*
X1627730D01*
G01X1609201D02*
X1610087D01*
G01X1634386Y867136D02*
X1660764D01*
G01Y865955D02*
X1606827D01*
G01X1636669Y863199D02*
X1620291D01*
G01X1626315Y860502D02*
X1630646D01*
G01X1625689Y859714D02*
X1631271D01*
G01Y858140D02*
X1625689D01*
G01X1630646Y857352D02*
X1626315D01*
G01X1636669Y853022D02*
X1620291D01*
G01X1633058Y882844D02*
X1632884Y883186D01*
G01X1629138Y881565D02*
X1629312Y881224D01*
G01X1621731Y877057D02*
X1621987Y876663D01*
G01X1632362Y883015D02*
X1632536Y882759D01*
G01X1629835Y881394D02*
X1629661Y881650D01*
G01X1626449Y872093D02*
X1626632Y871828D01*
X1626696Y871529D01*
X1626632Y871232D01*
G01X1619445Y870432D02*
X1619123Y870851D01*
X1618960Y871334D01*
X1618982Y871839D01*
X1619185Y872316D01*
X1619552Y872719D01*
X1620058Y872987D01*
X1620649Y873081D01*
X1621238Y872984D01*
X1621740Y872715D01*
X1622105Y872311D01*
X1622306Y871833D01*
X1622325Y871328D01*
X1622161Y870847D01*
X1621841Y870432D01*
G01X1614278D02*
X1613955Y870851D01*
X1613793Y871334D01*
X1613815Y871839D01*
X1614017Y872316D01*
X1614384Y872719D01*
X1614890Y872987D01*
X1615482Y873081D01*
X1616071Y872984D01*
X1616573Y872715D01*
X1616937Y872311D01*
X1617139Y871833D01*
X1617158Y871328D01*
X1616994Y870847D01*
X1616674Y870432D01*
G01X1632884Y883186D02*
X1632536Y883527D01*
G01X1629312Y881224D02*
X1629661Y880882D01*
G01X1621841Y870432D02*
X1622293Y869991D01*
X1622563Y869456D01*
X1622633Y868885D01*
X1622491Y868321D01*
X1622145Y867797D01*
X1621617Y867403D01*
X1620975Y867200D01*
X1620295Y867202D01*
X1619655Y867410D01*
X1619132Y867807D01*
X1618791Y868330D01*
X1618653Y868891D01*
X1618725Y869459D01*
X1618995Y869993D01*
G01X1616674Y870432D02*
X1617125Y869991D01*
X1617395Y869456D01*
X1617466Y868885D01*
X1617324Y868321D01*
X1616977Y867797D01*
X1616450Y867403D01*
X1615807Y867200D01*
X1615128Y867202D01*
X1614488Y867410D01*
X1613965Y867807D01*
X1613624Y868330D01*
X1613486Y868891D01*
X1613557Y869459D01*
X1613828Y869993D01*
G01X1629748Y884892D02*
X1630358Y884380D01*
G01X1629661D02*
X1629051Y884892D01*
G01X1621066Y869976D02*
X1621426Y869740D01*
X1621665Y869390D01*
X1621750Y868986D01*
X1621668Y868584D01*
X1621431Y868232D01*
X1621068Y867992D01*
X1620643Y867907D01*
G01X1620220Y867991D02*
X1619860Y868227D01*
X1619621Y868577D01*
X1619536Y868981D01*
X1619618Y869383D01*
X1619855Y869735D01*
X1620218Y869975D01*
X1620643Y870060D01*
G01X1615899Y869976D02*
X1616259Y869740D01*
X1616498Y869390D01*
X1616583Y868986D01*
X1616500Y868584D01*
X1616264Y868232D01*
X1615901Y867992D01*
X1615476Y867907D01*
G01X1615053Y867991D02*
X1614692Y868227D01*
X1614454Y868577D01*
X1614369Y868981D01*
X1614451Y869383D01*
X1614688Y869735D01*
X1615051Y869975D01*
X1615476Y870060D01*
G01X1632100Y883186D02*
X1632362Y883015D01*
G01X1626170Y872273D02*
X1626450Y872092D01*
G01X1620992Y872277D02*
X1621275Y872100D01*
X1621462Y871834D01*
X1621529Y871533D01*
X1621464Y871232D01*
X1621279Y870965D01*
X1620994Y870784D01*
X1620643Y870718D01*
G01X1620294Y870783D02*
X1620012Y870961D01*
X1619824Y871226D01*
X1619757Y871528D01*
X1619822Y871829D01*
X1620007Y872095D01*
X1620293Y872277D01*
X1620643Y872342D01*
G01X1615825Y872277D02*
X1616107Y872100D01*
X1616294Y871834D01*
X1616361Y871533D01*
X1616297Y871232D01*
X1616112Y870965D01*
X1615826Y870784D01*
X1615476Y870718D01*
G01X1615127Y870783D02*
X1614844Y870961D01*
X1614657Y871226D01*
X1614590Y871528D01*
X1614654Y871829D01*
X1614840Y872095D01*
X1615125Y872277D01*
X1615476Y872342D01*
G01X1632536Y883527D02*
X1632187Y883697D01*
G01X1630096Y881309D02*
X1629835Y881394D01*
G01X1629661Y880882D02*
X1630009Y880797D01*
G01X1616078Y921998D02*
X1628087D01*
G01X1608598D02*
X1615931D01*
G01X1620978Y921919D02*
X1619095D01*
G01X1626077Y921801D02*
X1625093D01*
G01X1626077Y921604D02*
X1625093D01*
G01X1626984Y921407D02*
X1620959D01*
G01X1626145Y921998D02*
Y922785D01*
G01X1626118Y921998D02*
Y922785D01*
G01X1625742Y921998D02*
Y922785D01*
G01X1622380D02*
Y921998D01*
G01X1620552Y921919D02*
Y929163D01*
G01X1620396Y922785D02*
Y921998D01*
G01X1618745D02*
Y922785D01*
G01X1616078Y921998D02*
Y922785D01*
G01X1615931Y921998D02*
Y922785D01*
G01X1614338Y921998D02*
Y922785D01*
G01X1613397D02*
Y921998D01*
G01X1610560Y922785D02*
Y921998D01*
G01X1610372D02*
Y922785D01*
G01X1608598Y921998D02*
Y922785D01*
G01X1626590Y988829D02*
G03X1626984Y989222I0J394D01*
G01Y986860D02*
G03X1626590Y987254I-394J0D01*
G01Y958829D02*
G03X1626984Y959222I0J394D01*
G01Y956860D02*
G03X1626590Y957254I-394J0D01*
G01Y943829D02*
G03X1626984Y944222I0J394D01*
G01Y941860D02*
G03X1626590Y942254I-394J0D01*
G01Y948829D02*
G03X1626984Y949222I0J394D01*
G01Y946860D02*
G03X1626590Y947254I-394J0D01*
G01Y968829D02*
G03X1626984Y969222I0J394D01*
G01Y966860D02*
G03X1626590Y967254I-394J0D01*
G01Y973829D02*
G03X1626984Y974222I0J394D01*
G01Y971860D02*
G03X1626590Y972254I-394J0D01*
G01Y983829D02*
G03X1626984Y984222I0J394D01*
G01Y981860D02*
G03X1626590Y982254I-394J0D01*
G01Y978829D02*
G03X1626984Y979222I0J394D01*
G01Y976860D02*
G03X1626590Y977254I-394J0D01*
G01Y963829D02*
G03X1626984Y964222I0J394D01*
G01Y961860D02*
G03X1626590Y962254I-394J0D01*
G01Y938829D02*
G03X1626984Y939222I0J394D01*
G01Y936860D02*
G03X1626590Y937254I-394J0D01*
G01X1626984Y992254D02*
X1621394D01*
G01X1615931Y992077D02*
X1608598D01*
G01X1628087D02*
X1616078D01*
G01X1626512Y992057D02*
X1625527D01*
G01X1656827Y991781D02*
X1630134D01*
G01X1626512Y991663D02*
X1625527D01*
G01X1626512Y991466D02*
X1625527D01*
G01X1616078Y991289D02*
X1628087D01*
G01X1608598D02*
X1615931D01*
G01X1628087Y990837D02*
X1626984D01*
G01X1624543Y989616D02*
X1623559D01*
G01X1624543Y989419D02*
X1623559D01*
G01X1624543Y989025D02*
X1623559D01*
G01X1615931Y988927D02*
X1608598D01*
G01X1628087D02*
X1616078D01*
G01X1619425Y988829D02*
X1626590D01*
G01X1616078Y988140D02*
X1628087D01*
G01X1608598D02*
X1615931D01*
G01X1619425Y987254D02*
X1626590D01*
G01X1624543Y987057D02*
X1623559D01*
G01X1624543Y986663D02*
X1623559D01*
G01X1624543Y986466D02*
X1623559D01*
G01X1615931Y985777D02*
X1608598D01*
G01X1628087D02*
X1616078D01*
G01Y984990D02*
X1628087D01*
G01X1608598D02*
X1615931D01*
G01X1624543Y984616D02*
X1623559D01*
G01X1624543Y984419D02*
X1623559D01*
G01X1624543Y984025D02*
X1623559D01*
G01X1619425Y983829D02*
X1626590D01*
G01X1615931Y982628D02*
X1608598D01*
G01X1628087D02*
X1616078D01*
G01X1619425Y982254D02*
X1626590D01*
G01X1624543Y982057D02*
X1623559D01*
G01X1616078Y981840D02*
X1628087D01*
G01X1608598D02*
X1615931D01*
G01X1624543Y981663D02*
X1623559D01*
G01X1624543Y981466D02*
X1623559D01*
G01X1624543Y979616D02*
X1623559D01*
G01X1615931Y979478D02*
X1608598D01*
G01X1628087D02*
X1616078D01*
G01X1624543Y979419D02*
X1623559D01*
G01X1624543Y979025D02*
X1623559D01*
G01X1619425Y978829D02*
X1626590D01*
G01X1616078Y978691D02*
X1628087D01*
G01X1608598D02*
X1615931D01*
G01X1619425Y977254D02*
X1626590D01*
G01X1624543Y977057D02*
X1623559D01*
G01X1624543Y976663D02*
X1623559D01*
G01X1624543Y976466D02*
X1623559D01*
G01X1615931Y976329D02*
X1608598D01*
G01X1628087D02*
X1616078D01*
G01Y975541D02*
X1628087D01*
G01X1608598D02*
X1615931D01*
G01X1656827Y975246D02*
X1630134D01*
G01X1624543Y974616D02*
X1623559D01*
G01X1624543Y974419D02*
X1623559D01*
G01X1624543Y974025D02*
X1623559D01*
G01X1619425Y973829D02*
X1626590D01*
G01X1615931Y973179D02*
X1608598D01*
G01X1628087D02*
X1616078D01*
G01X1656827Y972884D02*
X1630134D01*
G01X1616078Y972392D02*
X1628087D01*
G01X1608598D02*
X1615931D01*
G01X1619425Y972254D02*
X1626590D01*
G01X1624543Y972057D02*
X1623559D01*
G01X1624543Y971663D02*
X1623559D01*
G01X1624543Y971466D02*
X1623559D01*
G01X1615931Y970029D02*
X1608598D01*
G01X1628087D02*
X1616078D01*
G01X1624543Y969616D02*
X1623559D01*
G01X1624543Y969419D02*
X1623559D01*
G01X1616078Y969242D02*
X1628087D01*
G01X1608598D02*
X1615931D01*
G01X1624543Y969025D02*
X1623559D01*
G01X1619425Y968829D02*
X1626590D01*
G01X1619425Y967254D02*
X1626590D01*
G01X1624543Y967057D02*
X1623559D01*
G01X1615931Y966880D02*
X1608598D01*
G01X1628087D02*
X1616078D01*
G01X1624543Y966663D02*
X1623559D01*
G01X1624543Y966466D02*
X1623559D01*
G01X1616078Y966092D02*
X1628087D01*
G01X1608598D02*
X1615931D01*
G01X1624543Y964616D02*
X1623559D01*
G01X1624543Y964419D02*
X1623559D01*
G01X1624543Y964025D02*
X1623559D01*
G01X1619425Y963829D02*
X1626590D01*
G01X1615931Y963730D02*
X1608598D01*
G01X1628087D02*
X1616078D01*
G01Y962943D02*
X1628087D01*
G01X1608598D02*
X1615931D01*
G01X1619425Y962254D02*
X1626590D01*
G01X1624543Y962057D02*
X1623559D01*
G01X1624543Y961663D02*
X1623559D01*
G01X1624543Y961466D02*
X1623559D01*
G01X1615931Y960581D02*
X1608598D01*
G01X1628087D02*
X1616078D01*
G01Y959793D02*
X1628087D01*
G01X1608598D02*
X1615931D01*
G01X1624543Y959616D02*
X1623559D01*
G01X1624543Y959419D02*
X1623559D01*
G01X1624543Y959025D02*
X1623559D01*
G01X1619425Y958829D02*
X1626590D01*
G01X1615931Y957431D02*
X1608598D01*
G01X1628087D02*
X1616078D01*
G01X1619425Y957254D02*
X1626590D01*
G01X1624543Y957057D02*
X1623559D01*
G01X1624543Y956663D02*
X1623559D01*
G01X1616078Y956644D02*
X1628087D01*
G01X1608598D02*
X1615931D01*
G01X1624543Y956466D02*
X1623559D01*
G01X1656827Y956348D02*
X1630134D01*
G01X1626984Y955246D02*
X1628087D01*
G01X1626512Y954616D02*
X1625527D01*
G01X1626512Y954419D02*
X1625527D01*
G01X1615931Y954281D02*
X1608598D01*
G01X1628087D02*
X1616078D01*
G01X1626512Y954025D02*
X1625527D01*
G01X1656827Y953986D02*
X1630134D01*
G01X1626984Y953829D02*
X1621394D01*
G01X1616078Y953494D02*
X1628087D01*
G01X1608598D02*
X1615931D01*
G01X1626984Y952254D02*
X1621394D01*
G01X1626512Y952057D02*
X1625527D01*
G01X1626512Y951663D02*
X1625527D01*
G01X1626512Y951466D02*
X1625527D01*
G01X1615931Y951132D02*
X1608598D01*
G01X1628087D02*
X1616078D01*
G01X1628087Y950837D02*
X1626984D01*
G01X1616078Y950344D02*
X1628087D01*
G01X1608598D02*
X1615931D01*
G01X1624543Y949616D02*
X1623559D01*
G01X1624543Y949419D02*
X1623559D01*
G01X1624543Y949025D02*
X1623559D01*
G01X1619425Y948829D02*
X1626590D01*
G01X1615931Y947982D02*
X1608598D01*
G01X1628087D02*
X1616078D01*
G01X1619425Y947254D02*
X1626590D01*
G01X1616078Y947195D02*
X1628087D01*
G01X1608598D02*
X1615931D01*
G01X1624543Y947057D02*
X1623559D01*
G01X1624543Y946663D02*
X1623559D01*
G01X1624543Y946466D02*
X1623559D01*
G01X1615931Y944833D02*
X1608598D01*
G01X1628087D02*
X1616078D01*
G01X1624543Y944616D02*
X1623559D01*
G01X1624543Y944419D02*
X1623559D01*
G01X1616078Y944045D02*
X1628087D01*
G01X1608598D02*
X1615931D01*
G01X1624543Y944025D02*
X1623559D01*
G01X1619425Y943829D02*
X1626590D01*
G01X1619425Y942254D02*
X1626590D01*
G01X1624543Y942057D02*
X1623559D01*
G01X1657784Y941742D02*
X1638323D01*
G01X1615931Y941683D02*
X1608598D01*
G01X1628087D02*
X1616078D01*
G01X1624543Y941663D02*
X1623559D01*
G01X1624543Y941466D02*
X1623559D01*
G01X1616078Y940896D02*
X1628087D01*
G01X1608598D02*
X1615931D01*
G01X1624543Y939616D02*
X1623559D01*
G01X1624543Y939419D02*
X1623559D01*
G01X1624543Y939025D02*
X1623559D01*
G01X1619425Y938829D02*
X1626590D01*
G01X1615931Y938533D02*
X1608598D01*
G01X1628087D02*
X1616078D01*
G01Y937746D02*
X1628087D01*
G01X1608598D02*
X1615931D01*
G01X1656827Y937648D02*
X1630134D01*
G01X1619425Y937254D02*
X1626590D01*
G01X1624543Y937057D02*
X1623559D01*
G01X1624543Y936663D02*
X1623559D01*
G01X1624543Y936466D02*
X1623559D01*
G01X1615931Y935384D02*
X1608598D01*
G01X1628087D02*
X1616078D01*
G01X1638323Y935305D02*
X1656827D01*
G01X1628087D02*
X1626984D01*
G01X1652326Y935285D02*
X1630134D01*
G01X1628087Y935187D02*
X1620552D01*
G01X1625093Y934695D02*
X1622968D01*
G01X1616078Y934596D02*
X1628087D01*
G01X1608598D02*
X1615931D01*
G01X1626077Y934400D02*
X1625093D01*
G01X1626077Y934203D02*
X1625093D01*
G01X1626984Y934006D02*
X1620959D01*
G01X1626984Y932825D02*
X1620959D01*
G01X1626077Y932628D02*
X1625093D01*
G01X1626077Y932431D02*
X1625093D01*
G01X1615931Y932234D02*
X1608598D01*
G01X1628087D02*
X1616078D01*
G01Y931447D02*
X1628087D01*
G01X1608598D02*
X1615931D01*
G01X1620978Y931368D02*
X1619095D01*
G01X1626077Y931250D02*
X1625093D01*
G01X1626077Y931053D02*
X1625093D01*
G01X1626984Y930856D02*
X1620959D01*
G01X1626984Y929675D02*
X1620959D01*
G01X1626077Y929478D02*
X1625093D01*
G01X1626077Y929281D02*
X1625093D01*
G01X1619095Y929163D02*
X1620978D01*
G01X1615931Y929085D02*
X1608598D01*
G01X1628087D02*
X1616078D01*
G01Y928297D02*
X1628087D01*
G01X1608598D02*
X1615931D01*
G01X1626077Y928100D02*
X1625093D01*
G01X1626077Y927903D02*
X1625093D01*
G01X1626984Y927707D02*
X1620959D01*
G01X1626984Y926525D02*
X1620959D01*
G01X1626077Y926329D02*
X1625093D01*
G01X1626077Y926132D02*
X1625093D01*
G01X1615931Y925935D02*
X1608598D01*
G01X1628087D02*
X1616078D01*
G01Y925148D02*
X1628087D01*
G01X1608598D02*
X1615931D01*
G01X1626077Y924951D02*
X1625093D01*
G01X1626077Y924754D02*
X1625093D01*
G01X1626984Y924557D02*
X1620959D01*
G01X1626984Y923376D02*
X1620959D01*
G01X1626077Y923179D02*
X1625093D01*
G01X1626077Y922982D02*
X1625093D01*
G01X1615931Y922785D02*
X1608598D01*
G01X1628087D02*
X1616078D01*
G01X1632102Y975246D02*
Y991781D01*
G01Y956348D02*
Y972884D01*
G01Y937648D02*
Y953986D01*
G01X1626512Y954616D02*
Y951466D01*
G01Y994616D02*
Y991466D01*
G01X1626145Y991289D02*
Y992077D01*
G01Y988140D02*
Y988927D01*
G01Y981840D02*
Y982628D01*
G01Y984990D02*
Y985777D01*
G01Y978691D02*
Y979478D01*
G01Y972392D02*
Y973179D01*
G01Y975541D02*
Y976329D01*
G01Y969242D02*
Y970029D01*
G01Y962943D02*
Y963730D01*
G01Y966092D02*
Y966880D01*
G01Y959793D02*
Y960581D01*
G01Y953494D02*
Y954281D01*
G01Y956644D02*
Y957431D01*
G01Y950344D02*
Y951132D01*
G01Y944045D02*
Y944833D01*
G01Y947195D02*
Y947982D01*
G01Y940896D02*
Y941683D01*
G01Y934596D02*
Y935384D01*
G01Y937746D02*
Y938533D01*
G01Y931447D02*
Y932234D01*
G01Y925148D02*
Y925935D01*
G01Y928297D02*
Y929085D01*
G01X1626118Y991289D02*
Y992077D01*
G01Y988140D02*
Y988927D01*
G01Y981840D02*
Y982628D01*
G01Y984990D02*
Y985777D01*
G01Y978691D02*
Y979478D01*
G01Y972392D02*
Y973179D01*
G01Y975541D02*
Y976329D01*
G01Y969242D02*
Y970029D01*
G01Y962943D02*
Y963730D01*
G01Y966092D02*
Y966880D01*
G01Y959793D02*
Y960581D01*
G01Y953494D02*
Y954281D01*
G01Y956644D02*
Y957431D01*
G01Y950344D02*
Y951132D01*
G01Y944045D02*
Y944833D01*
G01Y947195D02*
Y947982D01*
G01Y940896D02*
Y941683D01*
G01Y934596D02*
Y935384D01*
G01Y937746D02*
Y938533D01*
G01Y931447D02*
Y932234D01*
G01Y925148D02*
Y925935D01*
G01Y928297D02*
Y929085D01*
G01X1626077Y925148D02*
Y922785D01*
G01Y928297D02*
Y925935D01*
G01Y931447D02*
Y929085D01*
G01Y934596D02*
Y932234D01*
G01X1625742Y991289D02*
Y992077D01*
G01Y988140D02*
Y988927D01*
G01Y981840D02*
Y982628D01*
G01Y984990D02*
Y985777D01*
G01Y978691D02*
Y979478D01*
G01Y972392D02*
Y973179D01*
G01Y975541D02*
Y976329D01*
G01Y969242D02*
Y970029D01*
G01Y962943D02*
Y963730D01*
G01Y966092D02*
Y966880D01*
G01Y959793D02*
Y960581D01*
G01Y953494D02*
Y954281D01*
G01Y956644D02*
Y957431D01*
G01Y950344D02*
Y951132D01*
G01Y944045D02*
Y944833D01*
G01Y947195D02*
Y947982D01*
G01Y940896D02*
Y941683D01*
G01Y934596D02*
Y935384D01*
G01Y937746D02*
Y938533D01*
G01Y931447D02*
Y932234D01*
G01Y925148D02*
Y925935D01*
G01Y928297D02*
Y929085D01*
G01X1625527Y938829D02*
Y937254D01*
G01Y943829D02*
Y942254D01*
G01Y948829D02*
Y947254D01*
G01Y954616D02*
Y951466D01*
G01Y958829D02*
Y957254D01*
G01Y963829D02*
Y962254D01*
G01Y968829D02*
Y967254D01*
G01Y973829D02*
Y972254D01*
G01Y978829D02*
Y977254D01*
G01Y983829D02*
Y982254D01*
G01Y988829D02*
Y987254D01*
G01Y994616D02*
Y991466D01*
G01X1624543Y939616D02*
Y936466D01*
G01Y944616D02*
Y941466D01*
G01Y949616D02*
Y946466D01*
G01Y953829D02*
Y952254D01*
G01Y959616D02*
Y956466D01*
G01Y964616D02*
Y961466D01*
G01Y969616D02*
Y966466D01*
G01Y974616D02*
Y971466D01*
G01Y979616D02*
Y976466D01*
G01Y984616D02*
Y981466D01*
G01Y989616D02*
Y986466D01*
G01Y993829D02*
Y992254D01*
G01X1624109Y924557D02*
Y923376D01*
G01Y927707D02*
Y926525D01*
G01Y934006D02*
Y932825D01*
G01Y930856D02*
Y929675D01*
G01X1623559Y939616D02*
Y936466D01*
G01Y944616D02*
Y941466D01*
G01Y949616D02*
Y946466D01*
G01Y959616D02*
Y956466D01*
G01Y964616D02*
Y961466D01*
G01Y969616D02*
Y966466D01*
G01Y974616D02*
Y971466D01*
G01Y979616D02*
Y976466D01*
G01Y984616D02*
Y981466D01*
G01Y989616D02*
Y986466D01*
G01X1622575Y938829D02*
Y937254D01*
G01Y943829D02*
Y942254D01*
G01Y948829D02*
Y947254D01*
G01Y958829D02*
Y957254D01*
G01Y963829D02*
Y962254D01*
G01Y968829D02*
Y967254D01*
G01Y973829D02*
Y972254D01*
G01Y978829D02*
Y977254D01*
G01Y983829D02*
Y982254D01*
G01Y988829D02*
Y987254D01*
G01X1622380Y925935D02*
Y925148D01*
G01Y929085D02*
Y928297D01*
G01Y932234D02*
Y931447D01*
G01Y935384D02*
Y934596D01*
G01Y938533D02*
Y937746D01*
G01Y941683D02*
Y940896D01*
G01Y944833D02*
Y944045D01*
G01Y947982D02*
Y947195D01*
G01Y951132D02*
Y950344D01*
G01Y954281D02*
Y953494D01*
G01Y957431D02*
Y956644D01*
G01Y960581D02*
Y959793D01*
G01Y963730D02*
Y962943D01*
G01Y966880D02*
Y966092D01*
G01Y970029D02*
Y969242D01*
G01Y973179D02*
Y972392D01*
G01Y976329D02*
Y975541D01*
G01Y979478D02*
Y978691D01*
G01Y982628D02*
Y981840D01*
G01Y985777D02*
Y984990D01*
G01Y988927D02*
Y988140D01*
G01Y992077D02*
Y991289D01*
G01X1621394Y953829D02*
Y952254D01*
G01Y993829D02*
Y992254D01*
G01X1620978Y931368D02*
Y929163D01*
G01X1620959Y924557D02*
Y923376D01*
G01Y927707D02*
Y926525D01*
G01Y934006D02*
Y932825D01*
G01Y930856D02*
Y929675D01*
G01X1620552Y931368D02*
Y935187D01*
G01X1620396Y925935D02*
Y925148D01*
G01Y929085D02*
Y928297D01*
G01Y932234D02*
Y931447D01*
G01Y935384D02*
Y934596D01*
G01Y938533D02*
Y937746D01*
G01Y941683D02*
Y940896D01*
G01Y944833D02*
Y944045D01*
G01Y947982D02*
Y947195D01*
G01Y951132D02*
Y950344D01*
G01Y954281D02*
Y953494D01*
G01Y957431D02*
Y956644D01*
G01Y960581D02*
Y959793D01*
G01Y963730D02*
Y962943D01*
G01Y966880D02*
Y966092D01*
G01Y970029D02*
Y969242D01*
G01Y973179D02*
Y972392D01*
G01Y976329D02*
Y975541D01*
G01Y979478D02*
Y978691D01*
G01Y982628D02*
Y981840D01*
G01Y985777D02*
Y984990D01*
G01Y988927D02*
Y988140D01*
G01Y992077D02*
Y991289D01*
G01X1619425Y938829D02*
Y937254D01*
G01Y943829D02*
Y942254D01*
G01Y948829D02*
Y947254D01*
G01Y958829D02*
Y957254D01*
G01Y963829D02*
Y962254D01*
G01Y968829D02*
Y967254D01*
G01Y973829D02*
Y972254D01*
G01Y978829D02*
Y977254D01*
G01Y983829D02*
Y982254D01*
G01Y988829D02*
Y987254D01*
G01X1619095Y929163D02*
Y931368D01*
G01X1618745Y991289D02*
Y992077D01*
G01Y988140D02*
Y988927D01*
G01Y981840D02*
Y982628D01*
G01Y984990D02*
Y985777D01*
G01Y978691D02*
Y979478D01*
G01Y972392D02*
Y973179D01*
G01Y975541D02*
Y976329D01*
G01Y969242D02*
Y970029D01*
G01Y962943D02*
Y963730D01*
G01Y966092D02*
Y966880D01*
G01Y959793D02*
Y960581D01*
G01Y953494D02*
Y954281D01*
G01Y956644D02*
Y957431D01*
G01Y950344D02*
Y951132D01*
G01Y944045D02*
Y944833D01*
G01Y947195D02*
Y947982D01*
G01Y940896D02*
Y941683D01*
G01Y934596D02*
Y935384D01*
G01Y937746D02*
Y938533D01*
G01Y931447D02*
Y932234D01*
G01Y925148D02*
Y925935D01*
G01Y928297D02*
Y929085D01*
G01X1617016Y925148D02*
Y922785D01*
G01Y928297D02*
Y925935D01*
G01Y931447D02*
Y929085D01*
G01Y934596D02*
Y932234D01*
G01Y937746D02*
Y935384D01*
G01Y940896D02*
Y938533D01*
G01Y944045D02*
Y941683D01*
G01Y947195D02*
Y944833D01*
G01Y950344D02*
Y947982D01*
G01Y953494D02*
Y951132D01*
G01Y956644D02*
Y954281D01*
G01Y959793D02*
Y957431D01*
G01Y962943D02*
Y960581D01*
G01Y966092D02*
Y963730D01*
G01Y969242D02*
Y966880D01*
G01Y972392D02*
Y970029D01*
G01Y975541D02*
Y973179D01*
G01Y978691D02*
Y976329D01*
G01Y981840D02*
Y979478D01*
G01Y984990D02*
Y982628D01*
G01Y988140D02*
Y985777D01*
G01Y991289D02*
Y988927D01*
G01Y994439D02*
Y992077D01*
G01X1616078Y991289D02*
Y992077D01*
G01Y988140D02*
Y988927D01*
G01Y981840D02*
Y982628D01*
G01Y984990D02*
Y985777D01*
G01Y978691D02*
Y979478D01*
G01Y972392D02*
Y973179D01*
G01Y975541D02*
Y976329D01*
G01Y969242D02*
Y970029D01*
G01Y962943D02*
Y963730D01*
G01Y966092D02*
Y966880D01*
G01Y959793D02*
Y960581D01*
G01Y953494D02*
Y954281D01*
G01Y956644D02*
Y957431D01*
G01Y950344D02*
Y951132D01*
G01Y944045D02*
Y944833D01*
G01Y947195D02*
Y947982D01*
G01Y940896D02*
Y941683D01*
G01Y934596D02*
Y935384D01*
G01Y937746D02*
Y938533D01*
G01Y931447D02*
Y932234D01*
G01Y925148D02*
Y925935D01*
G01Y928297D02*
Y929085D01*
G01X1615931Y991289D02*
Y992077D01*
G01Y988140D02*
Y988927D01*
G01Y981840D02*
Y982628D01*
G01Y984990D02*
Y985777D01*
G01Y978691D02*
Y979478D01*
G01Y972392D02*
Y973179D01*
G01Y975541D02*
Y976329D01*
G01Y969242D02*
Y970029D01*
G01Y962943D02*
Y963730D01*
G01Y966092D02*
Y966880D01*
G01Y959793D02*
Y960581D01*
G01Y953494D02*
Y954281D01*
G01Y956644D02*
Y957431D01*
G01Y950344D02*
Y951132D01*
G01Y944045D02*
Y944833D01*
G01Y947195D02*
Y947982D01*
G01Y940896D02*
Y941683D01*
G01Y934596D02*
Y935384D01*
G01Y937746D02*
Y938533D01*
G01Y931447D02*
Y932234D01*
G01Y925148D02*
Y925935D01*
G01Y928297D02*
Y929085D01*
G01X1614338Y991289D02*
Y992077D01*
G01Y988140D02*
Y988927D01*
G01Y981840D02*
Y982628D01*
G01Y984990D02*
Y985777D01*
G01Y978691D02*
Y979478D01*
G01Y972392D02*
Y973179D01*
G01Y975541D02*
Y976329D01*
G01Y969242D02*
Y970029D01*
G01Y962943D02*
Y963730D01*
G01Y966092D02*
Y966880D01*
G01Y959793D02*
Y960581D01*
G01Y953494D02*
Y954281D01*
G01Y956644D02*
Y957431D01*
G01Y950344D02*
Y951132D01*
G01Y944045D02*
Y944833D01*
G01Y947195D02*
Y947982D01*
G01Y940896D02*
Y941683D01*
G01Y934596D02*
Y935384D01*
G01Y937746D02*
Y938533D01*
G01Y931447D02*
Y932234D01*
G01Y925148D02*
Y925935D01*
G01Y928297D02*
Y929085D01*
G01X1613397Y925935D02*
Y925148D01*
G01Y929085D02*
Y928297D01*
G01Y932234D02*
Y931447D01*
G01Y935384D02*
Y934596D01*
G01Y938533D02*
Y937746D01*
G01Y941683D02*
Y940896D01*
G01Y944833D02*
Y944045D01*
G01Y947982D02*
Y947195D01*
G01Y951132D02*
Y950344D01*
G01Y954281D02*
Y953494D01*
G01Y957431D02*
Y956644D01*
G01Y960581D02*
Y959793D01*
G01Y963730D02*
Y962943D01*
G01Y966880D02*
Y966092D01*
G01Y970029D02*
Y969242D01*
G01Y973179D02*
Y972392D01*
G01Y976329D02*
Y975541D01*
G01Y979478D02*
Y978691D01*
G01Y982628D02*
Y981840D01*
G01Y985777D02*
Y984990D01*
G01Y988927D02*
Y988140D01*
G01Y992077D02*
Y991289D01*
G01X1610560Y925935D02*
Y925148D01*
G01Y929085D02*
Y928297D01*
G01Y932234D02*
Y931447D01*
G01Y935384D02*
Y934596D01*
G01Y938533D02*
Y937746D01*
G01Y941683D02*
Y940896D01*
G01Y944833D02*
Y944045D01*
G01Y947982D02*
Y947195D01*
G01Y951132D02*
Y950344D01*
G01Y954281D02*
Y953494D01*
G01Y957431D02*
Y956644D01*
G01Y960581D02*
Y959793D01*
G01Y963730D02*
Y962943D01*
G01Y966880D02*
Y966092D01*
G01Y970029D02*
Y969242D01*
G01Y973179D02*
Y972392D01*
G01Y976329D02*
Y975541D01*
G01Y979478D02*
Y978691D01*
G01Y982628D02*
Y981840D01*
G01Y985777D02*
Y984990D01*
G01Y988927D02*
Y988140D01*
G01Y992077D02*
Y991289D01*
G01X1610372D02*
Y992077D01*
G01Y988140D02*
Y988927D01*
G01Y981840D02*
Y982628D01*
G01Y984990D02*
Y985777D01*
G01Y978691D02*
Y979478D01*
G01Y972392D02*
Y973179D01*
G01Y975541D02*
Y976329D01*
G01Y969242D02*
Y970029D01*
G01Y962943D02*
Y963730D01*
G01Y966092D02*
Y966880D01*
G01Y959793D02*
Y960581D01*
G01Y953494D02*
Y954281D01*
G01Y956644D02*
Y957431D01*
G01Y950344D02*
Y951132D01*
G01Y944045D02*
Y944833D01*
G01Y947195D02*
Y947982D01*
G01Y940896D02*
Y941683D01*
G01Y934596D02*
Y935384D01*
G01Y937746D02*
Y938533D01*
G01Y931447D02*
Y932234D01*
G01Y925148D02*
Y925935D01*
G01Y928297D02*
Y929085D01*
G01X1608598Y991289D02*
Y992077D01*
G01Y988140D02*
Y988927D01*
G01Y981840D02*
Y982628D01*
G01Y984990D02*
Y985777D01*
G01Y978691D02*
Y979478D01*
G01Y972392D02*
Y973179D01*
G01Y975541D02*
Y976329D01*
G01Y969242D02*
Y970029D01*
G01Y962943D02*
Y963730D01*
G01Y966092D02*
Y966880D01*
G01Y959793D02*
Y960581D01*
G01Y953494D02*
Y954281D01*
G01Y956644D02*
Y957431D01*
G01Y950344D02*
Y951132D01*
G01Y944045D02*
Y944833D01*
G01Y947195D02*
Y947982D01*
G01Y940896D02*
Y941683D01*
G01Y934596D02*
Y935384D01*
G01Y937746D02*
Y938533D01*
G01Y931447D02*
Y932234D01*
G01Y925148D02*
Y925935D01*
G01Y928297D02*
Y929085D01*
G01X1628087Y995246D02*
X1626984D01*
G01X1615931Y995226D02*
X1608598D01*
G01X1628087D02*
X1616078D01*
G01X1626512Y994616D02*
X1625527D01*
G01X1616078Y994439D02*
X1628087D01*
G01X1608598D02*
X1615931D01*
G01X1626512Y994419D02*
X1625527D01*
G01X1656827Y994144D02*
X1630134D01*
G01X1626512Y994025D02*
X1625527D01*
G01X1626984Y993829D02*
X1621394D01*
G01X1632102Y994144D02*
Y1011663D01*
G01X1626145Y994439D02*
Y995226D01*
G01X1626118Y994439D02*
Y995226D01*
G01X1625742Y994439D02*
Y995226D01*
G01X1622380D02*
Y994439D01*
G01X1620396Y995226D02*
Y994439D01*
G01X1618745D02*
Y995226D01*
G01X1617016Y997588D02*
Y995226D01*
G01X1616078Y994439D02*
Y995226D01*
G01X1615931Y994439D02*
Y995226D01*
G01X1614338Y994439D02*
Y995226D01*
G01X1613397D02*
Y994439D01*
G01X1610560Y995226D02*
Y994439D01*
G01X1610372D02*
Y995226D01*
G01X1608598Y994439D02*
Y995226D01*
G01X1629774Y1021201D02*
G03X1631205I716J0D01*
G01X1626884D02*
G03X1628315I716J0D01*
G01X1630646Y1030581D02*
G03Y1033730I0J1575D01*
G01X1625786Y1020126D02*
G03X1628421Y1020271I1247J1352D01*
G01D02*
G03X1631202Y1020276I1388J1206D01*
G01X1625492Y1020797D02*
G03X1625786Y1020126I913J0D01*
G01X1626315Y1033730D02*
G03Y1030581I0J-1574D01*
G01X1621812Y1022617D02*
G03Y1020933I2237J-842D01*
G01X1626590Y1008829D02*
G03X1626984Y1009222I0J394D01*
G01Y1006860D02*
G03X1626590Y1007254I-394J0D01*
G01Y998829D02*
G03X1626984Y999222I0J394D01*
G01Y996860D02*
G03X1626590Y997254I-394J0D01*
G01Y1003829D02*
G03X1626984Y1004222I0J394D01*
G01Y1001860D02*
G03X1626590Y1002254I-394J0D01*
G01X1623285Y1022617D02*
G03X1621812I-736J-277D01*
G01Y1020933D02*
G03X1623285I737J277D01*
G01X1624558Y1022952D02*
G03X1624036Y1023517I-1351J-724D01*
G01X1620990Y1023516D02*
G03X1620470Y1022950I833J-1287D01*
G01Y1020638D02*
G03X1620991Y1020073I1351J723D01*
G01X1624038D02*
G03X1624558Y1020638I-832J1287D01*
G01X1623285Y1020933D02*
G03Y1022617I-2236J842D01*
G01X1624558Y1020638D02*
G03Y1022952I-2162J1157D01*
G01X1620470Y1022950D02*
G03Y1020638I2163J-1156D01*
G01X1624037Y1023517D02*
G03X1620990Y1023516I-1523J-2362D01*
G01X1620991Y1020073D02*
G03X1624038I1524J2361D01*
G01X1621394Y1020344D02*
G03I-2166J0D01*
G01X1617274Y1023061D02*
G03Y1017628I1954J-2717D01*
G01X1621183D02*
G03Y1023061I-1955J2717D01*
G01X1622732Y1020344D02*
G03I-3504J0D01*
G01X1621532Y1016447D02*
G03Y1024242I-2304J3898D01*
G01X1616925D02*
G03Y1016447I2303J-3898D01*
G01X1615312Y1022935D02*
G03X1614721Y1022570I-9J-646D01*
G01X1616085Y1022127D02*
G03X1615312Y1022935I-791J17D01*
G01X1614060Y1023639D02*
G03X1613217Y1022570I704J-1422D01*
G01X1613426Y1020684D02*
G03X1614660Y1019710I1735J930D01*
G01X1616303Y1019754D02*
G03X1617467Y1020893I-730J1910D01*
G01X1617381Y1022909D02*
G03X1615642Y1023926I-1807J-1094D01*
G01X1614660Y1019711D02*
G03X1616303Y1019754I757J2475D01*
G01X1617641Y1022049D02*
G03X1617380Y1022911I-2971J-429D01*
G01X1613087Y1022127D02*
G03X1613426Y1020684I3015J-53D01*
G01X1617641Y1021553D02*
G03Y1022050I-3524J248D01*
G01X1617468Y1020893D02*
G03X1617641Y1021553I-4020J1406D01*
G01X1614660Y1021301D02*
G03X1616085I713J-82D01*
G01X1615646Y1023926D02*
G03X1614060Y1023639I-263J-3073D01*
G01X1609888Y1021571D02*
X1608593Y1019719D01*
G01X1610665Y1020705D02*
X1609975Y1019719D01*
G01X1613061Y1023726D02*
X1611618Y1021579D01*
G01X1621987Y1014419D02*
X1621731Y1014025D01*
G01X1611653Y1023726D02*
X1610862Y1022448D01*
G01X1636669Y1038061D02*
X1620291D01*
G01X1626315Y1033730D02*
X1630646D01*
G01X1625689Y1032943D02*
X1631271D01*
G01Y1031368D02*
X1625689D01*
G01X1630646Y1030581D02*
X1626315D01*
G01X1636669Y1027884D02*
X1620291D01*
G01X1606827Y1025128D02*
X1660764D01*
G01X1621532Y1024242D02*
X1616925D01*
G01X1660764Y1023947D02*
X1634386D01*
G01X1610117Y1023726D02*
X1608567D01*
G01X1613061D02*
X1611653D01*
G01X1619693D02*
X1618232D01*
G01X1629774D02*
X1628315D01*
G01X1626884D02*
X1625492D01*
G01X1632645D02*
X1631205D01*
G01X1630449Y1023159D02*
X1606827D01*
G01X1617274Y1023061D02*
X1621183D01*
G01X1614721Y1022570D02*
X1613217D01*
G01X1616087Y1022127D02*
X1613087D01*
G01X1616086Y1021301D02*
X1614660D01*
G01X1609975Y1019719D02*
X1608593D01*
G01X1612887D02*
X1611270D01*
G01X1632645D02*
X1631202D01*
G01X1630449Y1019380D02*
X1606827D01*
G01X1619693Y1017972D02*
X1618232D01*
G01X1621183Y1017628D02*
X1617274D01*
G01X1630449Y1017411D02*
X1606827D01*
G01X1656827Y1016781D02*
X1606827D01*
G01X1616925Y1016447D02*
X1621532D01*
G01X1606827Y1015010D02*
X1630449D01*
G01X1621987Y1014478D02*
X1628087D01*
G01X1621987Y1014419D02*
X1628087D01*
G01X1607619Y1014025D02*
X1628087D01*
G01X1626984Y1012844D02*
X1636354D01*
G01X1658795Y1012254D02*
X1628087D01*
G01X1656827Y1011860D02*
X1638323D01*
G01X1636669Y1011663D02*
X1630134D01*
G01X1606827Y1011250D02*
X1626984D01*
G01Y1011073D02*
X1636354D01*
G01X1624543Y1009616D02*
X1623559D01*
G01X1622968Y1009498D02*
X1613984D01*
G01X1624543Y1009419D02*
X1623559D01*
G01X1624543Y1009025D02*
X1623559D01*
G01X1619425Y1008829D02*
X1626590D01*
G01X1615931Y1007825D02*
X1608598D01*
G01X1628087D02*
X1616078D01*
G01X1619425Y1007254D02*
X1626590D01*
G01X1624543Y1007057D02*
X1623559D01*
G01X1616078Y1007037D02*
X1628087D01*
G01X1608598D02*
X1615931D01*
G01X1624543Y1006663D02*
X1623559D01*
G01X1624543Y1006466D02*
X1623559D01*
G01X1615931Y1004675D02*
X1608598D01*
G01X1628087D02*
X1616078D01*
G01X1624543Y1004616D02*
X1623559D01*
G01X1624543Y1004419D02*
X1623559D01*
G01X1624543Y1004025D02*
X1623559D01*
G01X1616078Y1003888D02*
X1628087D01*
G01X1608598D02*
X1615931D01*
G01X1619425Y1003829D02*
X1626590D01*
G01X1619425Y1002254D02*
X1626590D01*
G01X1624543Y1002057D02*
X1623559D01*
G01X1624543Y1001663D02*
X1623559D01*
G01X1615931Y1001525D02*
X1608598D01*
G01X1628087D02*
X1616078D01*
G01X1624543Y1001466D02*
X1623559D01*
G01X1616078Y1000738D02*
X1628087D01*
G01X1608598D02*
X1615931D01*
G01X1624543Y999616D02*
X1623559D01*
G01X1624543Y999419D02*
X1623559D01*
G01X1624543Y999025D02*
X1623559D01*
G01X1619425Y998829D02*
X1626590D01*
G01X1615931Y998376D02*
X1608598D01*
G01X1628087D02*
X1616078D01*
G01Y997588D02*
X1628087D01*
G01X1608598D02*
X1615931D01*
G01X1619425Y997254D02*
X1626590D01*
G01X1624543Y997057D02*
X1623559D01*
G01X1624543Y996663D02*
X1623559D01*
G01X1624543Y996466D02*
X1623559D01*
G01X1617274Y1017628D02*
X1617256Y1017572D01*
X1617204Y1017407D01*
X1617125Y1017148D01*
X1617029Y1016821D01*
X1616925Y1016447D01*
G01X1621532Y1024242D02*
X1621429Y1023873D01*
X1621332Y1023543D01*
X1621252Y1023281D01*
X1621200Y1023115D01*
X1621183Y1023061D01*
G01X1636669Y1011663D02*
Y1038061D01*
G01X1636354Y1012844D02*
Y1011073D01*
G01X1634386Y1025128D02*
Y1016781D01*
G01X1632645Y1023726D02*
Y1019719D01*
G01X1631271Y1031368D02*
Y1032943D01*
G01X1631236D02*
Y1031368D01*
G01X1631212Y1032943D02*
Y1031368D01*
G01X1631205Y1021201D02*
Y1023726D01*
G01X1631202Y1020276D02*
Y1019719D01*
G01X1630449Y1017411D02*
Y1015010D01*
G01Y1023159D02*
Y1019380D01*
G01X1629889Y1031368D02*
Y1032943D01*
G01X1629774Y1023726D02*
Y1021201D01*
G01X1629519Y1032943D02*
Y1031368D01*
G01X1628315Y1021201D02*
Y1023726D01*
G01X1627442Y1031368D02*
Y1032943D01*
G01X1627072D02*
Y1031368D01*
G01X1626884Y1023726D02*
Y1021201D01*
G01X1626145Y1007037D02*
Y1007825D01*
G01Y1000738D02*
Y1001525D01*
G01Y1003888D02*
Y1004675D01*
G01Y997588D02*
Y998376D01*
G01X1626118Y1007037D02*
Y1007825D01*
G01Y1000738D02*
Y1001525D01*
G01Y1003888D02*
Y1004675D01*
G01Y997588D02*
Y998376D01*
G01X1625748Y1031368D02*
Y1032943D01*
G01X1625742Y1007037D02*
Y1007825D01*
G01Y1000738D02*
Y1001525D01*
G01Y1003888D02*
Y1004675D01*
G01Y997588D02*
Y998376D01*
G01X1625724Y1031368D02*
Y1032943D01*
G01X1625689D02*
Y1031368D01*
G01X1625527Y998829D02*
Y997254D01*
G01Y1003829D02*
Y1002254D01*
G01Y1008829D02*
Y1007254D01*
G01X1625492Y1023726D02*
Y1020797D01*
G01X1624543Y999616D02*
Y996466D01*
G01Y1004616D02*
Y1001466D01*
G01Y1009616D02*
Y1006466D01*
G01Y1016781D02*
Y1014478D01*
G01X1623559Y999616D02*
Y996466D01*
G01Y1004616D02*
Y1001466D01*
G01Y1009616D02*
Y1006466D01*
G01X1622575Y998829D02*
Y997254D01*
G01Y1003829D02*
Y1002254D01*
G01Y1008829D02*
Y1007254D01*
G01X1622380Y998376D02*
Y997588D01*
G01Y1001525D02*
Y1000738D01*
G01Y1004675D02*
Y1003888D01*
G01Y1007825D02*
Y1007037D01*
G01X1621987Y1014478D02*
Y1014419D01*
G01X1621348Y1014025D02*
Y1016781D01*
G01X1620396Y998376D02*
Y997588D01*
G01Y1001525D02*
Y1000738D01*
G01Y1004675D02*
Y1003888D01*
G01Y1007825D02*
Y1007037D01*
G01X1620291Y1038061D02*
Y1025128D01*
G01X1619693Y1023726D02*
Y1017972D01*
G01X1619425Y998829D02*
Y997254D01*
G01Y1003829D02*
Y1002254D01*
G01Y1008829D02*
Y1007254D01*
G01X1618745Y1007037D02*
Y1007825D01*
G01Y1000738D02*
Y1001525D01*
G01Y1003888D02*
Y1004675D01*
G01Y997588D02*
Y998376D01*
G01X1618232Y1023726D02*
Y1017972D01*
G01X1617016Y1000738D02*
Y998376D01*
G01Y1003888D02*
Y1001525D01*
G01Y1007037D02*
Y1004675D01*
G01Y1009498D02*
Y1007825D01*
G01X1616078Y1007037D02*
Y1007825D01*
G01Y1000738D02*
Y1001525D01*
G01Y1003888D02*
Y1004675D01*
G01Y997588D02*
Y998376D01*
G01X1615931Y1007037D02*
Y1007825D01*
G01Y1000738D02*
Y1001525D01*
G01Y1003888D02*
Y1004675D01*
G01Y997588D02*
Y998376D01*
G01X1614338Y1007037D02*
Y1007825D01*
G01Y1000738D02*
Y1001525D01*
G01Y1003888D02*
Y1004675D01*
G01Y997588D02*
Y998376D01*
G01X1613474Y1014025D02*
Y1016781D01*
G01X1613397Y998376D02*
Y997588D01*
G01Y1001525D02*
Y1000738D01*
G01Y1004675D02*
Y1003888D01*
G01Y1007825D02*
Y1007037D01*
G01X1610560Y998376D02*
Y997588D01*
G01Y1001525D02*
Y1000738D01*
G01Y1004675D02*
Y1003888D01*
G01Y1007825D02*
Y1007037D01*
G01X1610372D02*
Y1007825D01*
G01Y1000738D02*
Y1001525D01*
G01Y1003888D02*
Y1004675D01*
G01Y997588D02*
Y998376D01*
G01X1608598Y1007037D02*
Y1007825D01*
G01Y1000738D02*
Y1001525D01*
G01Y1003888D02*
Y1004675D01*
G01Y997588D02*
Y998376D01*
G01X1607619Y1014025D02*
Y1011250D01*
G01X1607144Y1016781D02*
Y1011250D01*
G01X1606827Y1025128D02*
Y1011250D01*
G01X1621183Y1017628D02*
X1621200Y1017572D01*
X1621253Y1017406D01*
X1621332Y1017148D01*
X1621427Y1016821D01*
X1621532Y1016447D01*
G01X1617274Y1023061D02*
X1617256Y1023117D01*
X1617204Y1023282D01*
X1617125Y1023541D01*
X1617029Y1023868D01*
X1616925Y1024242D01*
G01X1610117Y1023726D02*
X1610862Y1022448D01*
G01X1608567Y1023726D02*
X1609888Y1021571D01*
G01X1610665Y1020705D02*
X1611270Y1019719D01*
G01X1611618Y1021579D02*
X1612887Y1019719D01*
G01X1624887Y1274953D02*
G03X1623817Y1273130I2809J-2874D01*
G01X1631864Y1277854D02*
G03X1629649Y1272687I6937J-6032D01*
G01X1632749Y1277928D02*
G03X1630535Y1272687I7143J-6105D01*
G01X1625392Y1274409D02*
G03X1624851Y1273425I1277J-1343D01*
G01X1621394Y1276250D02*
G03I-2166J0D01*
G01X1622575D02*
G03I-3347J0D01*
G01X1622732D02*
G03I-3504J0D01*
G01X1623756D02*
G03I-4528J0D01*
G01X1611416Y1277854D02*
G03X1609201Y1272687I6937J-6032D01*
G01X1612301Y1277928D02*
G03X1610087Y1272687I7143J-6105D01*
G01X1631630Y1245659D02*
G03Y1244478I0J-591D01*
G01X1625331D02*
G03Y1245659I0J590D01*
G01Y1247234D02*
G03Y1248415I0J591D01*
G01X1631630D02*
G03Y1247234I0J-590D01*
G01X1630646Y1262864D02*
G03Y1266014I0J1575D01*
G01X1626315D02*
G03Y1262864I0J-1575D01*
G01X1628087Y1284340D02*
X1658795D01*
G01X1626984Y1283750D02*
X1636354D01*
G01X1607619Y1282569D02*
X1628087D01*
G01X1621987Y1282175D02*
X1628087D01*
G01Y1282116D02*
X1621987D01*
G01X1630449Y1281624D02*
X1606827D01*
G01X1656827Y1279813D02*
X1606827D01*
G01Y1279183D02*
X1630449D01*
G01X1612302Y1278592D02*
X1608463D01*
G01X1632749D02*
X1628911D01*
G01Y1277854D02*
X1631864D01*
G01X1608463D02*
X1611416D01*
G01X1630449Y1277214D02*
X1606827D01*
G01X1624113Y1276895D02*
X1624925D01*
G01X1625823Y1277854D02*
X1626170Y1277785D01*
G01X1630449Y1273435D02*
X1606827D01*
G01X1627730Y1273425D02*
X1624851D01*
G01X1629649Y1272687D02*
X1630535D01*
G01X1623817D02*
X1627730D01*
G01X1609201D02*
X1610087D01*
G01X1634386Y1272648D02*
X1660764D01*
G01Y1271466D02*
X1606827D01*
G01X1636669Y1268711D02*
X1620291D01*
G01X1626315Y1266014D02*
X1630646D01*
G01X1625689Y1265226D02*
X1631271D01*
G01Y1263651D02*
X1625689D01*
G01X1630646Y1262864D02*
X1626315D01*
G01X1636669Y1258533D02*
X1620291D01*
G01X1631630Y1249006D02*
X1625331D01*
G01X1630055Y1248711D02*
X1633205D01*
G01X1626905D02*
X1623756D01*
G01Y1246742D02*
X1626905D01*
G01X1633205D02*
X1630055D01*
G01X1623756Y1246151D02*
X1626905D01*
G01X1633205D02*
X1630055D01*
G01X1625341Y1245407D02*
X1625435D01*
G01Y1244659D02*
X1625341D01*
G01X1630055Y1244183D02*
X1633205D01*
G01X1626905D02*
X1623756D01*
G01X1625331Y1243888D02*
X1631630D01*
G01X1621066Y1275488D02*
X1621426Y1275252D01*
X1621665Y1274902D01*
X1621750Y1274498D01*
X1621668Y1274096D01*
X1621431Y1273744D01*
X1621068Y1273504D01*
X1620643Y1273419D01*
G01X1620220Y1273503D02*
X1619860Y1273739D01*
X1619621Y1274089D01*
X1619536Y1274493D01*
X1619618Y1274895D01*
X1619855Y1275247D01*
X1620218Y1275487D01*
X1620643Y1275572D01*
G01X1615899Y1275488D02*
X1616259Y1275252D01*
X1616498Y1274902D01*
X1616583Y1274498D01*
X1616500Y1274096D01*
X1616264Y1273744D01*
X1615901Y1273504D01*
X1615476Y1273419D01*
G01X1615053Y1273503D02*
X1614692Y1273739D01*
X1614454Y1274089D01*
X1614369Y1274493D01*
X1614451Y1274895D01*
X1614688Y1275247D01*
X1615051Y1275487D01*
X1615476Y1275572D01*
G01X1626170Y1277785D02*
X1626450Y1277604D01*
G01X1620992Y1277789D02*
X1621275Y1277611D01*
X1621462Y1277346D01*
X1621529Y1277044D01*
X1621464Y1276744D01*
X1621279Y1276477D01*
X1620994Y1276296D01*
X1620643Y1276230D01*
G01X1620294Y1276295D02*
X1620012Y1276473D01*
X1619824Y1276738D01*
X1619757Y1277040D01*
X1619822Y1277340D01*
X1620007Y1277607D01*
X1620293Y1277789D01*
X1620643Y1277854D01*
G01X1615825Y1277789D02*
X1616107Y1277611D01*
X1616294Y1277346D01*
X1616361Y1277044D01*
X1616297Y1276744D01*
X1616112Y1276477D01*
X1615826Y1276296D01*
X1615476Y1276230D01*
G01X1615127Y1276295D02*
X1614844Y1276473D01*
X1614657Y1276738D01*
X1614590Y1277040D01*
X1614654Y1277340D01*
X1614840Y1277607D01*
X1615125Y1277789D01*
X1615476Y1277854D01*
G01X1625181Y1277614D02*
X1625469Y1277792D01*
X1625823Y1277854D01*
G01X1620992Y1276295D02*
X1621275Y1276473D01*
X1621462Y1276738D01*
X1621529Y1277040D01*
X1621464Y1277340D01*
X1621279Y1277607D01*
X1620994Y1277789D01*
X1620643Y1277854D01*
G01X1620294Y1277789D02*
X1620012Y1277611D01*
X1619824Y1277346D01*
X1619757Y1277044D01*
X1619822Y1276744D01*
X1620007Y1276477D01*
X1620293Y1276296D01*
X1620643Y1276230D01*
G01X1615825Y1276295D02*
X1616107Y1276473D01*
X1616294Y1276738D01*
X1616361Y1277040D01*
X1616297Y1277340D01*
X1616112Y1277607D01*
X1615826Y1277789D01*
X1615476Y1277854D01*
G01X1615127Y1277789D02*
X1614844Y1277611D01*
X1614657Y1277346D01*
X1614590Y1277044D01*
X1614654Y1276744D01*
X1614840Y1276477D01*
X1615125Y1276296D01*
X1615476Y1276230D01*
G01X1621066Y1273503D02*
X1621426Y1273739D01*
X1621665Y1274089D01*
X1621750Y1274493D01*
X1621668Y1274895D01*
X1621431Y1275247D01*
X1621068Y1275487D01*
X1620643Y1275572D01*
G01X1620220Y1275488D02*
X1619860Y1275252D01*
X1619621Y1274902D01*
X1619536Y1274498D01*
X1619618Y1274096D01*
X1619855Y1273744D01*
X1620218Y1273504D01*
X1620643Y1273419D01*
G01X1615899Y1273503D02*
X1616259Y1273739D01*
X1616498Y1274089D01*
X1616583Y1274493D01*
X1616500Y1274895D01*
X1616264Y1275247D01*
X1615901Y1275487D01*
X1615476Y1275572D01*
G01X1615053Y1275488D02*
X1614692Y1275252D01*
X1614454Y1274902D01*
X1614369Y1274498D01*
X1614451Y1274096D01*
X1614688Y1273744D01*
X1615051Y1273504D01*
X1615476Y1273419D01*
G01X1621731Y1282569D02*
X1621987Y1282175D01*
G01X1626449Y1277605D02*
X1626632Y1277340D01*
X1626696Y1277041D01*
X1626632Y1276744D01*
G01X1619445Y1275943D02*
X1619123Y1276363D01*
X1618960Y1276846D01*
X1618982Y1277351D01*
X1619185Y1277828D01*
X1619552Y1278231D01*
X1620058Y1278499D01*
X1620649Y1278592D01*
X1621238Y1278495D01*
X1621740Y1278227D01*
X1622105Y1277823D01*
X1622306Y1277345D01*
X1622325Y1276840D01*
X1622161Y1276359D01*
X1621841Y1275943D01*
G01X1614278D02*
X1613955Y1276363D01*
X1613793Y1276846D01*
X1613815Y1277351D01*
X1614017Y1277828D01*
X1614384Y1278231D01*
X1614890Y1278499D01*
X1615482Y1278592D01*
X1616071Y1278495D01*
X1616573Y1278227D01*
X1616937Y1277823D01*
X1617139Y1277345D01*
X1617158Y1276840D01*
X1616994Y1276359D01*
X1616674Y1275943D01*
G01X1621841D02*
X1622293Y1275503D01*
X1622563Y1274967D01*
X1622633Y1274397D01*
X1622491Y1273833D01*
X1622145Y1273308D01*
X1621617Y1272915D01*
X1620975Y1272712D01*
X1620295Y1272714D01*
X1619655Y1272922D01*
X1619132Y1273318D01*
X1618791Y1273842D01*
X1618653Y1274403D01*
X1618725Y1274971D01*
X1618995Y1275505D01*
G01X1616674Y1275943D02*
X1617125Y1275503D01*
X1617395Y1274967D01*
X1617466Y1274397D01*
X1617324Y1273833D01*
X1616977Y1273308D01*
X1616450Y1272915D01*
X1615807Y1272712D01*
X1615128Y1272714D01*
X1614488Y1272922D01*
X1613965Y1273318D01*
X1613624Y1273842D01*
X1613486Y1274403D01*
X1613557Y1274971D01*
X1613828Y1275505D01*
G01X1627021Y1275956D02*
X1625392Y1274409D01*
G01X1619445Y1275943D02*
X1618994Y1275503D01*
X1618724Y1274967D01*
X1618653Y1274397D01*
X1618795Y1273833D01*
X1619142Y1273308D01*
X1619669Y1272915D01*
X1620312Y1272712D01*
X1620991Y1272714D01*
X1621631Y1272922D01*
X1622154Y1273318D01*
X1622495Y1273842D01*
X1622633Y1274403D01*
X1622562Y1274971D01*
X1622291Y1275505D01*
G01X1614278Y1275943D02*
X1613826Y1275503D01*
X1613556Y1274967D01*
X1613486Y1274397D01*
X1613628Y1273833D01*
X1613974Y1273308D01*
X1614502Y1272915D01*
X1615144Y1272712D01*
X1615824Y1272714D01*
X1616464Y1272922D01*
X1616986Y1273318D01*
X1617328Y1273842D01*
X1617466Y1274403D01*
X1617394Y1274971D01*
X1617124Y1275505D01*
G01X1626450Y1276480D02*
X1624887Y1274953D01*
G01X1625341Y1245280D02*
X1625248Y1245169D01*
G01Y1245296D02*
X1625341Y1245407D01*
G01X1621841Y1275943D02*
X1622164Y1276363D01*
X1622326Y1276846D01*
X1622304Y1277351D01*
X1622101Y1277828D01*
X1621735Y1278231D01*
X1621228Y1278499D01*
X1620637Y1278592D01*
X1620048Y1278495D01*
X1619546Y1278227D01*
X1619182Y1277823D01*
X1618980Y1277345D01*
X1618961Y1276840D01*
X1619125Y1276359D01*
X1619445Y1275943D01*
G01X1616674D02*
X1616996Y1276363D01*
X1617159Y1276846D01*
X1617137Y1277351D01*
X1616934Y1277828D01*
X1616567Y1278231D01*
X1616061Y1278499D01*
X1615470Y1278592D01*
X1614881Y1278495D01*
X1614378Y1278227D01*
X1614014Y1277823D01*
X1613813Y1277345D01*
X1613794Y1276840D01*
X1613958Y1276359D01*
X1614278Y1275943D01*
G01X1627021Y1275956D02*
X1627358Y1276417D01*
X1627504Y1276936D01*
X1627444Y1277453D01*
X1627193Y1277937D01*
X1626756Y1278332D01*
X1626183Y1278555D01*
X1625548Y1278574D01*
X1624964Y1278388D01*
X1624509Y1278035D01*
X1624216Y1277563D01*
X1624113Y1277042D01*
G01X1625182Y1277614D02*
X1624992Y1277346D01*
G01X1626450Y1276480D02*
X1626633Y1276746D01*
X1626696Y1277044D01*
X1626631Y1277341D01*
G01X1624992Y1277347D02*
X1624925Y1277042D01*
G01X1624113D02*
X1624199Y1277519D01*
X1624447Y1277961D01*
X1624835Y1278313D01*
X1625342Y1278533D01*
X1625919Y1278589D01*
X1626483Y1278467D01*
X1626959Y1278185D01*
X1627298Y1277780D01*
X1627478Y1277323D01*
X1627493Y1276843D01*
X1627336Y1276373D01*
X1627021Y1275956D01*
G01X1636669Y1258533D02*
Y1284931D01*
G01X1636354Y1285522D02*
Y1283750D01*
G01X1634386Y1271466D02*
Y1279813D01*
G01X1633205Y1244183D02*
Y1246151D01*
G01Y1248711D02*
Y1246742D01*
G01X1632749Y1277928D02*
Y1278592D01*
G01X1631630Y1248415D02*
Y1249006D01*
G01Y1245659D02*
Y1247234D01*
G01Y1243888D02*
Y1244478D01*
G01X1631271Y1263651D02*
Y1265226D01*
G01X1631236D02*
Y1263651D01*
G01X1631212Y1265226D02*
Y1263651D01*
G01X1630646Y1243888D02*
Y1249006D01*
G01X1630449D02*
Y1243888D01*
G01Y1277214D02*
Y1273435D01*
G01Y1281624D02*
Y1279183D01*
G01X1630055Y1246742D02*
Y1248711D01*
G01Y1246151D02*
Y1244183D01*
G01X1629889Y1263651D02*
Y1265226D01*
G01X1629519D02*
Y1263651D01*
G01X1628911Y1278592D02*
Y1277854D01*
G01X1628087Y1419990D02*
Y1282116D01*
G01X1627730Y1272687D02*
Y1273425D01*
G01X1627442Y1263651D02*
Y1265226D01*
G01X1627072D02*
Y1263651D01*
G01X1626984Y1282569D02*
Y1419537D01*
G01X1626905Y1246742D02*
Y1248711D01*
G01Y1246151D02*
Y1244183D01*
G01X1626512Y1249006D02*
Y1243888D01*
G01X1626315D02*
Y1249006D01*
G01X1625748Y1263651D02*
Y1265226D01*
G01X1625724Y1263651D02*
Y1265226D01*
G01X1625689D02*
Y1263651D01*
G01X1625435Y1245407D02*
Y1244659D01*
G01X1625341D02*
Y1245280D01*
G01X1625331Y1244478D02*
Y1243888D01*
G01Y1247234D02*
Y1245659D01*
G01Y1249006D02*
Y1248415D01*
G01X1625248Y1245169D02*
Y1245296D01*
G01X1624925Y1276895D02*
Y1277042D01*
G01X1624543Y1282116D02*
Y1279813D01*
G01X1624113Y1277042D02*
Y1276895D01*
G01X1623817Y1273130D02*
Y1272687D01*
G01X1623756Y1244183D02*
Y1246151D01*
G01Y1248711D02*
Y1246742D01*
G01X1622968Y1282569D02*
Y1419537D01*
G01X1621987Y1282175D02*
Y1282116D01*
G01X1621348Y1279813D02*
Y1282569D01*
G01X1620291Y1271466D02*
Y1258533D01*
G01X1613984Y1419537D02*
Y1282569D01*
G01X1613474Y1279813D02*
Y1282569D01*
G01X1612302Y1277928D02*
Y1278592D01*
G01X1608463D02*
Y1277854D01*
G01X1607619Y1285148D02*
Y1282569D01*
G01X1607144Y1285148D02*
Y1279813D01*
G01X1606827Y1285148D02*
Y1271466D01*
G01X1630358Y1286309D02*
X1630706Y1286394D01*
G01X1632013Y1286053D02*
X1632362Y1286138D01*
G01X1630271Y1286821D02*
X1630096D01*
G01X1630009Y1286309D02*
X1630358D01*
G01X1626984Y1285522D02*
X1636354D01*
G01X1626984Y1285148D02*
X1606827D01*
G01X1636669Y1284931D02*
X1630134D01*
G01X1656827Y1284734D02*
X1638323D01*
G01X1629661Y1286394D02*
X1630009Y1286309D01*
G01X1630096Y1286821D02*
X1629835Y1286906D01*
G01X1632274Y1286650D02*
X1632013Y1286565D01*
G01X1630532Y1286906D02*
X1630271Y1286821D01*
G01X1629312Y1286735D02*
X1629661Y1286394D01*
G01X1632362Y1286138D02*
X1632797Y1286394D01*
G01X1629138Y1287077D02*
X1629312Y1286735D01*
G01X1629835Y1286906D02*
X1629661Y1287162D01*
G01X1632536Y1286906D02*
X1632274Y1286650D01*
G01X1630706Y1286394D02*
X1631055Y1286735D01*
G01X1630706Y1287162D02*
X1630532Y1286906D01*
G01X1632797Y1286394D02*
X1633058Y1286821D01*
G01X1631055Y1286735D02*
X1631229Y1287077D01*
G01X1632623Y1287247D02*
X1632536Y1286906D01*
G01X1633058Y1286821D02*
X1633146Y1287247D01*
G01X1638323Y1417372D02*
Y1284734D01*
G01X1632102Y1301348D02*
Y1284931D01*
G01X1632013Y1286565D02*
Y1286053D01*
G01X1630134Y1284931D02*
Y1417175D01*
G01X1622514Y1285148D02*
Y1416762D01*
G01X1626590Y1349340D02*
G03X1626984Y1349734I0J394D01*
G01Y1347372D02*
G03X1626590Y1347766I-394J0D01*
G01Y1354340D02*
G03X1626984Y1354734I0J394D01*
G01Y1352372D02*
G03X1626590Y1352766I-394J0D01*
G01Y1319340D02*
G03X1626984Y1319734I0J394D01*
G01Y1317372D02*
G03X1626590Y1317766I-394J0D01*
G01Y1314340D02*
G03X1626984Y1314734I0J394D01*
G01X1626590Y1344340D02*
G03X1626984Y1344734I0J394D01*
G01Y1342372D02*
G03X1626590Y1342766I-394J0D01*
G01Y1289340D02*
G03X1626984Y1289734I0J394D01*
G01Y1287372D02*
G03X1626590Y1287766I-394J0D01*
G01X1626984Y1312372D02*
G03X1626590Y1312766I-394J0D01*
G01Y1309340D02*
G03X1626984Y1309734I0J394D01*
G01Y1307372D02*
G03X1626590Y1307766I-394J0D01*
G01Y1299340D02*
G03X1626984Y1299734I0J394D01*
G01Y1297372D02*
G03X1626590Y1297766I-394J0D01*
G01Y1304340D02*
G03X1626984Y1304734I0J394D01*
G01Y1302372D02*
G03X1626590Y1302766I-394J0D01*
G01Y1294340D02*
G03X1626984Y1294734I0J394D01*
G01Y1292372D02*
G03X1626590Y1292766I-394J0D01*
G01X1626512Y1357175D02*
X1625527D01*
G01X1626512Y1356978D02*
X1625527D01*
G01X1615931Y1356644D02*
X1608598D01*
G01X1628087D02*
X1616078D01*
G01X1628087Y1356348D02*
X1626984D01*
G01X1616078Y1355856D02*
X1628087D01*
G01X1608598D02*
X1615931D01*
G01X1624543Y1355128D02*
X1623559D01*
G01X1624543Y1354931D02*
X1623559D01*
G01X1624543Y1354537D02*
X1623559D01*
G01X1619425Y1354340D02*
X1626590D01*
G01X1615931Y1353494D02*
X1608598D01*
G01X1628087D02*
X1616078D01*
G01X1619425Y1352766D02*
X1626590D01*
G01X1616078Y1352707D02*
X1628087D01*
G01X1608598D02*
X1615931D01*
G01X1624543Y1352569D02*
X1623559D01*
G01X1624543Y1352175D02*
X1623559D01*
G01X1624543Y1351978D02*
X1623559D01*
G01X1615931Y1350344D02*
X1608598D01*
G01X1628087D02*
X1616078D01*
G01X1624543Y1350128D02*
X1623559D01*
G01X1624543Y1349931D02*
X1623559D01*
G01X1616078Y1349557D02*
X1628087D01*
G01X1608598D02*
X1615931D01*
G01X1624543Y1349537D02*
X1623559D01*
G01X1619425Y1349340D02*
X1626590D01*
G01X1619425Y1347766D02*
X1626590D01*
G01X1624543Y1347569D02*
X1623559D01*
G01X1657784Y1347254D02*
X1638323D01*
G01X1615931Y1347195D02*
X1608598D01*
G01X1628087D02*
X1616078D01*
G01X1624543Y1347175D02*
X1623559D01*
G01X1624543Y1346978D02*
X1623559D01*
G01X1616078Y1346407D02*
X1628087D01*
G01X1608598D02*
X1615931D01*
G01X1624543Y1345128D02*
X1623559D01*
G01X1624543Y1344931D02*
X1623559D01*
G01X1624543Y1344537D02*
X1623559D01*
G01X1619425Y1344340D02*
X1626590D01*
G01X1615931Y1344045D02*
X1608598D01*
G01X1628087D02*
X1616078D01*
G01Y1343258D02*
X1628087D01*
G01X1608598D02*
X1615931D01*
G01X1656827Y1343159D02*
X1630134D01*
G01X1619425Y1342766D02*
X1626590D01*
G01X1624543Y1342569D02*
X1623559D01*
G01X1624543Y1342175D02*
X1623559D01*
G01X1624543Y1341978D02*
X1623559D01*
G01X1615931Y1340896D02*
X1608598D01*
G01X1628087D02*
X1616078D01*
G01X1638323Y1340817D02*
X1656827D01*
G01X1628087D02*
X1626984D01*
G01X1652326Y1340797D02*
X1630134D01*
G01X1628087Y1340699D02*
X1620552D01*
G01X1625093Y1340207D02*
X1622968D01*
G01X1616078Y1340108D02*
X1628087D01*
G01X1608598D02*
X1615931D01*
G01X1626077Y1339911D02*
X1625093D01*
G01X1626077Y1339714D02*
X1625093D01*
G01X1626984Y1339518D02*
X1620959D01*
G01X1626984Y1338337D02*
X1620959D01*
G01X1626077Y1338140D02*
X1625093D01*
G01X1626077Y1337943D02*
X1625093D01*
G01X1615931Y1337746D02*
X1608598D01*
G01X1628087D02*
X1616078D01*
G01Y1336959D02*
X1628087D01*
G01X1608598D02*
X1615931D01*
G01X1620978Y1336880D02*
X1619095D01*
G01X1626077Y1336762D02*
X1625093D01*
G01X1626077Y1336565D02*
X1625093D01*
G01X1626984Y1336368D02*
X1620959D01*
G01X1626984Y1335187D02*
X1620959D01*
G01X1626077Y1334990D02*
X1625093D01*
G01X1626077Y1334793D02*
X1625093D01*
G01X1619095Y1334675D02*
X1620978D01*
G01X1615931Y1334596D02*
X1608598D01*
G01X1628087D02*
X1616078D01*
G01Y1333809D02*
X1628087D01*
G01X1608598D02*
X1615931D01*
G01X1626077Y1333612D02*
X1625093D01*
G01X1626077Y1333415D02*
X1625093D01*
G01X1626984Y1333218D02*
X1620959D01*
G01X1626984Y1332037D02*
X1620959D01*
G01X1626077Y1331840D02*
X1625093D01*
G01X1626077Y1331644D02*
X1625093D01*
G01X1615931Y1331447D02*
X1608598D01*
G01X1628087D02*
X1616078D01*
G01Y1330659D02*
X1628087D01*
G01X1608598D02*
X1615931D01*
G01X1626077Y1330463D02*
X1625093D01*
G01X1626077Y1330266D02*
X1625093D01*
G01X1626984Y1330069D02*
X1620959D01*
G01X1626984Y1328888D02*
X1620959D01*
G01X1626077Y1328691D02*
X1625093D01*
G01X1626077Y1328494D02*
X1625093D01*
G01X1615931Y1328297D02*
X1608598D01*
G01X1628087D02*
X1616078D01*
G01Y1327510D02*
X1628087D01*
G01X1608598D02*
X1615931D01*
G01X1620978Y1327431D02*
X1619095D01*
G01X1626077Y1327313D02*
X1625093D01*
G01X1626077Y1327116D02*
X1625093D01*
G01X1626984Y1326919D02*
X1620959D01*
G01X1626984Y1325738D02*
X1620959D01*
G01X1626077Y1325541D02*
X1625093D01*
G01X1626077Y1325344D02*
X1625093D01*
G01X1619095Y1325226D02*
X1620978D01*
G01X1615931Y1325148D02*
X1608598D01*
G01X1628087D02*
X1616078D01*
G01Y1324360D02*
X1628087D01*
G01X1608598D02*
X1615931D01*
G01X1626077Y1324163D02*
X1625093D01*
G01X1626077Y1323966D02*
X1625093D01*
G01X1626984Y1323770D02*
X1620959D01*
G01X1626984Y1322588D02*
X1620959D01*
G01X1626077Y1322392D02*
X1625093D01*
G01X1626077Y1322195D02*
X1625093D01*
G01X1615931Y1321998D02*
X1608598D01*
G01X1628087D02*
X1616078D01*
G01X1625093Y1321900D02*
X1622968D01*
G01X1620552Y1321407D02*
X1628087D01*
G01X1652326Y1321309D02*
X1630134D01*
G01X1628087Y1321289D02*
X1626984D01*
G01X1656827D02*
X1638323D01*
G01X1616078Y1321211D02*
X1628087D01*
G01X1608598D02*
X1615931D01*
G01X1624543Y1320128D02*
X1623559D01*
G01X1624543Y1319931D02*
X1623559D01*
G01X1624543Y1319537D02*
X1623559D01*
G01X1619425Y1319340D02*
X1626590D01*
G01X1656827Y1318947D02*
X1630134D01*
G01X1615931Y1318848D02*
X1608598D01*
G01X1628087D02*
X1616078D01*
G01Y1318061D02*
X1628087D01*
G01X1608598D02*
X1615931D01*
G01X1619425Y1317766D02*
X1626590D01*
G01X1624543Y1317569D02*
X1623559D01*
G01X1624543Y1317175D02*
X1623559D01*
G01X1624543Y1316978D02*
X1623559D01*
G01X1615931Y1315699D02*
X1608598D01*
G01X1628087D02*
X1616078D01*
G01X1624543Y1315128D02*
X1623559D01*
G01X1657784Y1314951D02*
X1638323D01*
G01X1624543Y1314931D02*
X1623559D01*
G01X1616078Y1314911D02*
X1628087D01*
G01X1608598D02*
X1615931D01*
G01X1624543Y1314537D02*
X1623559D01*
G01X1619425Y1314340D02*
X1626590D01*
G01X1619425Y1312766D02*
X1626590D01*
G01X1624543Y1312569D02*
X1623559D01*
G01X1615931Y1312549D02*
X1608598D01*
G01X1628087D02*
X1616078D01*
G01X1624543Y1312175D02*
X1623559D01*
G01X1624543Y1311978D02*
X1623559D01*
G01X1616078Y1311762D02*
X1628087D01*
G01X1608598D02*
X1615931D01*
G01X1624543Y1310128D02*
X1623559D01*
G01X1624543Y1309931D02*
X1623559D01*
G01X1624543Y1309537D02*
X1623559D01*
G01X1615931Y1309400D02*
X1608598D01*
G01X1628087D02*
X1616078D01*
G01X1619425Y1309340D02*
X1626590D01*
G01X1616078Y1308612D02*
X1628087D01*
G01X1608598D02*
X1615931D01*
G01X1619425Y1307766D02*
X1626590D01*
G01X1624543Y1307569D02*
X1623559D01*
G01X1624543Y1307175D02*
X1623559D01*
G01X1624543Y1306978D02*
X1623559D01*
G01X1615931Y1306250D02*
X1608598D01*
G01X1628087D02*
X1616078D01*
G01Y1305463D02*
X1628087D01*
G01X1608598D02*
X1615931D01*
G01X1624543Y1305128D02*
X1623559D01*
G01X1624543Y1304931D02*
X1623559D01*
G01X1624543Y1304537D02*
X1623559D01*
G01X1619425Y1304340D02*
X1626590D01*
G01X1656827Y1303711D02*
X1630134D01*
G01X1615931Y1303100D02*
X1608598D01*
G01X1628087D02*
X1616078D01*
G01X1619425Y1302766D02*
X1626590D01*
G01X1624543Y1302569D02*
X1623559D01*
G01X1616078Y1302313D02*
X1628087D01*
G01X1608598D02*
X1615931D01*
G01X1624543Y1302175D02*
X1623559D01*
G01X1624543Y1301978D02*
X1623559D01*
G01X1656827Y1301348D02*
X1630134D01*
G01X1624543Y1300128D02*
X1623559D01*
G01X1615931Y1299951D02*
X1608598D01*
G01X1628087D02*
X1616078D01*
G01X1624543Y1299931D02*
X1623559D01*
G01X1624543Y1299537D02*
X1623559D01*
G01X1619425Y1299340D02*
X1626590D01*
G01X1616078Y1299163D02*
X1628087D01*
G01X1608598D02*
X1615931D01*
G01X1619425Y1297766D02*
X1626590D01*
G01X1624543Y1297569D02*
X1623559D01*
G01X1624543Y1297175D02*
X1623559D01*
G01X1624543Y1296978D02*
X1623559D01*
G01X1615931Y1296801D02*
X1608598D01*
G01X1628087D02*
X1616078D01*
G01Y1296014D02*
X1628087D01*
G01X1608598D02*
X1615931D01*
G01X1624543Y1295128D02*
X1623559D01*
G01X1624543Y1294931D02*
X1623559D01*
G01X1624543Y1294537D02*
X1623559D01*
G01X1619425Y1294340D02*
X1626590D01*
G01X1615931Y1293651D02*
X1608598D01*
G01X1628087D02*
X1616078D01*
G01Y1292864D02*
X1628087D01*
G01X1608598D02*
X1615931D01*
G01X1619425Y1292766D02*
X1626590D01*
G01X1624543Y1292569D02*
X1623559D01*
G01X1624543Y1292175D02*
X1623559D01*
G01X1624543Y1291978D02*
X1623559D01*
G01X1629051Y1290915D02*
X1633146D01*
G01X1615931Y1290502D02*
X1608598D01*
G01X1628087D02*
X1616078D01*
G01X1633146Y1290403D02*
X1629748D01*
G01X1624543Y1290128D02*
X1623559D01*
G01X1624543Y1289931D02*
X1623559D01*
G01X1630358Y1289892D02*
X1629661D01*
G01X1616078Y1289714D02*
X1628087D01*
G01X1608598D02*
X1615931D01*
G01X1626531Y1289557D02*
X1618461D01*
G01X1624543Y1289537D02*
X1623559D01*
G01X1619425Y1289340D02*
X1626590D01*
G01X1632187Y1289209D02*
X1631752D01*
G01X1631839Y1288697D02*
X1632100D01*
G01X1619425Y1287766D02*
X1626590D01*
G01X1618461Y1287588D02*
X1626531D01*
G01X1624543Y1287569D02*
X1623559D01*
G01X1624543Y1287175D02*
X1623559D01*
G01X1622968Y1287136D02*
X1613984D01*
G01X1624543Y1286978D02*
X1623559D01*
G01X1632536Y1289039D02*
X1632187Y1289209D01*
G01X1630009Y1288953D02*
X1629748Y1288868D01*
G01X1632884Y1288697D02*
X1632536Y1289039D01*
G01X1629748Y1290403D02*
X1630358Y1289892D01*
G01X1629661D02*
X1629051Y1290403D01*
G01X1632100Y1288697D02*
X1632362Y1288527D01*
G01X1631752Y1289209D02*
X1631403Y1289039D01*
G01X1629835Y1288356D02*
X1630009Y1288442D01*
G01X1631577Y1288527D02*
X1631839Y1288697D01*
G01X1629748Y1288868D02*
X1629400Y1288612D01*
G01X1633058Y1288356D02*
X1632884Y1288697D01*
G01X1632362Y1288527D02*
X1632536Y1288271D01*
G01X1631403Y1289039D02*
X1631055Y1288697D01*
G01X1629661Y1288186D02*
X1629835Y1288356D01*
G01X1629400Y1288612D02*
X1629138Y1288271D01*
G01X1631403D02*
X1631577Y1288527D01*
G01X1633146Y1287930D02*
X1633058Y1288356D01*
G01X1632536Y1288271D02*
X1632623Y1287930D01*
G01X1629051Y1287418D02*
X1629138Y1287077D01*
G01X1629661Y1287162D02*
X1629574Y1287418D01*
G01X1631055Y1288697D02*
X1630881Y1288356D01*
G01X1630793Y1287418D02*
X1630706Y1287162D01*
G01X1629574Y1287930D02*
X1629661Y1288186D01*
G01X1631229Y1287077D02*
X1631316Y1287418D01*
G01Y1287930D02*
X1631403Y1288271D01*
G01X1630881Y1288356D02*
X1630793Y1287930D01*
G01X1629138Y1288271D02*
X1629051Y1287844D01*
G01X1633146Y1287247D02*
Y1287930D01*
G01Y1290915D02*
Y1290403D01*
G01X1632623Y1287930D02*
Y1287247D01*
G01X1632102Y1343159D02*
Y1359498D01*
G01Y1318947D02*
Y1303711D01*
G01Y1340797D02*
Y1321309D01*
G01X1631316Y1287418D02*
Y1287930D01*
G01X1630793D02*
Y1287418D01*
G01X1630009Y1288442D02*
Y1288953D01*
G01X1629574Y1287418D02*
Y1287930D01*
G01X1629051Y1290403D02*
Y1290915D01*
G01Y1287844D02*
Y1287418D01*
G01X1626905Y1340699D02*
Y1321407D01*
G01X1626590D02*
Y1340699D01*
G01X1626531Y1287588D02*
Y1289557D01*
G01X1626512Y1360128D02*
Y1356978D01*
G01X1626145Y1355856D02*
Y1356644D01*
G01Y1352707D02*
Y1353494D01*
G01Y1346407D02*
Y1347195D01*
G01Y1349557D02*
Y1350344D01*
G01Y1343258D02*
Y1344045D01*
G01Y1336959D02*
Y1337746D01*
G01Y1340108D02*
Y1340896D01*
G01Y1333809D02*
Y1334596D01*
G01Y1327510D02*
Y1328297D01*
G01Y1330659D02*
Y1331447D01*
G01Y1324360D02*
Y1325148D01*
G01Y1321211D02*
Y1321998D01*
G01Y1314911D02*
Y1315699D01*
G01Y1318061D02*
Y1318848D01*
G01Y1311762D02*
Y1312549D01*
G01Y1305463D02*
Y1306250D01*
G01Y1308612D02*
Y1309400D01*
G01Y1302313D02*
Y1303100D01*
G01Y1296014D02*
Y1296801D01*
G01Y1299163D02*
Y1299951D01*
G01Y1292864D02*
Y1293651D01*
G01Y1289714D02*
Y1290502D01*
G01X1626118Y1355856D02*
Y1356644D01*
G01Y1352707D02*
Y1353494D01*
G01Y1346407D02*
Y1347195D01*
G01Y1349557D02*
Y1350344D01*
G01Y1343258D02*
Y1344045D01*
G01Y1336959D02*
Y1337746D01*
G01Y1340108D02*
Y1340896D01*
G01Y1333809D02*
Y1334596D01*
G01Y1327510D02*
Y1328297D01*
G01Y1330659D02*
Y1331447D01*
G01Y1324360D02*
Y1325148D01*
G01Y1321211D02*
Y1321998D01*
G01Y1314911D02*
Y1315699D01*
G01Y1318061D02*
Y1318848D01*
G01Y1311762D02*
Y1312549D01*
G01Y1305463D02*
Y1306250D01*
G01Y1308612D02*
Y1309400D01*
G01Y1302313D02*
Y1303100D01*
G01Y1296014D02*
Y1296801D01*
G01Y1299163D02*
Y1299951D01*
G01Y1292864D02*
Y1293651D01*
G01Y1289714D02*
Y1290502D01*
G01X1626077Y1324360D02*
Y1321998D01*
G01Y1327510D02*
Y1325148D01*
G01Y1330659D02*
Y1328297D01*
G01Y1333809D02*
Y1331447D01*
G01Y1336959D02*
Y1334596D01*
G01Y1340108D02*
Y1337746D01*
G01X1625803Y1340699D02*
Y1321407D01*
G01X1625742Y1355856D02*
Y1356644D01*
G01Y1352707D02*
Y1353494D01*
G01Y1346407D02*
Y1347195D01*
G01Y1349557D02*
Y1350344D01*
G01Y1343258D02*
Y1344045D01*
G01Y1336959D02*
Y1337746D01*
G01Y1340108D02*
Y1340896D01*
G01Y1333809D02*
Y1334596D01*
G01Y1327510D02*
Y1328297D01*
G01Y1330659D02*
Y1331447D01*
G01Y1324360D02*
Y1325148D01*
G01Y1321211D02*
Y1321998D01*
G01Y1314911D02*
Y1315699D01*
G01Y1318061D02*
Y1318848D01*
G01Y1311762D02*
Y1312549D01*
G01Y1305463D02*
Y1306250D01*
G01Y1308612D02*
Y1309400D01*
G01Y1302313D02*
Y1303100D01*
G01Y1296014D02*
Y1296801D01*
G01Y1299163D02*
Y1299951D01*
G01Y1292864D02*
Y1293651D01*
G01Y1289714D02*
Y1290502D01*
G01X1625527Y1289340D02*
Y1287766D01*
G01Y1294340D02*
Y1292766D01*
G01Y1299340D02*
Y1297766D01*
G01Y1304340D02*
Y1302766D01*
G01Y1309340D02*
Y1307766D01*
G01Y1314340D02*
Y1312766D01*
G01Y1319340D02*
Y1317766D01*
G01Y1344340D02*
Y1342766D01*
G01Y1349340D02*
Y1347766D01*
G01Y1354340D02*
Y1352766D01*
G01Y1360128D02*
Y1356978D01*
G01X1625303Y1340699D02*
Y1321407D01*
G01X1625093Y1321900D02*
Y1340207D01*
G01X1624543Y1290128D02*
Y1286978D01*
G01Y1295128D02*
Y1291978D01*
G01Y1300128D02*
Y1296978D01*
G01Y1305128D02*
Y1301978D01*
G01Y1310128D02*
Y1306978D01*
G01Y1315128D02*
Y1311978D01*
G01Y1320128D02*
Y1316978D01*
G01Y1345128D02*
Y1341978D01*
G01Y1350128D02*
Y1346978D01*
G01Y1355128D02*
Y1351978D01*
G01X1624386Y1321407D02*
Y1340699D01*
G01X1624109Y1323770D02*
Y1322588D01*
G01Y1326919D02*
Y1325738D01*
G01Y1330069D02*
Y1328888D01*
G01Y1333218D02*
Y1332037D01*
G01Y1336368D02*
Y1335187D01*
G01Y1339518D02*
Y1338337D01*
G01X1623559Y1290128D02*
Y1286978D01*
G01Y1295128D02*
Y1291978D01*
G01Y1300128D02*
Y1296978D01*
G01Y1305128D02*
Y1301978D01*
G01Y1310128D02*
Y1306978D01*
G01Y1315128D02*
Y1311978D01*
G01Y1320128D02*
Y1316978D01*
G01Y1345128D02*
Y1341978D01*
G01Y1350128D02*
Y1346978D01*
G01Y1355128D02*
Y1351978D01*
G01X1622575Y1289340D02*
Y1287766D01*
G01Y1294340D02*
Y1292766D01*
G01Y1299340D02*
Y1297766D01*
G01Y1304340D02*
Y1302766D01*
G01Y1309340D02*
Y1307766D01*
G01Y1314340D02*
Y1312766D01*
G01Y1319340D02*
Y1317766D01*
G01Y1344340D02*
Y1342766D01*
G01Y1349340D02*
Y1347766D01*
G01Y1354340D02*
Y1352766D01*
G01X1622380Y1290502D02*
Y1289714D01*
G01Y1293651D02*
Y1292864D01*
G01Y1296801D02*
Y1296014D01*
G01Y1299951D02*
Y1299163D01*
G01Y1303100D02*
Y1302313D01*
G01Y1306250D02*
Y1305463D01*
G01Y1309400D02*
Y1308612D01*
G01Y1312549D02*
Y1311762D01*
G01Y1315699D02*
Y1314911D01*
G01Y1318848D02*
Y1318061D01*
G01Y1321998D02*
Y1321211D01*
G01Y1325148D02*
Y1324360D01*
G01Y1328297D02*
Y1327510D01*
G01Y1331447D02*
Y1330659D01*
G01Y1334596D02*
Y1333809D01*
G01Y1337746D02*
Y1336959D01*
G01Y1340896D02*
Y1340108D01*
G01Y1344045D02*
Y1343258D01*
G01Y1347195D02*
Y1346407D01*
G01Y1350344D02*
Y1349557D01*
G01Y1353494D02*
Y1352707D01*
G01Y1356644D02*
Y1355856D01*
G01X1621030Y1321407D02*
Y1340699D01*
G01X1620978Y1327431D02*
Y1325226D01*
G01Y1336880D02*
Y1334675D01*
G01X1620959Y1323770D02*
Y1322588D01*
G01Y1326919D02*
Y1325738D01*
G01Y1330069D02*
Y1328888D01*
G01Y1333218D02*
Y1332037D01*
G01Y1336368D02*
Y1335187D01*
G01Y1339518D02*
Y1338337D01*
G01X1620552Y1336880D02*
Y1340699D01*
G01Y1327431D02*
Y1334675D01*
G01Y1321407D02*
Y1325226D01*
G01X1620396Y1290502D02*
Y1289714D01*
G01Y1293651D02*
Y1292864D01*
G01Y1296801D02*
Y1296014D01*
G01Y1299951D02*
Y1299163D01*
G01Y1303100D02*
Y1302313D01*
G01Y1306250D02*
Y1305463D01*
G01Y1309400D02*
Y1308612D01*
G01Y1312549D02*
Y1311762D01*
G01Y1315699D02*
Y1314911D01*
G01Y1318848D02*
Y1318061D01*
G01Y1321998D02*
Y1321211D01*
G01Y1325148D02*
Y1324360D01*
G01Y1328297D02*
Y1327510D01*
G01Y1331447D02*
Y1330659D01*
G01Y1334596D02*
Y1333809D01*
G01Y1337746D02*
Y1336959D01*
G01Y1340896D02*
Y1340108D01*
G01Y1344045D02*
Y1343258D01*
G01Y1347195D02*
Y1346407D01*
G01Y1350344D02*
Y1349557D01*
G01Y1353494D02*
Y1352707D01*
G01Y1356644D02*
Y1355856D01*
G01X1619425Y1289340D02*
Y1287766D01*
G01Y1294340D02*
Y1292766D01*
G01Y1299340D02*
Y1297766D01*
G01Y1304340D02*
Y1302766D01*
G01Y1309340D02*
Y1307766D01*
G01Y1314340D02*
Y1312766D01*
G01Y1319340D02*
Y1317766D01*
G01Y1344340D02*
Y1342766D01*
G01Y1349340D02*
Y1347766D01*
G01Y1354340D02*
Y1352766D01*
G01X1619095Y1334675D02*
Y1336880D01*
G01Y1325226D02*
Y1327431D01*
G01X1618745Y1355856D02*
Y1356644D01*
G01Y1352707D02*
Y1353494D01*
G01Y1346407D02*
Y1347195D01*
G01Y1349557D02*
Y1350344D01*
G01Y1343258D02*
Y1344045D01*
G01Y1336959D02*
Y1337746D01*
G01Y1340108D02*
Y1340896D01*
G01Y1333809D02*
Y1334596D01*
G01Y1327510D02*
Y1328297D01*
G01Y1330659D02*
Y1331447D01*
G01Y1324360D02*
Y1325148D01*
G01Y1321211D02*
Y1321998D01*
G01Y1314911D02*
Y1315699D01*
G01Y1318061D02*
Y1318848D01*
G01Y1311762D02*
Y1312549D01*
G01Y1305463D02*
Y1306250D01*
G01Y1308612D02*
Y1309400D01*
G01Y1302313D02*
Y1303100D01*
G01Y1296014D02*
Y1296801D01*
G01Y1299163D02*
Y1299951D01*
G01Y1292864D02*
Y1293651D01*
G01Y1289714D02*
Y1290502D01*
G01X1618461Y1289557D02*
Y1287588D01*
G01X1617016Y1289714D02*
Y1287136D01*
G01Y1292864D02*
Y1290502D01*
G01Y1296014D02*
Y1293651D01*
G01Y1299163D02*
Y1296801D01*
G01Y1302313D02*
Y1299951D01*
G01Y1305463D02*
Y1303100D01*
G01Y1308612D02*
Y1306250D01*
G01Y1311762D02*
Y1309400D01*
G01Y1314911D02*
Y1312549D01*
G01Y1318061D02*
Y1315699D01*
G01Y1321211D02*
Y1318848D01*
G01Y1324360D02*
Y1321998D01*
G01Y1327510D02*
Y1325148D01*
G01Y1330659D02*
Y1328297D01*
G01Y1333809D02*
Y1331447D01*
G01Y1336959D02*
Y1334596D01*
G01Y1340108D02*
Y1337746D01*
G01Y1343258D02*
Y1340896D01*
G01Y1346407D02*
Y1344045D01*
G01Y1349557D02*
Y1347195D01*
G01Y1352707D02*
Y1350344D01*
G01Y1355856D02*
Y1353494D01*
G01Y1359006D02*
Y1356644D01*
G01X1616078Y1355856D02*
Y1356644D01*
G01Y1352707D02*
Y1353494D01*
G01Y1346407D02*
Y1347195D01*
G01Y1349557D02*
Y1350344D01*
G01Y1343258D02*
Y1344045D01*
G01Y1336959D02*
Y1337746D01*
G01Y1340108D02*
Y1340896D01*
G01Y1333809D02*
Y1334596D01*
G01Y1327510D02*
Y1328297D01*
G01Y1330659D02*
Y1331447D01*
G01Y1324360D02*
Y1325148D01*
G01Y1321211D02*
Y1321998D01*
G01Y1314911D02*
Y1315699D01*
G01Y1318061D02*
Y1318848D01*
G01Y1311762D02*
Y1312549D01*
G01Y1305463D02*
Y1306250D01*
G01Y1308612D02*
Y1309400D01*
G01Y1302313D02*
Y1303100D01*
G01Y1296014D02*
Y1296801D01*
G01Y1299163D02*
Y1299951D01*
G01Y1292864D02*
Y1293651D01*
G01Y1289714D02*
Y1290502D01*
G01X1615931Y1355856D02*
Y1356644D01*
G01Y1352707D02*
Y1353494D01*
G01Y1346407D02*
Y1347195D01*
G01Y1349557D02*
Y1350344D01*
G01Y1343258D02*
Y1344045D01*
G01Y1336959D02*
Y1337746D01*
G01Y1340108D02*
Y1340896D01*
G01Y1333809D02*
Y1334596D01*
G01Y1327510D02*
Y1328297D01*
G01Y1330659D02*
Y1331447D01*
G01Y1324360D02*
Y1325148D01*
G01Y1321211D02*
Y1321998D01*
G01Y1314911D02*
Y1315699D01*
G01Y1318061D02*
Y1318848D01*
G01Y1311762D02*
Y1312549D01*
G01Y1305463D02*
Y1306250D01*
G01Y1308612D02*
Y1309400D01*
G01Y1302313D02*
Y1303100D01*
G01Y1296014D02*
Y1296801D01*
G01Y1299163D02*
Y1299951D01*
G01Y1292864D02*
Y1293651D01*
G01Y1289714D02*
Y1290502D01*
G01X1614338Y1355856D02*
Y1356644D01*
G01Y1352707D02*
Y1353494D01*
G01Y1346407D02*
Y1347195D01*
G01Y1349557D02*
Y1350344D01*
G01Y1343258D02*
Y1344045D01*
G01Y1336959D02*
Y1337746D01*
G01Y1340108D02*
Y1340896D01*
G01Y1333809D02*
Y1334596D01*
G01Y1327510D02*
Y1328297D01*
G01Y1330659D02*
Y1331447D01*
G01Y1324360D02*
Y1325148D01*
G01Y1321211D02*
Y1321998D01*
G01Y1314911D02*
Y1315699D01*
G01Y1318061D02*
Y1318848D01*
G01Y1311762D02*
Y1312549D01*
G01Y1305463D02*
Y1306250D01*
G01Y1308612D02*
Y1309400D01*
G01Y1302313D02*
Y1303100D01*
G01Y1296014D02*
Y1296801D01*
G01Y1299163D02*
Y1299951D01*
G01Y1292864D02*
Y1293651D01*
G01Y1289714D02*
Y1290502D01*
G01X1613397D02*
Y1289714D01*
G01Y1293651D02*
Y1292864D01*
G01Y1296801D02*
Y1296014D01*
G01Y1299951D02*
Y1299163D01*
G01Y1303100D02*
Y1302313D01*
G01Y1306250D02*
Y1305463D01*
G01Y1309400D02*
Y1308612D01*
G01Y1312549D02*
Y1311762D01*
G01Y1315699D02*
Y1314911D01*
G01Y1318848D02*
Y1318061D01*
G01Y1321998D02*
Y1321211D01*
G01Y1325148D02*
Y1324360D01*
G01Y1328297D02*
Y1327510D01*
G01Y1331447D02*
Y1330659D01*
G01Y1334596D02*
Y1333809D01*
G01Y1337746D02*
Y1336959D01*
G01Y1340896D02*
Y1340108D01*
G01Y1344045D02*
Y1343258D01*
G01Y1347195D02*
Y1346407D01*
G01Y1350344D02*
Y1349557D01*
G01Y1353494D02*
Y1352707D01*
G01Y1356644D02*
Y1355856D01*
G01X1610560Y1290502D02*
Y1289714D01*
G01Y1293651D02*
Y1292864D01*
G01Y1296801D02*
Y1296014D01*
G01Y1299951D02*
Y1299163D01*
G01Y1303100D02*
Y1302313D01*
G01Y1306250D02*
Y1305463D01*
G01Y1309400D02*
Y1308612D01*
G01Y1312549D02*
Y1311762D01*
G01Y1315699D02*
Y1314911D01*
G01Y1318848D02*
Y1318061D01*
G01Y1321998D02*
Y1321211D01*
G01Y1325148D02*
Y1324360D01*
G01Y1328297D02*
Y1327510D01*
G01Y1331447D02*
Y1330659D01*
G01Y1334596D02*
Y1333809D01*
G01Y1337746D02*
Y1336959D01*
G01Y1340896D02*
Y1340108D01*
G01Y1344045D02*
Y1343258D01*
G01Y1347195D02*
Y1346407D01*
G01Y1350344D02*
Y1349557D01*
G01Y1353494D02*
Y1352707D01*
G01Y1356644D02*
Y1355856D01*
G01X1610372D02*
Y1356644D01*
G01Y1352707D02*
Y1353494D01*
G01Y1346407D02*
Y1347195D01*
G01Y1349557D02*
Y1350344D01*
G01Y1343258D02*
Y1344045D01*
G01Y1336959D02*
Y1337746D01*
G01Y1340108D02*
Y1340896D01*
G01Y1333809D02*
Y1334596D01*
G01Y1327510D02*
Y1328297D01*
G01Y1330659D02*
Y1331447D01*
G01Y1324360D02*
Y1325148D01*
G01Y1321211D02*
Y1321998D01*
G01Y1314911D02*
Y1315699D01*
G01Y1318061D02*
Y1318848D01*
G01Y1311762D02*
Y1312549D01*
G01Y1305463D02*
Y1306250D01*
G01Y1308612D02*
Y1309400D01*
G01Y1302313D02*
Y1303100D01*
G01Y1296014D02*
Y1296801D01*
G01Y1299163D02*
Y1299951D01*
G01Y1292864D02*
Y1293651D01*
G01Y1289714D02*
Y1290502D01*
G01X1608598Y1355856D02*
Y1356644D01*
G01Y1352707D02*
Y1353494D01*
G01Y1346407D02*
Y1347195D01*
G01Y1349557D02*
Y1350344D01*
G01Y1343258D02*
Y1344045D01*
G01Y1336959D02*
Y1337746D01*
G01Y1340108D02*
Y1340896D01*
G01Y1333809D02*
Y1334596D01*
G01Y1327510D02*
Y1328297D01*
G01Y1330659D02*
Y1331447D01*
G01Y1324360D02*
Y1325148D01*
G01Y1321211D02*
Y1321998D01*
G01Y1314911D02*
Y1315699D01*
G01Y1318061D02*
Y1318848D01*
G01Y1311762D02*
Y1312549D01*
G01Y1305463D02*
Y1306250D01*
G01Y1308612D02*
Y1309400D01*
G01Y1302313D02*
Y1303100D01*
G01Y1296014D02*
Y1296801D01*
G01Y1299163D02*
Y1299951D01*
G01Y1292864D02*
Y1293651D01*
G01Y1289714D02*
Y1290502D01*
G01X1615931Y1359793D02*
X1608598D01*
G01X1628087D02*
X1616078D01*
G01X1626512Y1359537D02*
X1625527D01*
G01X1656827Y1359498D02*
X1630134D01*
G01X1626984Y1359340D02*
X1621394D01*
G01X1616078Y1359006D02*
X1628087D01*
G01X1608598D02*
X1615931D01*
G01X1626984Y1357766D02*
X1621394D01*
G01X1626512Y1357569D02*
X1625527D01*
G01X1626145Y1359006D02*
Y1359793D01*
G01X1626118Y1359006D02*
Y1359793D01*
G01X1625742Y1359006D02*
Y1359793D01*
G01X1624543Y1359340D02*
Y1357766D01*
G01X1622380Y1359793D02*
Y1359006D01*
G01X1621394Y1359340D02*
Y1357766D01*
G01X1620396Y1359793D02*
Y1359006D01*
G01X1618745D02*
Y1359793D01*
G01X1617016Y1362155D02*
Y1359793D01*
G01X1616078Y1359006D02*
Y1359793D01*
G01X1615931Y1359006D02*
Y1359793D01*
G01X1614338Y1359006D02*
Y1359793D01*
G01X1613397D02*
Y1359006D01*
G01X1610560Y1359793D02*
Y1359006D01*
G01X1610372D02*
Y1359793D01*
G01X1608598Y1359006D02*
Y1359793D01*
G01X1629774Y1426713D02*
G03X1631205I716J0D01*
G01X1626884D02*
G03X1628315I716J0D01*
G01X1625786Y1425638D02*
G03X1628421Y1425782I1248J1351D01*
G01D02*
G03X1631202Y1425788I1388J1207D01*
G01X1625492Y1426309D02*
G03X1625786Y1425638I913J0D01*
G01X1621812Y1428129D02*
G03Y1426444I2237J-843D01*
G01X1626590Y1414340D02*
G03X1626984Y1414734I0J394D01*
G01Y1412372D02*
G03X1626590Y1412766I-394J0D01*
G01Y1404340D02*
G03X1626984Y1404734I0J394D01*
G01Y1402372D02*
G03X1626590Y1402766I-394J0D01*
G01Y1409340D02*
G03X1626984Y1409734I0J394D01*
G01Y1407372D02*
G03X1626590Y1407766I-394J0D01*
G01X1623285Y1428129D02*
G03X1621812I-736J-277D01*
G01Y1426444D02*
G03X1623285I737J278D01*
G01X1624558Y1428464D02*
G03X1624036Y1429029I-1351J-724D01*
G01X1620990Y1429027D02*
G03X1620470Y1428462I832J-1287D01*
G01Y1426150D02*
G03X1620991Y1425585I1351J723D01*
G01X1624038D02*
G03X1624558Y1426150I-832J1287D01*
G01X1623285Y1426444D02*
G03Y1428129I-2236J842D01*
G01X1624558Y1426150D02*
G03Y1428464I-2162J1157D01*
G01X1620470Y1428462D02*
G03Y1426150I2163J-1156D01*
G01X1624037Y1429029D02*
G03X1620990Y1429028I-1523J-2362D01*
G01X1620991Y1425584D02*
G03X1624038Y1425585I1523J2362D01*
G01X1626590Y1364340D02*
G03X1626984Y1364734I0J394D01*
G01Y1362372D02*
G03X1626590Y1362766I-394J0D01*
G01Y1374340D02*
G03X1626984Y1374734I0J394D01*
G01Y1372372D02*
G03X1626590Y1372766I-394J0D01*
G01Y1379340D02*
G03X1626984Y1379734I0J394D01*
G01Y1377372D02*
G03X1626590Y1377766I-394J0D01*
G01Y1394340D02*
G03X1626984Y1394734I0J394D01*
G01Y1392372D02*
G03X1626590Y1392766I-394J0D01*
G01Y1389340D02*
G03X1626984Y1389734I0J394D01*
G01Y1387372D02*
G03X1626590Y1387766I-394J0D01*
G01Y1384340D02*
G03X1626984Y1384734I0J394D01*
G01Y1382372D02*
G03X1626590Y1382766I-394J0D01*
G01Y1369340D02*
G03X1626984Y1369734I0J394D01*
G01Y1367372D02*
G03X1626590Y1367766I-394J0D01*
G01X1621394Y1425856D02*
G03I-2166J0D01*
G01X1617274Y1428573D02*
G03Y1423140I1954J-2716D01*
G01X1621183D02*
G03Y1428573I-1955J2717D01*
G01X1622732Y1425856D02*
G03I-3504J0D01*
G01X1621532Y1421959D02*
G03Y1429754I-2304J3898D01*
G01X1616925D02*
G03Y1421959I2303J-3898D01*
G01X1615312Y1428447D02*
G03X1614721Y1428082I-9J-646D01*
G01X1616085Y1427639D02*
G03X1615312Y1428447I-791J17D01*
G01X1614060Y1429151D02*
G03X1613217Y1428082I704J-1422D01*
G01X1613426Y1426196D02*
G03X1614660Y1425222I1735J930D01*
G01X1616303Y1425266D02*
G03X1617467Y1426404I-730J1911D01*
G01X1617381Y1428420D02*
G03X1615642Y1429438I-1807J-1093D01*
G01X1614660Y1425223D02*
G03X1616303Y1425266I757J2475D01*
G01X1617641Y1427560D02*
G03X1617380Y1428423I-2971J-428D01*
G01X1613087Y1427639D02*
G03X1613426Y1426196I3015J-53D01*
G01X1617641Y1427065D02*
G03Y1427562I-3524J249D01*
G01X1617468Y1426404D02*
G03X1617641Y1427065I-4020J1405D01*
G01X1614660Y1426813D02*
G03X1616085I713J-83D01*
G01X1615646Y1429438D02*
G03X1614060Y1429151I-263J-3073D01*
G01X1621532Y1429754D02*
X1616925D01*
G01X1660764Y1429459D02*
X1634386D01*
G01X1610117Y1429238D02*
X1608567D01*
G01X1613061D02*
X1611653D01*
G01X1619693D02*
X1618232D01*
G01X1629774D02*
X1628315D01*
G01X1626884D02*
X1625492D01*
G01X1632645D02*
X1631205D01*
G01X1630449Y1428671D02*
X1606827D01*
G01X1617274Y1428573D02*
X1621183D01*
G01X1614721Y1428082D02*
X1613217D01*
G01X1616087Y1427639D02*
X1613087D01*
G01X1616086Y1426813D02*
X1614660D01*
G01X1609975Y1425231D02*
X1608593D01*
G01X1612887D02*
X1611270D01*
G01X1632645D02*
X1631202D01*
G01X1630449Y1424892D02*
X1606827D01*
G01X1619693Y1423484D02*
X1618232D01*
G01X1621183Y1423140D02*
X1617274D01*
G01X1630449Y1422923D02*
X1606827D01*
G01X1656827Y1422293D02*
X1606827D01*
G01X1616925Y1421959D02*
X1621532D01*
G01X1606827Y1420522D02*
X1630449D01*
G01X1621987Y1419990D02*
X1628087D01*
G01X1621987Y1419931D02*
X1628087D01*
G01X1607619Y1419537D02*
X1628087D01*
G01X1626984Y1418356D02*
X1636354D01*
G01X1658795Y1417766D02*
X1628087D01*
G01X1656827Y1417372D02*
X1638323D01*
G01X1636669Y1417175D02*
X1630134D01*
G01X1606827Y1416762D02*
X1626984D01*
G01Y1416585D02*
X1636354D01*
G01X1624543Y1415128D02*
X1623559D01*
G01X1622968Y1415010D02*
X1613984D01*
G01X1624543Y1414931D02*
X1623559D01*
G01X1624543Y1414537D02*
X1623559D01*
G01X1619425Y1414340D02*
X1626590D01*
G01X1615931Y1413337D02*
X1608598D01*
G01X1628087D02*
X1616078D01*
G01X1619425Y1412766D02*
X1626590D01*
G01X1624543Y1412569D02*
X1623559D01*
G01X1616078Y1412549D02*
X1628087D01*
G01X1608598D02*
X1615931D01*
G01X1624543Y1412175D02*
X1623559D01*
G01X1624543Y1411978D02*
X1623559D01*
G01X1615931Y1410187D02*
X1608598D01*
G01X1628087D02*
X1616078D01*
G01X1624543Y1410128D02*
X1623559D01*
G01X1624543Y1409931D02*
X1623559D01*
G01X1624543Y1409537D02*
X1623559D01*
G01X1616078Y1409400D02*
X1628087D01*
G01X1608598D02*
X1615931D01*
G01X1619425Y1409340D02*
X1626590D01*
G01X1619425Y1407766D02*
X1626590D01*
G01X1624543Y1407569D02*
X1623559D01*
G01X1624543Y1407175D02*
X1623559D01*
G01X1615931Y1407037D02*
X1608598D01*
G01X1628087D02*
X1616078D01*
G01X1624543Y1406978D02*
X1623559D01*
G01X1616078Y1406250D02*
X1628087D01*
G01X1608598D02*
X1615931D01*
G01X1624543Y1405128D02*
X1623559D01*
G01X1624543Y1404931D02*
X1623559D01*
G01X1624543Y1404537D02*
X1623559D01*
G01X1619425Y1404340D02*
X1626590D01*
G01X1615931Y1403888D02*
X1608598D01*
G01X1628087D02*
X1616078D01*
G01Y1403100D02*
X1628087D01*
G01X1608598D02*
X1615931D01*
G01X1619425Y1402766D02*
X1626590D01*
G01X1624543Y1402569D02*
X1623559D01*
G01X1624543Y1402175D02*
X1623559D01*
G01X1624543Y1401978D02*
X1623559D01*
G01X1628087Y1400758D02*
X1626984D01*
G01X1615931Y1400738D02*
X1608598D01*
G01X1628087D02*
X1616078D01*
G01X1626512Y1400128D02*
X1625527D01*
G01X1616078Y1399951D02*
X1628087D01*
G01X1608598D02*
X1615931D01*
G01X1626512Y1399931D02*
X1625527D01*
G01X1656827Y1399655D02*
X1630134D01*
G01X1626512Y1399537D02*
X1625527D01*
G01X1626984Y1399340D02*
X1621394D01*
G01X1626984Y1397766D02*
X1621394D01*
G01X1615931Y1397588D02*
X1608598D01*
G01X1628087D02*
X1616078D01*
G01X1626512Y1397569D02*
X1625527D01*
G01X1656827Y1397293D02*
X1630134D01*
G01X1626512Y1397175D02*
X1625527D01*
G01X1626512Y1396978D02*
X1625527D01*
G01X1616078Y1396801D02*
X1628087D01*
G01X1608598D02*
X1615931D01*
G01X1628087Y1396348D02*
X1626984D01*
G01X1624543Y1395128D02*
X1623559D01*
G01X1624543Y1394931D02*
X1623559D01*
G01X1624543Y1394537D02*
X1623559D01*
G01X1615931Y1394439D02*
X1608598D01*
G01X1628087D02*
X1616078D01*
G01X1619425Y1394340D02*
X1626590D01*
G01X1616078Y1393651D02*
X1628087D01*
G01X1608598D02*
X1615931D01*
G01X1619425Y1392766D02*
X1626590D01*
G01X1624543Y1392569D02*
X1623559D01*
G01X1624543Y1392175D02*
X1623559D01*
G01X1624543Y1391978D02*
X1623559D01*
G01X1615931Y1391289D02*
X1608598D01*
G01X1628087D02*
X1616078D01*
G01Y1390502D02*
X1628087D01*
G01X1608598D02*
X1615931D01*
G01X1624543Y1390128D02*
X1623559D01*
G01X1624543Y1389931D02*
X1623559D01*
G01X1624543Y1389537D02*
X1623559D01*
G01X1619425Y1389340D02*
X1626590D01*
G01X1615931Y1388140D02*
X1608598D01*
G01X1628087D02*
X1616078D01*
G01X1619425Y1387766D02*
X1626590D01*
G01X1624543Y1387569D02*
X1623559D01*
G01X1616078Y1387352D02*
X1628087D01*
G01X1608598D02*
X1615931D01*
G01X1624543Y1387175D02*
X1623559D01*
G01X1624543Y1386978D02*
X1623559D01*
G01X1624543Y1385128D02*
X1623559D01*
G01X1615931Y1384990D02*
X1608598D01*
G01X1628087D02*
X1616078D01*
G01X1624543Y1384931D02*
X1623559D01*
G01X1624543Y1384537D02*
X1623559D01*
G01X1619425Y1384340D02*
X1626590D01*
G01X1616078Y1384203D02*
X1628087D01*
G01X1608598D02*
X1615931D01*
G01X1619425Y1382766D02*
X1626590D01*
G01X1624543Y1382569D02*
X1623559D01*
G01X1624543Y1382175D02*
X1623559D01*
G01X1624543Y1381978D02*
X1623559D01*
G01X1615931Y1381840D02*
X1608598D01*
G01X1628087D02*
X1616078D01*
G01Y1381053D02*
X1628087D01*
G01X1608598D02*
X1615931D01*
G01X1656827Y1380758D02*
X1630134D01*
G01X1624543Y1380128D02*
X1623559D01*
G01X1624543Y1379931D02*
X1623559D01*
G01X1624543Y1379537D02*
X1623559D01*
G01X1619425Y1379340D02*
X1626590D01*
G01X1615931Y1378691D02*
X1608598D01*
G01X1628087D02*
X1616078D01*
G01X1656827Y1378396D02*
X1630134D01*
G01X1616078Y1377903D02*
X1628087D01*
G01X1608598D02*
X1615931D01*
G01X1619425Y1377766D02*
X1626590D01*
G01X1624543Y1377569D02*
X1623559D01*
G01X1624543Y1377175D02*
X1623559D01*
G01X1624543Y1376978D02*
X1623559D01*
G01X1615931Y1375541D02*
X1608598D01*
G01X1628087D02*
X1616078D01*
G01X1624543Y1375128D02*
X1623559D01*
G01X1624543Y1374931D02*
X1623559D01*
G01X1616078Y1374754D02*
X1628087D01*
G01X1608598D02*
X1615931D01*
G01X1624543Y1374537D02*
X1623559D01*
G01X1619425Y1374340D02*
X1626590D01*
G01X1619425Y1372766D02*
X1626590D01*
G01X1624543Y1372569D02*
X1623559D01*
G01X1615931Y1372392D02*
X1608598D01*
G01X1628087D02*
X1616078D01*
G01X1624543Y1372175D02*
X1623559D01*
G01X1624543Y1371978D02*
X1623559D01*
G01X1616078Y1371604D02*
X1628087D01*
G01X1608598D02*
X1615931D01*
G01X1624543Y1370128D02*
X1623559D01*
G01X1624543Y1369931D02*
X1623559D01*
G01X1624543Y1369537D02*
X1623559D01*
G01X1619425Y1369340D02*
X1626590D01*
G01X1615931Y1369242D02*
X1608598D01*
G01X1628087D02*
X1616078D01*
G01Y1368455D02*
X1628087D01*
G01X1608598D02*
X1615931D01*
G01X1619425Y1367766D02*
X1626590D01*
G01X1624543Y1367569D02*
X1623559D01*
G01X1624543Y1367175D02*
X1623559D01*
G01X1624543Y1366978D02*
X1623559D01*
G01X1615931Y1366092D02*
X1608598D01*
G01X1628087D02*
X1616078D01*
G01Y1365305D02*
X1628087D01*
G01X1608598D02*
X1615931D01*
G01X1624543Y1365128D02*
X1623559D01*
G01X1624543Y1364931D02*
X1623559D01*
G01X1624543Y1364537D02*
X1623559D01*
G01X1619425Y1364340D02*
X1626590D01*
G01X1615931Y1362943D02*
X1608598D01*
G01X1628087D02*
X1616078D01*
G01X1619425Y1362766D02*
X1626590D01*
G01X1624543Y1362569D02*
X1623559D01*
G01X1624543Y1362175D02*
X1623559D01*
G01X1616078Y1362155D02*
X1628087D01*
G01X1608598D02*
X1615931D01*
G01X1624543Y1361978D02*
X1623559D01*
G01X1656827Y1361860D02*
X1630134D01*
G01X1626984Y1360758D02*
X1628087D01*
G01X1626512Y1360128D02*
X1625527D01*
G01X1626512Y1359931D02*
X1625527D01*
G01X1608567Y1429238D02*
X1609888Y1427082D01*
G01X1610665Y1426217D02*
X1611270Y1425231D01*
G01X1611618Y1427091D02*
X1612887Y1425231D01*
G01X1621183Y1423140D02*
X1621200Y1423084D01*
X1621253Y1422918D01*
X1621332Y1422660D01*
X1621427Y1422332D01*
X1621532Y1421959D01*
G01X1617274Y1428573D02*
X1617256Y1428629D01*
X1617204Y1428794D01*
X1617125Y1429053D01*
X1617029Y1429380D01*
X1616925Y1429754D01*
G01X1610117Y1429238D02*
X1610862Y1427960D01*
G01X1636669Y1417175D02*
Y1443573D01*
G01X1636354Y1418356D02*
Y1416585D01*
G01X1634386Y1430640D02*
Y1422293D01*
G01X1632645Y1429238D02*
Y1425231D01*
G01X1632102Y1399655D02*
Y1417175D01*
G01Y1380758D02*
Y1397293D01*
G01Y1361860D02*
Y1378396D01*
G01X1631205Y1426713D02*
Y1429238D01*
G01X1631202Y1425788D02*
Y1425231D01*
G01X1630449Y1422923D02*
Y1420522D01*
G01Y1428671D02*
Y1424892D01*
G01X1629774Y1429238D02*
Y1426713D01*
G01X1628315D02*
Y1429238D01*
G01X1626884D02*
Y1426713D01*
G01X1626512Y1400128D02*
Y1396978D01*
G01X1626145Y1412549D02*
Y1413337D01*
G01Y1409400D02*
Y1410187D01*
G01Y1403100D02*
Y1403888D01*
G01Y1406250D02*
Y1407037D01*
G01Y1399951D02*
Y1400738D01*
G01Y1393651D02*
Y1394439D01*
G01Y1396801D02*
Y1397588D01*
G01Y1390502D02*
Y1391289D01*
G01Y1384203D02*
Y1384990D01*
G01Y1387352D02*
Y1388140D01*
G01Y1381053D02*
Y1381840D01*
G01Y1374754D02*
Y1375541D01*
G01Y1377903D02*
Y1378691D01*
G01Y1371604D02*
Y1372392D01*
G01Y1365305D02*
Y1366092D01*
G01Y1368455D02*
Y1369242D01*
G01Y1362155D02*
Y1362943D01*
G01X1626118Y1412549D02*
Y1413337D01*
G01Y1409400D02*
Y1410187D01*
G01Y1403100D02*
Y1403888D01*
G01Y1406250D02*
Y1407037D01*
G01Y1399951D02*
Y1400738D01*
G01Y1393651D02*
Y1394439D01*
G01Y1396801D02*
Y1397588D01*
G01Y1390502D02*
Y1391289D01*
G01Y1384203D02*
Y1384990D01*
G01Y1387352D02*
Y1388140D01*
G01Y1381053D02*
Y1381840D01*
G01Y1374754D02*
Y1375541D01*
G01Y1377903D02*
Y1378691D01*
G01Y1371604D02*
Y1372392D01*
G01Y1365305D02*
Y1366092D01*
G01Y1368455D02*
Y1369242D01*
G01Y1362155D02*
Y1362943D01*
G01X1625742Y1412549D02*
Y1413337D01*
G01Y1409400D02*
Y1410187D01*
G01Y1403100D02*
Y1403888D01*
G01Y1406250D02*
Y1407037D01*
G01Y1399951D02*
Y1400738D01*
G01Y1393651D02*
Y1394439D01*
G01Y1396801D02*
Y1397588D01*
G01Y1390502D02*
Y1391289D01*
G01Y1384203D02*
Y1384990D01*
G01Y1387352D02*
Y1388140D01*
G01Y1381053D02*
Y1381840D01*
G01Y1374754D02*
Y1375541D01*
G01Y1377903D02*
Y1378691D01*
G01Y1371604D02*
Y1372392D01*
G01Y1365305D02*
Y1366092D01*
G01Y1368455D02*
Y1369242D01*
G01Y1362155D02*
Y1362943D01*
G01X1625527Y1364340D02*
Y1362766D01*
G01Y1369340D02*
Y1367766D01*
G01Y1374340D02*
Y1372766D01*
G01Y1379340D02*
Y1377766D01*
G01Y1384340D02*
Y1382766D01*
G01Y1389340D02*
Y1387766D01*
G01Y1394340D02*
Y1392766D01*
G01Y1400128D02*
Y1396978D01*
G01Y1404340D02*
Y1402766D01*
G01Y1409340D02*
Y1407766D01*
G01Y1414340D02*
Y1412766D01*
G01X1625492Y1429238D02*
Y1426309D01*
G01X1624543Y1365128D02*
Y1361978D01*
G01Y1370128D02*
Y1366978D01*
G01Y1375128D02*
Y1371978D01*
G01Y1380128D02*
Y1376978D01*
G01Y1385128D02*
Y1381978D01*
G01Y1390128D02*
Y1386978D01*
G01Y1395128D02*
Y1391978D01*
G01Y1399340D02*
Y1397766D01*
G01Y1405128D02*
Y1401978D01*
G01Y1410128D02*
Y1406978D01*
G01Y1415128D02*
Y1411978D01*
G01Y1422293D02*
Y1419990D01*
G01X1623559Y1365128D02*
Y1361978D01*
G01Y1370128D02*
Y1366978D01*
G01Y1375128D02*
Y1371978D01*
G01Y1380128D02*
Y1376978D01*
G01Y1385128D02*
Y1381978D01*
G01Y1390128D02*
Y1386978D01*
G01Y1395128D02*
Y1391978D01*
G01Y1405128D02*
Y1401978D01*
G01Y1410128D02*
Y1406978D01*
G01Y1415128D02*
Y1411978D01*
G01X1622575Y1364340D02*
Y1362766D01*
G01Y1369340D02*
Y1367766D01*
G01Y1374340D02*
Y1372766D01*
G01Y1379340D02*
Y1377766D01*
G01Y1384340D02*
Y1382766D01*
G01Y1389340D02*
Y1387766D01*
G01Y1394340D02*
Y1392766D01*
G01Y1404340D02*
Y1402766D01*
G01Y1409340D02*
Y1407766D01*
G01Y1414340D02*
Y1412766D01*
G01X1622380Y1362943D02*
Y1362155D01*
G01Y1366092D02*
Y1365305D01*
G01Y1369242D02*
Y1368455D01*
G01Y1372392D02*
Y1371604D01*
G01Y1375541D02*
Y1374754D01*
G01Y1378691D02*
Y1377903D01*
G01Y1381840D02*
Y1381053D01*
G01Y1384990D02*
Y1384203D01*
G01Y1388140D02*
Y1387352D01*
G01Y1391289D02*
Y1390502D01*
G01Y1394439D02*
Y1393651D01*
G01Y1397588D02*
Y1396801D01*
G01Y1400738D02*
Y1399951D01*
G01Y1403888D02*
Y1403100D01*
G01Y1407037D02*
Y1406250D01*
G01Y1410187D02*
Y1409400D01*
G01Y1413337D02*
Y1412549D01*
G01X1621987Y1419990D02*
Y1419931D01*
G01X1621394Y1399340D02*
Y1397766D01*
G01X1621348Y1419537D02*
Y1422293D01*
G01X1620396Y1362943D02*
Y1362155D01*
G01Y1366092D02*
Y1365305D01*
G01Y1369242D02*
Y1368455D01*
G01Y1372392D02*
Y1371604D01*
G01Y1375541D02*
Y1374754D01*
G01Y1378691D02*
Y1377903D01*
G01Y1381840D02*
Y1381053D01*
G01Y1384990D02*
Y1384203D01*
G01Y1388140D02*
Y1387352D01*
G01Y1391289D02*
Y1390502D01*
G01Y1394439D02*
Y1393651D01*
G01Y1397588D02*
Y1396801D01*
G01Y1400738D02*
Y1399951D01*
G01Y1403888D02*
Y1403100D01*
G01Y1407037D02*
Y1406250D01*
G01Y1410187D02*
Y1409400D01*
G01Y1413337D02*
Y1412549D01*
G01X1619693Y1429238D02*
Y1423484D01*
G01X1619425Y1364340D02*
Y1362766D01*
G01Y1369340D02*
Y1367766D01*
G01Y1374340D02*
Y1372766D01*
G01Y1379340D02*
Y1377766D01*
G01Y1384340D02*
Y1382766D01*
G01Y1389340D02*
Y1387766D01*
G01Y1394340D02*
Y1392766D01*
G01Y1404340D02*
Y1402766D01*
G01Y1409340D02*
Y1407766D01*
G01Y1414340D02*
Y1412766D01*
G01X1618745Y1412549D02*
Y1413337D01*
G01Y1409400D02*
Y1410187D01*
G01Y1403100D02*
Y1403888D01*
G01Y1406250D02*
Y1407037D01*
G01Y1399951D02*
Y1400738D01*
G01Y1393651D02*
Y1394439D01*
G01Y1396801D02*
Y1397588D01*
G01Y1390502D02*
Y1391289D01*
G01Y1384203D02*
Y1384990D01*
G01Y1387352D02*
Y1388140D01*
G01Y1381053D02*
Y1381840D01*
G01Y1374754D02*
Y1375541D01*
G01Y1377903D02*
Y1378691D01*
G01Y1371604D02*
Y1372392D01*
G01Y1365305D02*
Y1366092D01*
G01Y1368455D02*
Y1369242D01*
G01Y1362155D02*
Y1362943D01*
G01X1618232Y1429238D02*
Y1423484D01*
G01X1617016Y1365305D02*
Y1362943D01*
G01Y1368455D02*
Y1366092D01*
G01Y1371604D02*
Y1369242D01*
G01Y1374754D02*
Y1372392D01*
G01Y1377903D02*
Y1375541D01*
G01Y1381053D02*
Y1378691D01*
G01Y1384203D02*
Y1381840D01*
G01Y1387352D02*
Y1384990D01*
G01Y1390502D02*
Y1388140D01*
G01Y1393651D02*
Y1391289D01*
G01Y1396801D02*
Y1394439D01*
G01Y1399951D02*
Y1397588D01*
G01Y1403100D02*
Y1400738D01*
G01Y1406250D02*
Y1403888D01*
G01Y1409400D02*
Y1407037D01*
G01Y1412549D02*
Y1410187D01*
G01Y1415010D02*
Y1413337D01*
G01X1616078Y1412549D02*
Y1413337D01*
G01Y1409400D02*
Y1410187D01*
G01Y1403100D02*
Y1403888D01*
G01Y1406250D02*
Y1407037D01*
G01Y1399951D02*
Y1400738D01*
G01Y1393651D02*
Y1394439D01*
G01Y1396801D02*
Y1397588D01*
G01Y1390502D02*
Y1391289D01*
G01Y1384203D02*
Y1384990D01*
G01Y1387352D02*
Y1388140D01*
G01Y1381053D02*
Y1381840D01*
G01Y1374754D02*
Y1375541D01*
G01Y1377903D02*
Y1378691D01*
G01Y1371604D02*
Y1372392D01*
G01Y1365305D02*
Y1366092D01*
G01Y1368455D02*
Y1369242D01*
G01Y1362155D02*
Y1362943D01*
G01X1615931Y1412549D02*
Y1413337D01*
G01Y1409400D02*
Y1410187D01*
G01Y1403100D02*
Y1403888D01*
G01Y1406250D02*
Y1407037D01*
G01Y1399951D02*
Y1400738D01*
G01Y1393651D02*
Y1394439D01*
G01Y1396801D02*
Y1397588D01*
G01Y1390502D02*
Y1391289D01*
G01Y1384203D02*
Y1384990D01*
G01Y1387352D02*
Y1388140D01*
G01Y1381053D02*
Y1381840D01*
G01Y1374754D02*
Y1375541D01*
G01Y1377903D02*
Y1378691D01*
G01Y1371604D02*
Y1372392D01*
G01Y1365305D02*
Y1366092D01*
G01Y1368455D02*
Y1369242D01*
G01Y1362155D02*
Y1362943D01*
G01X1614338Y1412549D02*
Y1413337D01*
G01Y1409400D02*
Y1410187D01*
G01Y1403100D02*
Y1403888D01*
G01Y1406250D02*
Y1407037D01*
G01Y1399951D02*
Y1400738D01*
G01Y1393651D02*
Y1394439D01*
G01Y1396801D02*
Y1397588D01*
G01Y1390502D02*
Y1391289D01*
G01Y1384203D02*
Y1384990D01*
G01Y1387352D02*
Y1388140D01*
G01Y1381053D02*
Y1381840D01*
G01Y1374754D02*
Y1375541D01*
G01Y1377903D02*
Y1378691D01*
G01Y1371604D02*
Y1372392D01*
G01Y1365305D02*
Y1366092D01*
G01Y1368455D02*
Y1369242D01*
G01Y1362155D02*
Y1362943D01*
G01X1613474Y1419537D02*
Y1422293D01*
G01X1613397Y1362943D02*
Y1362155D01*
G01Y1366092D02*
Y1365305D01*
G01Y1369242D02*
Y1368455D01*
G01Y1372392D02*
Y1371604D01*
G01Y1375541D02*
Y1374754D01*
G01Y1378691D02*
Y1377903D01*
G01Y1381840D02*
Y1381053D01*
G01Y1384990D02*
Y1384203D01*
G01Y1388140D02*
Y1387352D01*
G01Y1391289D02*
Y1390502D01*
G01Y1394439D02*
Y1393651D01*
G01Y1397588D02*
Y1396801D01*
G01Y1400738D02*
Y1399951D01*
G01Y1403888D02*
Y1403100D01*
G01Y1407037D02*
Y1406250D01*
G01Y1410187D02*
Y1409400D01*
G01Y1413337D02*
Y1412549D01*
G01X1610560Y1362943D02*
Y1362155D01*
G01Y1366092D02*
Y1365305D01*
G01Y1369242D02*
Y1368455D01*
G01Y1372392D02*
Y1371604D01*
G01Y1375541D02*
Y1374754D01*
G01Y1378691D02*
Y1377903D01*
G01Y1381840D02*
Y1381053D01*
G01Y1384990D02*
Y1384203D01*
G01Y1388140D02*
Y1387352D01*
G01Y1391289D02*
Y1390502D01*
G01Y1394439D02*
Y1393651D01*
G01Y1397588D02*
Y1396801D01*
G01Y1400738D02*
Y1399951D01*
G01Y1403888D02*
Y1403100D01*
G01Y1407037D02*
Y1406250D01*
G01Y1410187D02*
Y1409400D01*
G01Y1413337D02*
Y1412549D01*
G01X1610372D02*
Y1413337D01*
G01Y1409400D02*
Y1410187D01*
G01Y1403100D02*
Y1403888D01*
G01Y1406250D02*
Y1407037D01*
G01Y1399951D02*
Y1400738D01*
G01Y1393651D02*
Y1394439D01*
G01Y1396801D02*
Y1397588D01*
G01Y1390502D02*
Y1391289D01*
G01Y1384203D02*
Y1384990D01*
G01Y1387352D02*
Y1388140D01*
G01Y1381053D02*
Y1381840D01*
G01Y1374754D02*
Y1375541D01*
G01Y1377903D02*
Y1378691D01*
G01Y1371604D02*
Y1372392D01*
G01Y1365305D02*
Y1366092D01*
G01Y1368455D02*
Y1369242D01*
G01Y1362155D02*
Y1362943D01*
G01X1608598Y1412549D02*
Y1413337D01*
G01Y1409400D02*
Y1410187D01*
G01Y1403100D02*
Y1403888D01*
G01Y1406250D02*
Y1407037D01*
G01Y1399951D02*
Y1400738D01*
G01Y1393651D02*
Y1394439D01*
G01Y1396801D02*
Y1397588D01*
G01Y1390502D02*
Y1391289D01*
G01Y1384203D02*
Y1384990D01*
G01Y1387352D02*
Y1388140D01*
G01Y1381053D02*
Y1381840D01*
G01Y1374754D02*
Y1375541D01*
G01Y1377903D02*
Y1378691D01*
G01Y1371604D02*
Y1372392D01*
G01Y1365305D02*
Y1366092D01*
G01Y1368455D02*
Y1369242D01*
G01Y1362155D02*
Y1362943D01*
G01X1607619Y1419537D02*
Y1416762D01*
G01X1607144Y1422293D02*
Y1416762D01*
G01X1606827Y1430640D02*
Y1416762D01*
G01X1609888Y1427082D02*
X1608593Y1425231D01*
G01X1610665Y1426217D02*
X1609975Y1425231D01*
G01X1613061Y1429238D02*
X1611618Y1427091D01*
G01X1621987Y1419931D02*
X1621731Y1419537D01*
G01X1611653Y1429238D02*
X1610862Y1427960D01*
G01X1617274Y1423140D02*
X1617256Y1423084D01*
X1617204Y1422919D01*
X1617125Y1422660D01*
X1617029Y1422333D01*
X1616925Y1421959D01*
G01X1621532Y1429754D02*
X1621429Y1429385D01*
X1621332Y1429055D01*
X1621252Y1428793D01*
X1621200Y1428627D01*
X1621183Y1428573D01*
G01X1606827Y1430640D02*
X1660764D01*
G01X1620291Y1443573D02*
Y1430640D01*
G01X1630646Y1436092D02*
G03Y1439242I0J1575D01*
G01X1626315D02*
G03Y1436092I0J-1575D01*
G01X1609491Y1491660D02*
X1612414D01*
G01X1638092Y1487330D02*
X1637604D01*
Y1488052D01*
X1638092Y1487330D01*
G01X1639055Y1474661D02*
X1640029D01*
G01X1618737Y1473939D02*
X1621660D01*
G01X1636669Y1443573D02*
X1620291D01*
G01X1626315Y1439242D02*
X1630646D01*
G01X1625689Y1438455D02*
X1631271D01*
G01Y1436880D02*
X1625689D01*
G01X1630646Y1436092D02*
X1626315D01*
G01X1636669Y1433396D02*
X1620291D01*
G01X1629809Y1492382D02*
X1628835Y1493104D01*
X1628347Y1493826D01*
Y1494548D01*
X1628835Y1495269D01*
X1629809Y1495991D01*
X1630784D01*
X1631758Y1495269D01*
X1632245Y1494548D01*
Y1493826D01*
X1631758Y1493104D01*
X1630784Y1492382D01*
G01X1629809Y1487330D02*
X1628835Y1488052D01*
G01X1631758Y1491660D02*
X1632732Y1490217D01*
Y1489495D01*
G01X1628835Y1488052D02*
X1627860Y1489495D01*
Y1490217D01*
G01X1638080Y1477548D02*
X1639055Y1478270D01*
X1640029D01*
X1641004Y1477548D01*
X1641491Y1476827D01*
Y1476105D01*
X1641004Y1475383D01*
X1640029Y1474661D01*
X1641004Y1473939D01*
G01X1631271Y1436880D02*
Y1438455D01*
G01X1631236D02*
Y1436880D01*
G01X1631212Y1438455D02*
Y1436880D01*
G01X1629889D02*
Y1438455D01*
G01X1629519D02*
Y1436880D01*
G01X1627442D02*
Y1438455D01*
G01X1627072D02*
Y1436880D01*
G01X1625748D02*
Y1438455D01*
G01X1625724Y1436880D02*
Y1438455D01*
G01X1625689D02*
Y1436880D01*
G01X1613865Y1474661D02*
X1611916Y1473218D01*
X1610941Y1471774D01*
X1610454Y1469609D01*
X1614352D01*
G01X1604619Y1492382D02*
X1602670Y1490939D01*
X1601696Y1489495D01*
X1601208Y1487330D01*
X1605106D01*
G01X1641978Y1471774D02*
X1641004Y1470331D01*
X1640029Y1469609D01*
X1639055D01*
X1638080Y1470331D01*
X1637593Y1471052D01*
G01X1632732Y1489495D02*
X1631758Y1488052D01*
X1630784Y1487330D01*
X1629809D01*
G01X1627860Y1490217D02*
X1628835Y1491660D01*
X1629809Y1492382D01*
X1630784D01*
X1631758Y1491660D01*
G01X1610454Y1476827D02*
X1610941Y1477548D01*
X1611916Y1478270D01*
X1612890D01*
X1613865Y1477548D01*
X1614352Y1476827D01*
Y1475383D01*
X1613865Y1474661D01*
G01X1601208Y1494548D02*
X1601696Y1495269D01*
X1602670Y1495991D01*
X1603644D01*
X1604619Y1495269D01*
X1605106Y1494548D01*
Y1493104D01*
X1604619Y1492382D01*
G01X1624818Y1467444D02*
X1632035Y1480436D01*
G01X1615572Y1485164D02*
X1622790Y1498157D01*
G01X1624096Y1473939D02*
X1624818Y1476105D01*
X1626261Y1477548D01*
X1628427Y1478270D01*
X1630592Y1477548D01*
X1632035Y1476105D01*
X1632757Y1473939D01*
X1632035Y1471774D01*
X1630592Y1470331D01*
X1628427Y1469609D01*
X1626261Y1470331D01*
X1624818Y1471774D01*
X1624096Y1473939D01*
G01X1614850Y1491660D02*
X1615572Y1493826D01*
X1617015Y1495269D01*
X1619181Y1495991D01*
X1621346Y1495269D01*
X1622790Y1493826D01*
X1623512Y1491660D01*
X1622790Y1489495D01*
X1621346Y1488052D01*
X1619181Y1487330D01*
X1617015Y1488052D01*
X1615572Y1489495D01*
X1614850Y1491660D01*
G01X1599844Y1467443D02*
X1714463D01*
G01X1596694D02*
X1599844D01*
G01X1590598Y1485164D02*
X1884509D01*
G01X1587449D02*
X1590598D01*
G01X1631630Y1651171D02*
G03Y1649990I0J-590D01*
G01X1625331D02*
G03Y1651171I0J591D01*
G01X1625341Y1650919D02*
X1625435D01*
G01Y1650171D02*
X1625341D01*
G01X1630055Y1649695D02*
X1633205D01*
G01X1626905D02*
X1623756D01*
G01X1625331Y1649400D02*
X1631630D01*
G01X1633205Y1649695D02*
Y1651663D01*
G01X1631630Y1651171D02*
Y1652746D01*
G01Y1649400D02*
Y1649990D01*
G01X1630646Y1649400D02*
Y1654518D01*
G01X1630449D02*
Y1649400D01*
G01X1630055Y1651663D02*
Y1649695D01*
G01X1626905Y1651663D02*
Y1649695D01*
G01X1626512Y1654518D02*
Y1649400D01*
G01X1626315D02*
Y1654518D01*
G01X1625435Y1650919D02*
Y1650171D01*
G01X1625341D02*
Y1650792D01*
G01X1625331Y1649990D02*
Y1649400D01*
G01Y1652746D02*
Y1651171D01*
G01X1625248Y1650680D02*
Y1650808D01*
G01X1623756Y1649695D02*
Y1651663D01*
G01X1625341Y1650792D02*
X1625248Y1650680D01*
G01Y1650808D02*
X1625341Y1650919D01*
G01X1631630Y1653927D02*
G03Y1652746I0J-590D01*
G01X1630646Y1668376D02*
G03Y1671525I0J1575D01*
G01X1631864Y1683366D02*
G03X1629649Y1678199I6937J-6032D01*
G01X1632749Y1683440D02*
G03X1630535Y1678199I7143J-6105D01*
G01X1626590Y1719852D02*
G03X1626984Y1720246I0J394D01*
G01Y1717884D02*
G03X1626590Y1718277I-393J0D01*
G01Y1714852D02*
G03X1626984Y1715246I0J394D01*
G01Y1712884D02*
G03X1626590Y1713277I-393J0D01*
G01Y1709852D02*
G03X1626984Y1710246I0J394D01*
G01Y1707884D02*
G03X1626590Y1708277I-393J0D01*
G01Y1694852D02*
G03X1626984Y1695246I0J394D01*
G01Y1692884D02*
G03X1626590Y1693277I-393J0D01*
G01Y1704852D02*
G03X1626984Y1705246I0J394D01*
G01Y1702884D02*
G03X1626590Y1703277I-393J0D01*
G01Y1699852D02*
G03X1626984Y1700246I0J394D01*
G01Y1697884D02*
G03X1626590Y1698277I-393J0D01*
G01X1625392Y1679921D02*
G03X1624851Y1678937I1277J-1343D01*
G01X1625331Y1652746D02*
G03Y1653927I0J591D01*
G01X1626315Y1671525D02*
G03Y1668376I0J-1574D01*
G01X1624887Y1680465D02*
G03X1623817Y1678642I2809J-2875D01*
G01X1621394Y1681762D02*
G03I-2166J0D01*
G01X1622575D02*
G03I-3347J0D01*
G01X1622732D02*
G03I-3504J0D01*
G01X1623756D02*
G03I-4528J0D01*
G01X1611416Y1683366D02*
G03X1609201Y1678199I6937J-6032D01*
G01X1612301Y1683440D02*
G03X1610087Y1678199I7143J-6105D01*
G01X1630358Y1691821D02*
X1630706Y1691906D01*
G01X1632013Y1691565D02*
X1632362Y1691650D01*
G01X1624543Y1720640D02*
X1623559D01*
G01X1657784Y1720463D02*
X1638323D01*
G01X1624543Y1720443D02*
X1623559D01*
G01X1616078Y1720423D02*
X1628087D01*
G01X1608598D02*
X1615931D01*
G01X1624543Y1720049D02*
X1623559D01*
G01X1619425Y1719852D02*
X1626590D01*
G01X1619425Y1718277D02*
X1626590D01*
G01X1624543Y1718081D02*
X1623559D01*
G01X1615931Y1718061D02*
X1608598D01*
G01X1628087D02*
X1616078D01*
G01X1624543Y1717687D02*
X1623559D01*
G01X1624543Y1717490D02*
X1623559D01*
G01X1616078Y1717274D02*
X1628087D01*
G01X1608598D02*
X1615931D01*
G01X1624543Y1715640D02*
X1623559D01*
G01X1624543Y1715443D02*
X1623559D01*
G01X1624543Y1715049D02*
X1623559D01*
G01X1615931Y1714911D02*
X1608598D01*
G01X1628087D02*
X1616078D01*
G01X1619425Y1714852D02*
X1626590D01*
G01X1616078Y1714124D02*
X1628087D01*
G01X1608598D02*
X1615931D01*
G01X1619425Y1713277D02*
X1626590D01*
G01X1624543Y1713081D02*
X1623559D01*
G01X1624543Y1712687D02*
X1623559D01*
G01X1624543Y1712490D02*
X1623559D01*
G01X1615931Y1711762D02*
X1608598D01*
G01X1628087D02*
X1616078D01*
G01Y1710974D02*
X1628087D01*
G01X1608598D02*
X1615931D01*
G01X1624543Y1710640D02*
X1623559D01*
G01X1624543Y1710443D02*
X1623559D01*
G01X1624543Y1710049D02*
X1623559D01*
G01X1619425Y1709852D02*
X1626590D01*
G01X1656827Y1709222D02*
X1630134D01*
G01X1615931Y1708612D02*
X1608598D01*
G01X1628087D02*
X1616078D01*
G01X1619425Y1708277D02*
X1626590D01*
G01X1624543Y1708081D02*
X1623559D01*
G01X1616078Y1707825D02*
X1628087D01*
G01X1608598D02*
X1615931D01*
G01X1624543Y1707687D02*
X1623559D01*
G01X1624543Y1707490D02*
X1623559D01*
G01X1656827Y1706860D02*
X1630134D01*
G01X1624543Y1705640D02*
X1623559D01*
G01X1615931Y1705463D02*
X1608598D01*
G01X1628087D02*
X1616078D01*
G01X1624543Y1705443D02*
X1623559D01*
G01X1624543Y1705049D02*
X1623559D01*
G01X1619425Y1704852D02*
X1626590D01*
G01X1616078Y1704675D02*
X1628087D01*
G01X1608598D02*
X1615931D01*
G01X1619425Y1703277D02*
X1626590D01*
G01X1624543Y1703081D02*
X1623559D01*
G01X1624543Y1702687D02*
X1623559D01*
G01X1624543Y1702490D02*
X1623559D01*
G01X1615931Y1702313D02*
X1608598D01*
G01X1628087D02*
X1616078D01*
G01Y1701525D02*
X1628087D01*
G01X1608598D02*
X1615931D01*
G01X1624543Y1700640D02*
X1623559D01*
G01X1624543Y1700443D02*
X1623559D01*
G01X1624543Y1700049D02*
X1623559D01*
G01X1619425Y1699852D02*
X1626590D01*
G01X1615931Y1699163D02*
X1608598D01*
G01X1628087D02*
X1616078D01*
G01Y1698376D02*
X1628087D01*
G01X1608598D02*
X1615931D01*
G01X1619425Y1698277D02*
X1626590D01*
G01X1624543Y1698081D02*
X1623559D01*
G01X1624543Y1697687D02*
X1623559D01*
G01X1624543Y1697490D02*
X1623559D01*
G01X1629051Y1696427D02*
X1633146D01*
G01X1615931Y1696014D02*
X1608598D01*
G01X1628087D02*
X1616078D01*
G01X1633146Y1695915D02*
X1629748D01*
G01X1624543Y1695640D02*
X1623559D01*
G01X1624543Y1695443D02*
X1623559D01*
G01X1630358Y1695403D02*
X1629661D01*
G01X1616078Y1695226D02*
X1628087D01*
G01X1608598D02*
X1615931D01*
G01X1626531Y1695069D02*
X1618461D01*
G01X1624543Y1695049D02*
X1623559D01*
G01X1619425Y1694852D02*
X1626590D01*
G01X1632187Y1694721D02*
X1631752D01*
G01X1631839Y1694209D02*
X1632100D01*
G01X1619425Y1693277D02*
X1626590D01*
G01X1618461Y1693100D02*
X1626531D01*
G01X1624543Y1693081D02*
X1623559D01*
G01X1624543Y1692687D02*
X1623559D01*
G01X1622968Y1692648D02*
X1613984D01*
G01X1624543Y1692490D02*
X1623559D01*
G01X1630271Y1692333D02*
X1630096D01*
G01X1630009Y1691821D02*
X1630358D01*
G01X1626984Y1691033D02*
X1636354D01*
G01X1626984Y1690659D02*
X1606827D01*
G01X1636669Y1690443D02*
X1630134D01*
G01X1656827Y1690246D02*
X1638323D01*
G01X1628087Y1689852D02*
X1658795D01*
G01X1626984Y1689262D02*
X1636354D01*
G01X1607619Y1688081D02*
X1628087D01*
G01X1621987Y1687687D02*
X1628087D01*
G01Y1687628D02*
X1621987D01*
G01X1630449Y1687136D02*
X1606827D01*
G01X1656827Y1685325D02*
X1606827D01*
G01Y1684695D02*
X1630449D01*
G01X1612302Y1684104D02*
X1608463D01*
G01X1632749D02*
X1628911D01*
G01Y1683366D02*
X1631864D01*
G01X1608463D02*
X1611416D01*
G01X1630449Y1682726D02*
X1606827D01*
G01X1624113Y1682406D02*
X1624925D01*
G01X1630449Y1678947D02*
X1606827D01*
G01X1627730Y1678937D02*
X1624851D01*
G01X1629649Y1678199D02*
X1630535D01*
G01X1623817D02*
X1627730D01*
G01X1609201D02*
X1610087D01*
G01X1634386Y1678159D02*
X1660764D01*
G01Y1676978D02*
X1606827D01*
G01X1636669Y1674222D02*
X1620291D01*
G01X1626315Y1671525D02*
X1630646D01*
G01X1625689Y1670738D02*
X1631271D01*
G01Y1669163D02*
X1625689D01*
G01X1630646Y1668376D02*
X1626315D01*
G01X1636669Y1664045D02*
X1620291D01*
G01X1629661Y1691906D02*
X1630009Y1691821D01*
G01X1625823Y1683366D02*
X1626170Y1683297D01*
G01X1631630Y1654518D02*
X1625331D01*
G01X1630055Y1654222D02*
X1633205D01*
G01X1626905D02*
X1623756D01*
G01Y1652254D02*
X1626905D01*
G01X1633205D02*
X1630055D01*
G01X1623756Y1651663D02*
X1626905D01*
G01X1633205D02*
X1630055D01*
G01X1630096Y1692333D02*
X1629835Y1692418D01*
G01X1632100Y1694209D02*
X1632362Y1694039D01*
G01X1626170Y1683297D02*
X1626450Y1683116D01*
G01X1620992Y1683301D02*
X1621275Y1683123D01*
X1621462Y1682858D01*
X1621529Y1682556D01*
X1621464Y1682256D01*
X1621279Y1681989D01*
X1620994Y1681808D01*
X1620643Y1681742D01*
G01X1620294Y1681807D02*
X1620012Y1681985D01*
X1619824Y1682250D01*
X1619757Y1682552D01*
X1619822Y1682852D01*
X1620007Y1683119D01*
X1620293Y1683300D01*
X1620643Y1683366D01*
G01X1615825Y1683301D02*
X1616107Y1683123D01*
X1616294Y1682858D01*
X1616361Y1682556D01*
X1616297Y1682256D01*
X1616112Y1681989D01*
X1615826Y1681808D01*
X1615476Y1681742D01*
G01X1615127Y1681807D02*
X1614844Y1681985D01*
X1614657Y1682250D01*
X1614590Y1682552D01*
X1614654Y1682852D01*
X1614840Y1683119D01*
X1615125Y1683300D01*
X1615476Y1683366D01*
G01X1632536Y1694550D02*
X1632187Y1694721D01*
G01X1629748Y1695915D02*
X1630358Y1695403D01*
G01X1629661D02*
X1629051Y1695915D01*
G01X1621066Y1681000D02*
X1621426Y1680764D01*
X1621665Y1680414D01*
X1621750Y1680010D01*
X1621668Y1679608D01*
X1621431Y1679256D01*
X1621068Y1679016D01*
X1620643Y1678931D01*
G01X1620220Y1679015D02*
X1619860Y1679251D01*
X1619621Y1679601D01*
X1619536Y1680005D01*
X1619618Y1680407D01*
X1619855Y1680759D01*
X1620218Y1680999D01*
X1620643Y1681084D01*
G01X1615899Y1681000D02*
X1616259Y1680764D01*
X1616498Y1680414D01*
X1616583Y1680010D01*
X1616500Y1679608D01*
X1616264Y1679256D01*
X1615901Y1679016D01*
X1615476Y1678931D01*
G01X1615053Y1679015D02*
X1614692Y1679251D01*
X1614454Y1679601D01*
X1614369Y1680005D01*
X1614451Y1680407D01*
X1614688Y1680759D01*
X1615051Y1680999D01*
X1615476Y1681084D01*
G01X1632884Y1694209D02*
X1632536Y1694550D01*
G01X1629312Y1692247D02*
X1629661Y1691906D01*
G01X1621841Y1681455D02*
X1622293Y1681015D01*
X1622563Y1680479D01*
X1622633Y1679909D01*
X1622491Y1679345D01*
X1622145Y1678820D01*
X1621617Y1678427D01*
X1620975Y1678224D01*
X1620295Y1678226D01*
X1619655Y1678434D01*
X1619132Y1678830D01*
X1618791Y1679354D01*
X1618653Y1679915D01*
X1618725Y1680483D01*
X1618995Y1681017D01*
G01X1616674Y1681455D02*
X1617125Y1681015D01*
X1617395Y1680479D01*
X1617466Y1679909D01*
X1617324Y1679345D01*
X1616977Y1678820D01*
X1616450Y1678427D01*
X1615807Y1678224D01*
X1615128Y1678226D01*
X1614488Y1678434D01*
X1613965Y1678830D01*
X1613624Y1679354D01*
X1613486Y1679915D01*
X1613557Y1680483D01*
X1613828Y1681017D01*
G01X1621731Y1688081D02*
X1621987Y1687687D01*
G01X1632362Y1694039D02*
X1632536Y1693783D01*
G01X1629835Y1692418D02*
X1629661Y1692674D01*
G01X1626449Y1683116D02*
X1626632Y1682852D01*
X1626696Y1682553D01*
X1626632Y1682256D01*
G01X1619445Y1681455D02*
X1619123Y1681875D01*
X1618960Y1682358D01*
X1618982Y1682863D01*
X1619185Y1683340D01*
X1619552Y1683743D01*
X1620058Y1684010D01*
X1620649Y1684104D01*
X1621238Y1684007D01*
X1621740Y1683738D01*
X1622105Y1683334D01*
X1622306Y1682856D01*
X1622325Y1682352D01*
X1622161Y1681870D01*
X1621841Y1681455D01*
G01X1614278D02*
X1613955Y1681875D01*
X1613793Y1682358D01*
X1613815Y1682863D01*
X1614017Y1683340D01*
X1614384Y1683743D01*
X1614890Y1684010D01*
X1615482Y1684104D01*
X1616071Y1684007D01*
X1616573Y1683738D01*
X1616937Y1683334D01*
X1617139Y1682856D01*
X1617158Y1682352D01*
X1616994Y1681870D01*
X1616674Y1681455D01*
G01X1633058Y1693868D02*
X1632884Y1694209D01*
G01X1629138Y1692588D02*
X1629312Y1692247D01*
G01X1632536Y1693783D02*
X1632623Y1693442D01*
G01X1629661Y1692674D02*
X1629574Y1692930D01*
G01X1633146Y1693442D02*
X1633058Y1693868D01*
G01X1629051Y1692930D02*
X1629138Y1692588D01*
G01X1638323Y1822884D02*
Y1690246D01*
G01X1636669Y1664045D02*
Y1690443D01*
G01X1636354Y1691033D02*
Y1689262D01*
G01X1634386Y1676978D02*
Y1685325D01*
G01X1633205Y1654222D02*
Y1652254D01*
G01X1633146Y1692759D02*
Y1693442D01*
G01Y1696427D02*
Y1695915D01*
G01X1632749Y1683440D02*
Y1684104D01*
G01X1632623Y1693442D02*
Y1692759D01*
G01X1632102Y1706860D02*
Y1690443D01*
G01Y1724459D02*
Y1709222D01*
G01X1632013Y1692077D02*
Y1691565D01*
G01X1631630Y1653927D02*
Y1654518D01*
G01X1631316Y1692930D02*
Y1693442D01*
G01X1631271Y1669163D02*
Y1670738D01*
G01X1631236D02*
Y1669163D01*
G01X1631212Y1670738D02*
Y1669163D01*
G01X1630793Y1693442D02*
Y1692930D01*
G01X1630449Y1682726D02*
Y1678947D01*
G01Y1687136D02*
Y1684695D01*
G01X1630134Y1690443D02*
Y1822687D01*
G01X1630055Y1652254D02*
Y1654222D01*
G01X1630009Y1693953D02*
Y1694465D01*
G01X1629889Y1669163D02*
Y1670738D01*
G01X1629574Y1692930D02*
Y1693442D01*
G01X1629519Y1670738D02*
Y1669163D01*
G01X1629051Y1695915D02*
Y1696427D01*
G01Y1693356D02*
Y1692930D01*
G01X1628911Y1684104D02*
Y1683366D01*
G01X1628087Y1825502D02*
Y1687628D01*
G01X1627730Y1678199D02*
Y1678937D01*
G01X1627442Y1669163D02*
Y1670738D01*
G01X1627072D02*
Y1669163D01*
G01X1626984Y1688081D02*
Y1825049D01*
G01X1626905Y1652254D02*
Y1654222D01*
G01X1626531Y1693100D02*
Y1695069D01*
G01X1626145Y1717274D02*
Y1718061D01*
G01Y1720423D02*
Y1721211D01*
G01Y1714124D02*
Y1714911D01*
G01Y1707825D02*
Y1708612D01*
G01Y1710974D02*
Y1711762D01*
G01Y1704675D02*
Y1705463D01*
G01Y1698376D02*
Y1699163D01*
G01Y1701525D02*
Y1702313D01*
G01Y1695226D02*
Y1696014D01*
G01X1626118Y1717274D02*
Y1718061D01*
G01Y1720423D02*
Y1721211D01*
G01Y1714124D02*
Y1714911D01*
G01Y1707825D02*
Y1708612D01*
G01Y1710974D02*
Y1711762D01*
G01Y1704675D02*
Y1705463D01*
G01Y1698376D02*
Y1699163D01*
G01Y1701525D02*
Y1702313D01*
G01Y1695226D02*
Y1696014D01*
G01X1625748Y1669163D02*
Y1670738D01*
G01X1625742Y1717274D02*
Y1718061D01*
G01Y1720423D02*
Y1721211D01*
G01Y1714124D02*
Y1714911D01*
G01Y1707825D02*
Y1708612D01*
G01Y1710974D02*
Y1711762D01*
G01Y1704675D02*
Y1705463D01*
G01Y1698376D02*
Y1699163D01*
G01Y1701525D02*
Y1702313D01*
G01Y1695226D02*
Y1696014D01*
G01X1625724Y1669163D02*
Y1670738D01*
G01X1625689D02*
Y1669163D01*
G01X1625527Y1694852D02*
Y1693277D01*
G01Y1699852D02*
Y1698277D01*
G01Y1704852D02*
Y1703277D01*
G01Y1709852D02*
Y1708277D01*
G01Y1714852D02*
Y1713277D01*
G01Y1719852D02*
Y1718277D01*
G01X1625331Y1654518D02*
Y1653927D01*
G01X1624925Y1682406D02*
Y1682554D01*
G01X1624543Y1687628D02*
Y1685325D01*
G01Y1695640D02*
Y1692490D01*
G01Y1700640D02*
Y1697490D01*
G01Y1705640D02*
Y1702490D01*
G01Y1710640D02*
Y1707490D01*
G01Y1715640D02*
Y1712490D01*
G01Y1720640D02*
Y1717490D01*
G01X1624113Y1682554D02*
Y1682406D01*
G01X1623817Y1678642D02*
Y1678199D01*
G01X1623756Y1654222D02*
Y1652254D01*
G01X1623559Y1695640D02*
Y1692490D01*
G01Y1700640D02*
Y1697490D01*
G01Y1705640D02*
Y1702490D01*
G01Y1710640D02*
Y1707490D01*
G01Y1715640D02*
Y1712490D01*
G01Y1720640D02*
Y1717490D01*
G01X1622968Y1688081D02*
Y1825049D01*
G01X1622575Y1694852D02*
Y1693277D01*
G01Y1699852D02*
Y1698277D01*
G01Y1704852D02*
Y1703277D01*
G01Y1709852D02*
Y1708277D01*
G01Y1714852D02*
Y1713277D01*
G01Y1719852D02*
Y1718277D01*
G01X1622514Y1690659D02*
Y1822274D01*
G01X1622380Y1696014D02*
Y1695226D01*
G01Y1699163D02*
Y1698376D01*
G01Y1702313D02*
Y1701525D01*
G01Y1705463D02*
Y1704675D01*
G01Y1708612D02*
Y1707825D01*
G01Y1711762D02*
Y1710974D01*
G01Y1714911D02*
Y1714124D01*
G01Y1718061D02*
Y1717274D01*
G01Y1721211D02*
Y1720423D01*
G01X1621987Y1687687D02*
Y1687628D01*
G01X1621348Y1685325D02*
Y1688081D01*
G01X1620396Y1696014D02*
Y1695226D01*
G01Y1699163D02*
Y1698376D01*
G01Y1702313D02*
Y1701525D01*
G01Y1705463D02*
Y1704675D01*
G01Y1708612D02*
Y1707825D01*
G01Y1711762D02*
Y1710974D01*
G01Y1714911D02*
Y1714124D01*
G01Y1718061D02*
Y1717274D01*
G01Y1721211D02*
Y1720423D01*
G01X1620291Y1676978D02*
Y1664045D01*
G01X1619425Y1694852D02*
Y1693277D01*
G01Y1699852D02*
Y1698277D01*
G01Y1704852D02*
Y1703277D01*
G01Y1709852D02*
Y1708277D01*
G01Y1714852D02*
Y1713277D01*
G01Y1719852D02*
Y1718277D01*
G01X1618745Y1717274D02*
Y1718061D01*
G01Y1720423D02*
Y1721211D01*
G01Y1714124D02*
Y1714911D01*
G01Y1707825D02*
Y1708612D01*
G01Y1710974D02*
Y1711762D01*
G01Y1704675D02*
Y1705463D01*
G01Y1698376D02*
Y1699163D01*
G01Y1701525D02*
Y1702313D01*
G01Y1695226D02*
Y1696014D01*
G01X1618461Y1695069D02*
Y1693100D01*
G01X1617016Y1695226D02*
Y1692648D01*
G01Y1698376D02*
Y1696014D01*
G01Y1701525D02*
Y1699163D01*
G01Y1704675D02*
Y1702313D01*
G01Y1707825D02*
Y1705463D01*
G01Y1710974D02*
Y1708612D01*
G01Y1714124D02*
Y1711762D01*
G01Y1717274D02*
Y1714911D01*
G01Y1720423D02*
Y1718061D01*
G01X1616078Y1717274D02*
Y1718061D01*
G01Y1720423D02*
Y1721211D01*
G01Y1714124D02*
Y1714911D01*
G01Y1707825D02*
Y1708612D01*
G01Y1710974D02*
Y1711762D01*
G01Y1704675D02*
Y1705463D01*
G01Y1698376D02*
Y1699163D01*
G01Y1701525D02*
Y1702313D01*
G01Y1695226D02*
Y1696014D01*
G01X1615931Y1717274D02*
Y1718061D01*
G01Y1720423D02*
Y1721211D01*
G01Y1714124D02*
Y1714911D01*
G01Y1707825D02*
Y1708612D01*
G01Y1710974D02*
Y1711762D01*
G01Y1704675D02*
Y1705463D01*
G01Y1698376D02*
Y1699163D01*
G01Y1701525D02*
Y1702313D01*
G01Y1695226D02*
Y1696014D01*
G01X1614338Y1717274D02*
Y1718061D01*
G01Y1720423D02*
Y1721211D01*
G01Y1714124D02*
Y1714911D01*
G01Y1707825D02*
Y1708612D01*
G01Y1710974D02*
Y1711762D01*
G01Y1704675D02*
Y1705463D01*
G01Y1698376D02*
Y1699163D01*
G01Y1701525D02*
Y1702313D01*
G01Y1695226D02*
Y1696014D01*
G01X1613984Y1825049D02*
Y1688081D01*
G01X1613474Y1685325D02*
Y1688081D01*
G01X1613397Y1696014D02*
Y1695226D01*
G01Y1699163D02*
Y1698376D01*
G01Y1702313D02*
Y1701525D01*
G01Y1705463D02*
Y1704675D01*
G01Y1708612D02*
Y1707825D01*
G01Y1711762D02*
Y1710974D01*
G01Y1714911D02*
Y1714124D01*
G01Y1718061D02*
Y1717274D01*
G01Y1721211D02*
Y1720423D01*
G01X1612302Y1683440D02*
Y1684104D01*
G01X1610560Y1696014D02*
Y1695226D01*
G01Y1699163D02*
Y1698376D01*
G01Y1702313D02*
Y1701525D01*
G01Y1705463D02*
Y1704675D01*
G01Y1708612D02*
Y1707825D01*
G01Y1711762D02*
Y1710974D01*
G01Y1714911D02*
Y1714124D01*
G01Y1718061D02*
Y1717274D01*
G01Y1721211D02*
Y1720423D01*
G01X1610372Y1717274D02*
Y1718061D01*
G01Y1720423D02*
Y1721211D01*
G01Y1714124D02*
Y1714911D01*
G01Y1707825D02*
Y1708612D01*
G01Y1710974D02*
Y1711762D01*
G01Y1704675D02*
Y1705463D01*
G01Y1698376D02*
Y1699163D01*
G01Y1701525D02*
Y1702313D01*
G01Y1695226D02*
Y1696014D01*
G01X1608598Y1717274D02*
Y1718061D01*
G01Y1720423D02*
Y1721211D01*
G01Y1714124D02*
Y1714911D01*
G01Y1707825D02*
Y1708612D01*
G01Y1710974D02*
Y1711762D01*
G01Y1704675D02*
Y1705463D01*
G01Y1698376D02*
Y1699163D01*
G01Y1701525D02*
Y1702313D01*
G01Y1695226D02*
Y1696014D01*
G01X1608463Y1684104D02*
Y1683366D01*
G01X1607619Y1690659D02*
Y1688081D01*
G01X1607144Y1690659D02*
Y1685325D01*
G01X1606827Y1690659D02*
Y1676978D01*
G01X1632623Y1692759D02*
X1632536Y1692418D01*
G01X1631229Y1692588D02*
X1631316Y1692930D01*
G01Y1693442D02*
X1631403Y1693783D01*
G01X1624992Y1682859D02*
X1624925Y1682554D01*
G01X1633058Y1692333D02*
X1633146Y1692759D01*
G01X1630881Y1693868D02*
X1630793Y1693442D01*
G01X1629138Y1693783D02*
X1629051Y1693356D01*
G01X1624113Y1682554D02*
X1624199Y1683031D01*
X1624447Y1683473D01*
X1624835Y1683825D01*
X1625342Y1684045D01*
X1625919Y1684101D01*
X1626483Y1683979D01*
X1626959Y1683696D01*
X1627298Y1683292D01*
X1627478Y1682835D01*
X1627493Y1682355D01*
X1627336Y1681884D01*
X1627021Y1681467D01*
G01X1632274Y1692162D02*
X1632013Y1692077D01*
G01X1630532Y1692418D02*
X1630271Y1692333D01*
G01X1630009Y1694465D02*
X1629748Y1694380D01*
G01X1627021Y1681467D02*
X1627358Y1681929D01*
X1627504Y1682447D01*
X1627444Y1682965D01*
X1627193Y1683449D01*
X1626756Y1683844D01*
X1626183Y1684067D01*
X1625548Y1684086D01*
X1624964Y1683900D01*
X1624509Y1683547D01*
X1624216Y1683075D01*
X1624113Y1682554D01*
G01X1625182Y1683126D02*
X1624992Y1682858D01*
G01X1626450Y1681992D02*
X1626633Y1682258D01*
X1626696Y1682555D01*
X1626631Y1682853D01*
G01X1630706Y1692674D02*
X1630532Y1692418D01*
G01X1631403Y1693783D02*
X1631577Y1694039D01*
G01X1632797Y1691906D02*
X1633058Y1692333D01*
G01X1631055Y1692247D02*
X1631229Y1692588D01*
G01X1631055Y1694209D02*
X1630881Y1693868D01*
G01X1630793Y1692930D02*
X1630706Y1692674D01*
G01X1629574Y1693442D02*
X1629661Y1693697D01*
G01X1631752Y1694721D02*
X1631403Y1694550D01*
G01X1629835Y1693868D02*
X1630009Y1693953D01*
G01X1632362Y1691650D02*
X1632797Y1691906D01*
G01X1625181Y1683125D02*
X1625469Y1683304D01*
X1625823Y1683366D01*
G01X1620992Y1681807D02*
X1621275Y1681985D01*
X1621462Y1682250D01*
X1621529Y1682552D01*
X1621464Y1682852D01*
X1621279Y1683119D01*
X1620994Y1683300D01*
X1620643Y1683366D01*
G01X1620294Y1683301D02*
X1620012Y1683123D01*
X1619824Y1682858D01*
X1619757Y1682556D01*
X1619822Y1682256D01*
X1620007Y1681989D01*
X1620293Y1681808D01*
X1620643Y1681742D01*
G01X1615825Y1681807D02*
X1616107Y1681985D01*
X1616294Y1682250D01*
X1616361Y1682552D01*
X1616297Y1682852D01*
X1616112Y1683119D01*
X1615826Y1683300D01*
X1615476Y1683366D01*
G01X1615127Y1683301D02*
X1614844Y1683123D01*
X1614657Y1682858D01*
X1614590Y1682556D01*
X1614654Y1682256D01*
X1614840Y1681989D01*
X1615125Y1681808D01*
X1615476Y1681742D01*
G01X1631577Y1694039D02*
X1631839Y1694209D01*
G01X1621066Y1679015D02*
X1621426Y1679251D01*
X1621665Y1679601D01*
X1621750Y1680005D01*
X1621668Y1680407D01*
X1621431Y1680759D01*
X1621068Y1680999D01*
X1620643Y1681084D01*
G01X1620220Y1681000D02*
X1619860Y1680764D01*
X1619621Y1680414D01*
X1619536Y1680010D01*
X1619618Y1679608D01*
X1619855Y1679256D01*
X1620218Y1679016D01*
X1620643Y1678931D01*
G01X1615899Y1679015D02*
X1616259Y1679251D01*
X1616498Y1679601D01*
X1616583Y1680005D01*
X1616500Y1680407D01*
X1616264Y1680759D01*
X1615901Y1680999D01*
X1615476Y1681084D01*
G01X1615053Y1681000D02*
X1614692Y1680764D01*
X1614454Y1680414D01*
X1614369Y1680010D01*
X1614451Y1679608D01*
X1614688Y1679256D01*
X1615051Y1679016D01*
X1615476Y1678931D01*
G01X1629748Y1694380D02*
X1629400Y1694124D01*
G01X1627021Y1681467D02*
X1625392Y1679921D01*
G01X1619445Y1681455D02*
X1618994Y1681015D01*
X1618724Y1680479D01*
X1618653Y1679909D01*
X1618795Y1679345D01*
X1619142Y1678820D01*
X1619669Y1678427D01*
X1620312Y1678224D01*
X1620991Y1678226D01*
X1621631Y1678434D01*
X1622154Y1678830D01*
X1622495Y1679354D01*
X1622633Y1679915D01*
X1622562Y1680483D01*
X1622291Y1681017D01*
G01X1614278Y1681455D02*
X1613826Y1681015D01*
X1613556Y1680479D01*
X1613486Y1679909D01*
X1613628Y1679345D01*
X1613974Y1678820D01*
X1614502Y1678427D01*
X1615144Y1678224D01*
X1615824Y1678226D01*
X1616464Y1678434D01*
X1616986Y1678830D01*
X1617328Y1679354D01*
X1617466Y1679915D01*
X1617394Y1680483D01*
X1617124Y1681017D01*
G01X1626450Y1681992D02*
X1624887Y1680465D01*
G01X1632536Y1692418D02*
X1632274Y1692162D01*
G01X1630706Y1691906D02*
X1631055Y1692247D01*
G01X1631403Y1694550D02*
X1631055Y1694209D01*
G01X1629661Y1693697D02*
X1629835Y1693868D01*
G01X1621841Y1681455D02*
X1622164Y1681875D01*
X1622326Y1682358D01*
X1622304Y1682863D01*
X1622101Y1683340D01*
X1621735Y1683743D01*
X1621228Y1684010D01*
X1620637Y1684104D01*
X1620048Y1684007D01*
X1619546Y1683738D01*
X1619182Y1683334D01*
X1618980Y1682856D01*
X1618961Y1682352D01*
X1619125Y1681870D01*
X1619445Y1681455D01*
G01X1616674D02*
X1616996Y1681875D01*
X1617159Y1682358D01*
X1617137Y1682863D01*
X1616934Y1683340D01*
X1616567Y1683743D01*
X1616061Y1684010D01*
X1615470Y1684104D01*
X1614881Y1684007D01*
X1614378Y1683738D01*
X1614014Y1683334D01*
X1613813Y1682856D01*
X1613794Y1682352D01*
X1613958Y1681870D01*
X1614278Y1681455D01*
G01X1629400Y1694124D02*
X1629138Y1693783D01*
G01X1575921Y1769675D02*
G03I-590J0D01*
G01X1584976Y1771840D02*
X1573559D01*
G01Y1770069D02*
X1569917D01*
G01X1588618D02*
X1584976D01*
G01X1569125Y1769990D02*
X1569218D01*
G01Y1769242D02*
X1569125D01*
G01X1573559Y1769085D02*
X1569917D01*
G01X1588618D02*
X1584976D01*
G01X1573559Y1767510D02*
X1569917D01*
G01X1588618D02*
X1584976D01*
G01X1573559Y1766525D02*
X1569917D01*
G01X1588618D02*
X1584976D01*
G01X1573559Y1764951D02*
X1569917D01*
G01X1588618D02*
X1584976D01*
G01X1573559Y1763966D02*
X1569917D01*
G01X1588618D02*
X1584976D01*
G01X1573559Y1762392D02*
X1569917D01*
G01X1588618D02*
X1584976D01*
G01X1573559Y1761407D02*
X1569917D01*
G01X1588618D02*
X1584976D01*
G01X1573559Y1759636D02*
X1584976D01*
G01X1586731Y1762392D02*
Y1761407D01*
G01Y1764951D02*
Y1763966D01*
G01Y1767510D02*
Y1766525D01*
G01Y1770069D02*
Y1769085D01*
G01X1586649Y1762392D02*
Y1761407D01*
G01Y1764951D02*
Y1763966D01*
G01Y1767510D02*
Y1766525D01*
G01Y1770069D02*
Y1769085D01*
G01X1585255Y1762392D02*
Y1761407D01*
G01Y1764951D02*
Y1763966D01*
G01Y1767510D02*
Y1766525D01*
G01Y1770069D02*
Y1769085D01*
G01X1585173Y1762392D02*
Y1761407D01*
G01Y1764951D02*
Y1763966D01*
G01Y1767510D02*
Y1766525D01*
G01Y1770069D02*
Y1769085D01*
G01X1584976Y1759636D02*
Y1771840D01*
G01X1573559D02*
Y1759636D01*
G01X1573362Y1762392D02*
Y1761407D01*
G01Y1764951D02*
Y1763966D01*
G01Y1767510D02*
Y1766525D01*
G01Y1770069D02*
Y1769085D01*
G01X1573281Y1762392D02*
Y1761407D01*
G01Y1764951D02*
Y1763966D01*
G01Y1767510D02*
Y1766525D01*
G01Y1770069D02*
Y1769085D01*
G01X1571886Y1762392D02*
Y1761407D01*
G01Y1764951D02*
Y1763966D01*
G01Y1767510D02*
Y1766525D01*
G01Y1770069D02*
Y1769085D01*
G01X1571804Y1762392D02*
Y1761407D01*
G01Y1764951D02*
Y1763966D01*
G01Y1767510D02*
Y1766525D01*
G01Y1770069D02*
Y1769085D01*
G01X1569917Y1762392D02*
Y1761407D01*
G01Y1764951D02*
Y1763966D01*
G01Y1767510D02*
Y1766525D01*
G01Y1770069D02*
Y1769085D01*
G01X1569218Y1769990D02*
Y1769242D01*
G01X1569125D02*
Y1769863D01*
G01X1569031Y1769751D02*
Y1769879D01*
G01X1569125Y1769863D02*
X1569031Y1769751D01*
G01Y1769879D02*
X1569125Y1769990D01*
G01X1626984Y1722884D02*
G03X1626590Y1723277I-393J0D01*
G01X1616078Y1723573D02*
X1628087D01*
G01X1608598D02*
X1615931D01*
G01X1619425Y1723277D02*
X1626590D01*
G01X1624543Y1723081D02*
X1623559D01*
G01X1624543Y1722687D02*
X1623559D01*
G01X1624543Y1722490D02*
X1623559D01*
G01X1615931Y1721211D02*
X1608598D01*
G01X1628087D02*
X1616078D01*
G01X1626145Y1723573D02*
Y1724360D01*
G01X1626118Y1723573D02*
Y1724360D01*
G01X1625742Y1723573D02*
Y1724360D01*
G01X1625527Y1724852D02*
Y1723277D01*
G01X1624543Y1725640D02*
Y1722490D01*
G01X1623559Y1725640D02*
Y1722490D01*
G01X1622575Y1724852D02*
Y1723277D01*
G01X1622380Y1724360D02*
Y1723573D01*
G01X1620396Y1724360D02*
Y1723573D01*
G01X1619425Y1724852D02*
Y1723277D01*
G01X1618745Y1723573D02*
Y1724360D01*
G01X1617016Y1723573D02*
Y1721211D01*
G01X1616078Y1723573D02*
Y1724360D01*
G01X1615931Y1723573D02*
Y1724360D01*
G01X1614338Y1723573D02*
Y1724360D01*
G01X1613397D02*
Y1723573D01*
G01X1610560Y1724360D02*
Y1723573D01*
G01X1610372D02*
Y1724360D01*
G01X1608598Y1723573D02*
Y1724360D01*
G01X1626590Y1769852D02*
G03X1626984Y1770246I0J394D01*
G01Y1767884D02*
G03X1626590Y1768277I-393J0D01*
G01Y1779852D02*
G03X1626984Y1780246I0J394D01*
G01Y1777884D02*
G03X1626590Y1778277I-393J0D01*
G01Y1784852D02*
G03X1626984Y1785246I0J394D01*
G01Y1782884D02*
G03X1626590Y1783277I-393J0D01*
G01X1626984Y1792884D02*
G03X1626590Y1793277I-393J0D01*
G01Y1789852D02*
G03X1626984Y1790246I0J394D01*
G01Y1787884D02*
G03X1626590Y1788277I-393J0D01*
G01Y1774852D02*
G03X1626984Y1775246I0J394D01*
G01Y1772884D02*
G03X1626590Y1773277I-393J0D01*
G01Y1754852D02*
G03X1626984Y1755246I0J394D01*
G01Y1752884D02*
G03X1626590Y1753277I-393J0D01*
G01Y1759852D02*
G03X1626984Y1760246I0J394D01*
G01Y1757884D02*
G03X1626590Y1758277I-393J0D01*
G01Y1724852D02*
G03X1626984Y1725246I0J394D01*
G01X1626590Y1749852D02*
G03X1626984Y1750246I0J394D01*
G01Y1747884D02*
G03X1626590Y1748277I-393J0D01*
G01X1615931Y1793651D02*
X1608598D01*
G01X1628087D02*
X1616078D01*
G01X1619425Y1793277D02*
X1626590D01*
G01X1624543Y1793081D02*
X1623559D01*
G01X1616078Y1792864D02*
X1628087D01*
G01X1608598D02*
X1615931D01*
G01X1624543Y1792687D02*
X1623559D01*
G01X1624543Y1792490D02*
X1623559D01*
G01X1624543Y1790640D02*
X1623559D01*
G01X1615931Y1790502D02*
X1608598D01*
G01X1628087D02*
X1616078D01*
G01X1624543Y1790443D02*
X1623559D01*
G01X1624543Y1790049D02*
X1623559D01*
G01X1619425Y1789852D02*
X1626590D01*
G01X1616078Y1789714D02*
X1628087D01*
G01X1608598D02*
X1615931D01*
G01X1619425Y1788277D02*
X1626590D01*
G01X1624543Y1788081D02*
X1623559D01*
G01X1624543Y1787687D02*
X1623559D01*
G01X1624543Y1787490D02*
X1623559D01*
G01X1615931Y1787352D02*
X1608598D01*
G01X1628087D02*
X1616078D01*
G01Y1786565D02*
X1628087D01*
G01X1608598D02*
X1615931D01*
G01X1656827Y1786270D02*
X1630134D01*
G01X1624543Y1785640D02*
X1623559D01*
G01X1624543Y1785443D02*
X1623559D01*
G01X1624543Y1785049D02*
X1623559D01*
G01X1619425Y1784852D02*
X1626590D01*
G01X1615931Y1784203D02*
X1608598D01*
G01X1628087D02*
X1616078D01*
G01X1656827Y1783907D02*
X1630134D01*
G01X1616078Y1783415D02*
X1628087D01*
G01X1608598D02*
X1615931D01*
G01X1619425Y1783277D02*
X1626590D01*
G01X1624543Y1783081D02*
X1623559D01*
G01X1624543Y1782687D02*
X1623559D01*
G01X1624543Y1782490D02*
X1623559D01*
G01X1615931Y1781053D02*
X1608598D01*
G01X1628087D02*
X1616078D01*
G01X1624543Y1780640D02*
X1623559D01*
G01X1624543Y1780443D02*
X1623559D01*
G01X1616078Y1780266D02*
X1628087D01*
G01X1608598D02*
X1615931D01*
G01X1624543Y1780049D02*
X1623559D01*
G01X1619425Y1779852D02*
X1626590D01*
G01X1619425Y1778277D02*
X1626590D01*
G01X1624543Y1778081D02*
X1623559D01*
G01X1615931Y1777903D02*
X1608598D01*
G01X1628087D02*
X1616078D01*
G01X1624543Y1777687D02*
X1623559D01*
G01X1624543Y1777490D02*
X1623559D01*
G01X1616078Y1777116D02*
X1628087D01*
G01X1608598D02*
X1615931D01*
G01X1624543Y1775640D02*
X1623559D01*
G01X1624543Y1775443D02*
X1623559D01*
G01X1624543Y1775049D02*
X1623559D01*
G01X1619425Y1774852D02*
X1626590D01*
G01X1615931Y1774754D02*
X1608598D01*
G01X1628087D02*
X1616078D01*
G01Y1773966D02*
X1628087D01*
G01X1608598D02*
X1615931D01*
G01X1619425Y1773277D02*
X1626590D01*
G01X1624543Y1773081D02*
X1623559D01*
G01X1624543Y1772687D02*
X1623559D01*
G01X1624543Y1772490D02*
X1623559D01*
G01X1615931Y1771604D02*
X1608598D01*
G01X1628087D02*
X1616078D01*
G01Y1770817D02*
X1628087D01*
G01X1608598D02*
X1615931D01*
G01X1624543Y1770640D02*
X1623559D01*
G01X1624543Y1770443D02*
X1623559D01*
G01X1624543Y1770049D02*
X1623559D01*
G01X1619425Y1769852D02*
X1626590D01*
G01X1615931Y1768455D02*
X1608598D01*
G01X1628087D02*
X1616078D01*
G01X1619425Y1768277D02*
X1626590D01*
G01X1624543Y1768081D02*
X1623559D01*
G01X1624543Y1767687D02*
X1623559D01*
G01X1616078Y1767667D02*
X1628087D01*
G01X1608598D02*
X1615931D01*
G01X1624543Y1767490D02*
X1623559D01*
G01X1656827Y1767372D02*
X1630134D01*
G01X1626984Y1766270D02*
X1628087D01*
G01X1626512Y1765640D02*
X1625527D01*
G01X1626512Y1765443D02*
X1625527D01*
G01X1615931Y1765305D02*
X1608598D01*
G01X1628087D02*
X1616078D01*
G01X1626512Y1765049D02*
X1625527D01*
G01X1656827Y1765010D02*
X1630134D01*
G01X1626984Y1764852D02*
X1621394D01*
G01X1616078Y1764518D02*
X1628087D01*
G01X1608598D02*
X1615931D01*
G01X1626984Y1763277D02*
X1621394D01*
G01X1626512Y1763081D02*
X1625527D01*
G01X1626512Y1762687D02*
X1625527D01*
G01X1626512Y1762490D02*
X1625527D01*
G01X1615931Y1762155D02*
X1608598D01*
G01X1628087D02*
X1616078D01*
G01X1628087Y1761860D02*
X1626984D01*
G01X1616078Y1761368D02*
X1628087D01*
G01X1608598D02*
X1615931D01*
G01X1624543Y1760640D02*
X1623559D01*
G01X1624543Y1760443D02*
X1623559D01*
G01X1624543Y1760049D02*
X1623559D01*
G01X1619425Y1759852D02*
X1626590D01*
G01X1615931Y1759006D02*
X1608598D01*
G01X1628087D02*
X1616078D01*
G01X1619425Y1758277D02*
X1626590D01*
G01X1616078Y1758218D02*
X1628087D01*
G01X1608598D02*
X1615931D01*
G01X1624543Y1758081D02*
X1623559D01*
G01X1624543Y1757687D02*
X1623559D01*
G01X1624543Y1757490D02*
X1623559D01*
G01X1615931Y1755856D02*
X1608598D01*
G01X1628087D02*
X1616078D01*
G01X1624543Y1755640D02*
X1623559D01*
G01X1624543Y1755443D02*
X1623559D01*
G01X1616078Y1755069D02*
X1628087D01*
G01X1608598D02*
X1615931D01*
G01X1624543Y1755049D02*
X1623559D01*
G01X1619425Y1754852D02*
X1626590D01*
G01X1619425Y1753277D02*
X1626590D01*
G01X1624543Y1753081D02*
X1623559D01*
G01X1657784Y1752766D02*
X1638323D01*
G01X1615931Y1752707D02*
X1608598D01*
G01X1628087D02*
X1616078D01*
G01X1624543Y1752687D02*
X1623559D01*
G01X1624543Y1752490D02*
X1623559D01*
G01X1616078Y1751919D02*
X1628087D01*
G01X1608598D02*
X1615931D01*
G01X1624543Y1750640D02*
X1623559D01*
G01X1624543Y1750443D02*
X1623559D01*
G01X1624543Y1750049D02*
X1623559D01*
G01X1619425Y1749852D02*
X1626590D01*
G01X1615931Y1749557D02*
X1608598D01*
G01X1628087D02*
X1616078D01*
G01Y1748770D02*
X1628087D01*
G01X1608598D02*
X1615931D01*
G01X1656827Y1748671D02*
X1630134D01*
G01X1619425Y1748277D02*
X1626590D01*
G01X1624543Y1748081D02*
X1623559D01*
G01X1624543Y1747687D02*
X1623559D01*
G01X1624543Y1747490D02*
X1623559D01*
G01X1615931Y1746407D02*
X1608598D01*
G01X1628087D02*
X1616078D01*
G01X1638323Y1746329D02*
X1656827D01*
G01X1628087D02*
X1626984D01*
G01X1652326Y1746309D02*
X1630134D01*
G01X1628087Y1746211D02*
X1620552D01*
G01X1625093Y1745718D02*
X1622968D01*
G01X1616078Y1745620D02*
X1628087D01*
G01X1608598D02*
X1615931D01*
G01X1626077Y1745423D02*
X1625093D01*
G01X1626077Y1745226D02*
X1625093D01*
G01X1626984Y1745029D02*
X1620959D01*
G01X1626984Y1743848D02*
X1620959D01*
G01X1626077Y1743651D02*
X1625093D01*
G01X1626077Y1743455D02*
X1625093D01*
G01X1615931Y1743258D02*
X1608598D01*
G01X1628087D02*
X1616078D01*
G01Y1742470D02*
X1628087D01*
G01X1608598D02*
X1615931D01*
G01X1620978Y1742392D02*
X1619095D01*
G01X1626077Y1742274D02*
X1625093D01*
G01X1626077Y1742077D02*
X1625093D01*
G01X1626984Y1741880D02*
X1620959D01*
G01X1626984Y1740699D02*
X1620959D01*
G01X1626077Y1740502D02*
X1625093D01*
G01X1626077Y1740305D02*
X1625093D01*
G01X1619095Y1740187D02*
X1620978D01*
G01X1615931Y1740108D02*
X1608598D01*
G01X1628087D02*
X1616078D01*
G01Y1739321D02*
X1628087D01*
G01X1608598D02*
X1615931D01*
G01X1626077Y1739124D02*
X1625093D01*
G01X1626077Y1738927D02*
X1625093D01*
G01X1626984Y1738730D02*
X1620959D01*
G01X1626984Y1737549D02*
X1620959D01*
G01X1626077Y1737352D02*
X1625093D01*
G01X1626077Y1737155D02*
X1625093D01*
G01X1615931Y1736959D02*
X1608598D01*
G01X1628087D02*
X1616078D01*
G01Y1736171D02*
X1628087D01*
G01X1608598D02*
X1615931D01*
G01X1626077Y1735974D02*
X1625093D01*
G01X1626077Y1735777D02*
X1625093D01*
G01X1626984Y1735581D02*
X1620959D01*
G01X1626984Y1734400D02*
X1620959D01*
G01X1626077Y1734203D02*
X1625093D01*
G01X1626077Y1734006D02*
X1625093D01*
G01X1615931Y1733809D02*
X1608598D01*
G01X1628087D02*
X1616078D01*
G01Y1733022D02*
X1628087D01*
G01X1608598D02*
X1615931D01*
G01X1620978Y1732943D02*
X1619095D01*
G01X1626077Y1732825D02*
X1625093D01*
G01X1626077Y1732628D02*
X1625093D01*
G01X1626984Y1732431D02*
X1620959D01*
G01X1626984Y1731250D02*
X1620959D01*
G01X1626077Y1731053D02*
X1625093D01*
G01X1626077Y1730856D02*
X1625093D01*
G01X1619095Y1730738D02*
X1620978D01*
G01X1615931Y1730659D02*
X1608598D01*
G01X1628087D02*
X1616078D01*
G01Y1729872D02*
X1628087D01*
G01X1608598D02*
X1615931D01*
G01X1626077Y1729675D02*
X1625093D01*
G01X1626077Y1729478D02*
X1625093D01*
G01X1626984Y1729281D02*
X1620959D01*
G01X1626984Y1728100D02*
X1620959D01*
G01X1626077Y1727903D02*
X1625093D01*
G01X1626077Y1727707D02*
X1625093D01*
G01X1615931Y1727510D02*
X1608598D01*
G01X1628087D02*
X1616078D01*
G01X1625093Y1727411D02*
X1622968D01*
G01X1620552Y1726919D02*
X1628087D01*
G01X1652326Y1726821D02*
X1630134D01*
G01X1628087Y1726801D02*
X1626984D01*
G01X1656827D02*
X1638323D01*
G01X1616078Y1726722D02*
X1628087D01*
G01X1608598D02*
X1615931D01*
G01X1624543Y1725640D02*
X1623559D01*
G01X1624543Y1725443D02*
X1623559D01*
G01X1624543Y1725049D02*
X1623559D01*
G01X1619425Y1724852D02*
X1626590D01*
G01X1656827Y1724459D02*
X1630134D01*
G01X1615931Y1724360D02*
X1608598D01*
G01X1628087D02*
X1616078D01*
G01X1632102Y1786270D02*
Y1802805D01*
G01Y1767372D02*
Y1783907D01*
G01Y1748671D02*
Y1765010D01*
G01Y1746309D02*
Y1726821D01*
G01X1626905Y1746211D02*
Y1726919D01*
G01X1626590D02*
Y1746211D01*
G01X1626512Y1765640D02*
Y1762490D01*
G01X1626145Y1792864D02*
Y1793651D01*
G01Y1786565D02*
Y1787352D01*
G01Y1789714D02*
Y1790502D01*
G01Y1783415D02*
Y1784203D01*
G01Y1777116D02*
Y1777903D01*
G01Y1780266D02*
Y1781053D01*
G01Y1773966D02*
Y1774754D01*
G01Y1767667D02*
Y1768455D01*
G01Y1770817D02*
Y1771604D01*
G01Y1764518D02*
Y1765305D01*
G01Y1758218D02*
Y1759006D01*
G01Y1761368D02*
Y1762155D01*
G01Y1755069D02*
Y1755856D01*
G01Y1748770D02*
Y1749557D01*
G01Y1751919D02*
Y1752707D01*
G01Y1745620D02*
Y1746407D01*
G01Y1742470D02*
Y1743258D01*
G01Y1736171D02*
Y1736959D01*
G01Y1739321D02*
Y1740108D01*
G01Y1733022D02*
Y1733809D01*
G01Y1726722D02*
Y1727510D01*
G01Y1729872D02*
Y1730659D01*
G01X1626118Y1792864D02*
Y1793651D01*
G01Y1786565D02*
Y1787352D01*
G01Y1789714D02*
Y1790502D01*
G01Y1783415D02*
Y1784203D01*
G01Y1777116D02*
Y1777903D01*
G01Y1780266D02*
Y1781053D01*
G01Y1773966D02*
Y1774754D01*
G01Y1767667D02*
Y1768455D01*
G01Y1770817D02*
Y1771604D01*
G01Y1764518D02*
Y1765305D01*
G01Y1758218D02*
Y1759006D01*
G01Y1761368D02*
Y1762155D01*
G01Y1755069D02*
Y1755856D01*
G01Y1748770D02*
Y1749557D01*
G01Y1751919D02*
Y1752707D01*
G01Y1745620D02*
Y1746407D01*
G01Y1742470D02*
Y1743258D01*
G01Y1736171D02*
Y1736959D01*
G01Y1739321D02*
Y1740108D01*
G01Y1733022D02*
Y1733809D01*
G01Y1726722D02*
Y1727510D01*
G01Y1729872D02*
Y1730659D01*
G01X1626077Y1729872D02*
Y1727510D01*
G01Y1733022D02*
Y1730659D01*
G01Y1736171D02*
Y1733809D01*
G01Y1739321D02*
Y1736959D01*
G01Y1742470D02*
Y1740108D01*
G01Y1745620D02*
Y1743258D01*
G01X1625803Y1746211D02*
Y1726919D01*
G01X1625742Y1792864D02*
Y1793651D01*
G01Y1786565D02*
Y1787352D01*
G01Y1789714D02*
Y1790502D01*
G01Y1783415D02*
Y1784203D01*
G01Y1777116D02*
Y1777903D01*
G01Y1780266D02*
Y1781053D01*
G01Y1773966D02*
Y1774754D01*
G01Y1767667D02*
Y1768455D01*
G01Y1770817D02*
Y1771604D01*
G01Y1764518D02*
Y1765305D01*
G01Y1758218D02*
Y1759006D01*
G01Y1761368D02*
Y1762155D01*
G01Y1755069D02*
Y1755856D01*
G01Y1748770D02*
Y1749557D01*
G01Y1751919D02*
Y1752707D01*
G01Y1745620D02*
Y1746407D01*
G01Y1742470D02*
Y1743258D01*
G01Y1736171D02*
Y1736959D01*
G01Y1739321D02*
Y1740108D01*
G01Y1733022D02*
Y1733809D01*
G01Y1726722D02*
Y1727510D01*
G01Y1729872D02*
Y1730659D01*
G01X1625527Y1749852D02*
Y1748277D01*
G01Y1754852D02*
Y1753277D01*
G01Y1759852D02*
Y1758277D01*
G01Y1765640D02*
Y1762490D01*
G01Y1769852D02*
Y1768277D01*
G01Y1774852D02*
Y1773277D01*
G01Y1779852D02*
Y1778277D01*
G01Y1784852D02*
Y1783277D01*
G01Y1789852D02*
Y1788277D01*
G01Y1794852D02*
Y1793277D01*
G01X1625303Y1746211D02*
Y1726919D01*
G01X1625093Y1727411D02*
Y1745718D01*
G01X1624543Y1750640D02*
Y1747490D01*
G01Y1755640D02*
Y1752490D01*
G01Y1760640D02*
Y1757490D01*
G01Y1764852D02*
Y1763277D01*
G01Y1770640D02*
Y1767490D01*
G01Y1775640D02*
Y1772490D01*
G01Y1780640D02*
Y1777490D01*
G01Y1785640D02*
Y1782490D01*
G01Y1790640D02*
Y1787490D01*
G01Y1795640D02*
Y1792490D01*
G01X1624386Y1726919D02*
Y1746211D01*
G01X1624109Y1729281D02*
Y1728100D01*
G01Y1732431D02*
Y1731250D01*
G01Y1735581D02*
Y1734400D01*
G01Y1738730D02*
Y1737549D01*
G01Y1741880D02*
Y1740699D01*
G01Y1745029D02*
Y1743848D01*
G01X1623559Y1750640D02*
Y1747490D01*
G01Y1755640D02*
Y1752490D01*
G01Y1760640D02*
Y1757490D01*
G01Y1770640D02*
Y1767490D01*
G01Y1775640D02*
Y1772490D01*
G01Y1780640D02*
Y1777490D01*
G01Y1785640D02*
Y1782490D01*
G01Y1790640D02*
Y1787490D01*
G01Y1795640D02*
Y1792490D01*
G01X1622575Y1749852D02*
Y1748277D01*
G01Y1754852D02*
Y1753277D01*
G01Y1759852D02*
Y1758277D01*
G01Y1769852D02*
Y1768277D01*
G01Y1774852D02*
Y1773277D01*
G01Y1779852D02*
Y1778277D01*
G01Y1784852D02*
Y1783277D01*
G01Y1789852D02*
Y1788277D01*
G01Y1794852D02*
Y1793277D01*
G01X1622380Y1727510D02*
Y1726722D01*
G01Y1730659D02*
Y1729872D01*
G01Y1733809D02*
Y1733022D01*
G01Y1736959D02*
Y1736171D01*
G01Y1740108D02*
Y1739321D01*
G01Y1743258D02*
Y1742470D01*
G01Y1746407D02*
Y1745620D01*
G01Y1749557D02*
Y1748770D01*
G01Y1752707D02*
Y1751919D01*
G01Y1755856D02*
Y1755069D01*
G01Y1759006D02*
Y1758218D01*
G01Y1762155D02*
Y1761368D01*
G01Y1765305D02*
Y1764518D01*
G01Y1768455D02*
Y1767667D01*
G01Y1771604D02*
Y1770817D01*
G01Y1774754D02*
Y1773966D01*
G01Y1777903D02*
Y1777116D01*
G01Y1781053D02*
Y1780266D01*
G01Y1784203D02*
Y1783415D01*
G01Y1787352D02*
Y1786565D01*
G01Y1790502D02*
Y1789714D01*
G01Y1793651D02*
Y1792864D01*
G01X1621394Y1764852D02*
Y1763277D01*
G01X1621030Y1726919D02*
Y1746211D01*
G01X1620978Y1732943D02*
Y1730738D01*
G01Y1742392D02*
Y1740187D01*
G01X1620959Y1729281D02*
Y1728100D01*
G01Y1732431D02*
Y1731250D01*
G01Y1735581D02*
Y1734400D01*
G01Y1738730D02*
Y1737549D01*
G01Y1741880D02*
Y1740699D01*
G01Y1745029D02*
Y1743848D01*
G01X1620552Y1742392D02*
Y1746211D01*
G01Y1732943D02*
Y1740187D01*
G01Y1726919D02*
Y1730738D01*
G01X1620396Y1727510D02*
Y1726722D01*
G01Y1730659D02*
Y1729872D01*
G01Y1733809D02*
Y1733022D01*
G01Y1736959D02*
Y1736171D01*
G01Y1740108D02*
Y1739321D01*
G01Y1743258D02*
Y1742470D01*
G01Y1746407D02*
Y1745620D01*
G01Y1749557D02*
Y1748770D01*
G01Y1752707D02*
Y1751919D01*
G01Y1755856D02*
Y1755069D01*
G01Y1759006D02*
Y1758218D01*
G01Y1762155D02*
Y1761368D01*
G01Y1765305D02*
Y1764518D01*
G01Y1768455D02*
Y1767667D01*
G01Y1771604D02*
Y1770817D01*
G01Y1774754D02*
Y1773966D01*
G01Y1777903D02*
Y1777116D01*
G01Y1781053D02*
Y1780266D01*
G01Y1784203D02*
Y1783415D01*
G01Y1787352D02*
Y1786565D01*
G01Y1790502D02*
Y1789714D01*
G01Y1793651D02*
Y1792864D01*
G01X1619425Y1749852D02*
Y1748277D01*
G01Y1754852D02*
Y1753277D01*
G01Y1759852D02*
Y1758277D01*
G01Y1769852D02*
Y1768277D01*
G01Y1774852D02*
Y1773277D01*
G01Y1779852D02*
Y1778277D01*
G01Y1784852D02*
Y1783277D01*
G01Y1789852D02*
Y1788277D01*
G01Y1794852D02*
Y1793277D01*
G01X1619095Y1740187D02*
Y1742392D01*
G01Y1730738D02*
Y1732943D01*
G01X1618745Y1792864D02*
Y1793651D01*
G01Y1786565D02*
Y1787352D01*
G01Y1789714D02*
Y1790502D01*
G01Y1783415D02*
Y1784203D01*
G01Y1777116D02*
Y1777903D01*
G01Y1780266D02*
Y1781053D01*
G01Y1773966D02*
Y1774754D01*
G01Y1767667D02*
Y1768455D01*
G01Y1770817D02*
Y1771604D01*
G01Y1764518D02*
Y1765305D01*
G01Y1758218D02*
Y1759006D01*
G01Y1761368D02*
Y1762155D01*
G01Y1755069D02*
Y1755856D01*
G01Y1748770D02*
Y1749557D01*
G01Y1751919D02*
Y1752707D01*
G01Y1745620D02*
Y1746407D01*
G01Y1742470D02*
Y1743258D01*
G01Y1736171D02*
Y1736959D01*
G01Y1739321D02*
Y1740108D01*
G01Y1733022D02*
Y1733809D01*
G01Y1726722D02*
Y1727510D01*
G01Y1729872D02*
Y1730659D01*
G01X1617016Y1726722D02*
Y1724360D01*
G01Y1729872D02*
Y1727510D01*
G01Y1733022D02*
Y1730659D01*
G01Y1736171D02*
Y1733809D01*
G01Y1739321D02*
Y1736959D01*
G01Y1742470D02*
Y1740108D01*
G01Y1745620D02*
Y1743258D01*
G01Y1748770D02*
Y1746407D01*
G01Y1751919D02*
Y1749557D01*
G01Y1755069D02*
Y1752707D01*
G01Y1758218D02*
Y1755856D01*
G01Y1761368D02*
Y1759006D01*
G01Y1764518D02*
Y1762155D01*
G01Y1767667D02*
Y1765305D01*
G01Y1770817D02*
Y1768455D01*
G01Y1773966D02*
Y1771604D01*
G01Y1777116D02*
Y1774754D01*
G01Y1780266D02*
Y1777903D01*
G01Y1783415D02*
Y1781053D01*
G01Y1786565D02*
Y1784203D01*
G01Y1789714D02*
Y1787352D01*
G01Y1792864D02*
Y1790502D01*
G01Y1796014D02*
Y1793651D01*
G01X1616078Y1792864D02*
Y1793651D01*
G01Y1786565D02*
Y1787352D01*
G01Y1789714D02*
Y1790502D01*
G01Y1783415D02*
Y1784203D01*
G01Y1777116D02*
Y1777903D01*
G01Y1780266D02*
Y1781053D01*
G01Y1773966D02*
Y1774754D01*
G01Y1767667D02*
Y1768455D01*
G01Y1770817D02*
Y1771604D01*
G01Y1764518D02*
Y1765305D01*
G01Y1758218D02*
Y1759006D01*
G01Y1761368D02*
Y1762155D01*
G01Y1755069D02*
Y1755856D01*
G01Y1748770D02*
Y1749557D01*
G01Y1751919D02*
Y1752707D01*
G01Y1745620D02*
Y1746407D01*
G01Y1742470D02*
Y1743258D01*
G01Y1736171D02*
Y1736959D01*
G01Y1739321D02*
Y1740108D01*
G01Y1733022D02*
Y1733809D01*
G01Y1726722D02*
Y1727510D01*
G01Y1729872D02*
Y1730659D01*
G01X1615931Y1792864D02*
Y1793651D01*
G01Y1786565D02*
Y1787352D01*
G01Y1789714D02*
Y1790502D01*
G01Y1783415D02*
Y1784203D01*
G01Y1777116D02*
Y1777903D01*
G01Y1780266D02*
Y1781053D01*
G01Y1773966D02*
Y1774754D01*
G01Y1767667D02*
Y1768455D01*
G01Y1770817D02*
Y1771604D01*
G01Y1764518D02*
Y1765305D01*
G01Y1758218D02*
Y1759006D01*
G01Y1761368D02*
Y1762155D01*
G01Y1755069D02*
Y1755856D01*
G01Y1748770D02*
Y1749557D01*
G01Y1751919D02*
Y1752707D01*
G01Y1745620D02*
Y1746407D01*
G01Y1742470D02*
Y1743258D01*
G01Y1736171D02*
Y1736959D01*
G01Y1739321D02*
Y1740108D01*
G01Y1733022D02*
Y1733809D01*
G01Y1726722D02*
Y1727510D01*
G01Y1729872D02*
Y1730659D01*
G01X1614338Y1792864D02*
Y1793651D01*
G01Y1786565D02*
Y1787352D01*
G01Y1789714D02*
Y1790502D01*
G01Y1783415D02*
Y1784203D01*
G01Y1777116D02*
Y1777903D01*
G01Y1780266D02*
Y1781053D01*
G01Y1773966D02*
Y1774754D01*
G01Y1767667D02*
Y1768455D01*
G01Y1770817D02*
Y1771604D01*
G01Y1764518D02*
Y1765305D01*
G01Y1758218D02*
Y1759006D01*
G01Y1761368D02*
Y1762155D01*
G01Y1755069D02*
Y1755856D01*
G01Y1748770D02*
Y1749557D01*
G01Y1751919D02*
Y1752707D01*
G01Y1745620D02*
Y1746407D01*
G01Y1742470D02*
Y1743258D01*
G01Y1736171D02*
Y1736959D01*
G01Y1739321D02*
Y1740108D01*
G01Y1733022D02*
Y1733809D01*
G01Y1726722D02*
Y1727510D01*
G01Y1729872D02*
Y1730659D01*
G01X1613397Y1727510D02*
Y1726722D01*
G01Y1730659D02*
Y1729872D01*
G01Y1733809D02*
Y1733022D01*
G01Y1736959D02*
Y1736171D01*
G01Y1740108D02*
Y1739321D01*
G01Y1743258D02*
Y1742470D01*
G01Y1746407D02*
Y1745620D01*
G01Y1749557D02*
Y1748770D01*
G01Y1752707D02*
Y1751919D01*
G01Y1755856D02*
Y1755069D01*
G01Y1759006D02*
Y1758218D01*
G01Y1762155D02*
Y1761368D01*
G01Y1765305D02*
Y1764518D01*
G01Y1768455D02*
Y1767667D01*
G01Y1771604D02*
Y1770817D01*
G01Y1774754D02*
Y1773966D01*
G01Y1777903D02*
Y1777116D01*
G01Y1781053D02*
Y1780266D01*
G01Y1784203D02*
Y1783415D01*
G01Y1787352D02*
Y1786565D01*
G01Y1790502D02*
Y1789714D01*
G01Y1793651D02*
Y1792864D01*
G01X1610560Y1727510D02*
Y1726722D01*
G01Y1730659D02*
Y1729872D01*
G01Y1733809D02*
Y1733022D01*
G01Y1736959D02*
Y1736171D01*
G01Y1740108D02*
Y1739321D01*
G01Y1743258D02*
Y1742470D01*
G01Y1746407D02*
Y1745620D01*
G01Y1749557D02*
Y1748770D01*
G01Y1752707D02*
Y1751919D01*
G01Y1755856D02*
Y1755069D01*
G01Y1759006D02*
Y1758218D01*
G01Y1762155D02*
Y1761368D01*
G01Y1765305D02*
Y1764518D01*
G01Y1768455D02*
Y1767667D01*
G01Y1771604D02*
Y1770817D01*
G01Y1774754D02*
Y1773966D01*
G01Y1777903D02*
Y1777116D01*
G01Y1781053D02*
Y1780266D01*
G01Y1784203D02*
Y1783415D01*
G01Y1787352D02*
Y1786565D01*
G01Y1790502D02*
Y1789714D01*
G01Y1793651D02*
Y1792864D01*
G01X1610372D02*
Y1793651D01*
G01Y1786565D02*
Y1787352D01*
G01Y1789714D02*
Y1790502D01*
G01Y1783415D02*
Y1784203D01*
G01Y1777116D02*
Y1777903D01*
G01Y1780266D02*
Y1781053D01*
G01Y1773966D02*
Y1774754D01*
G01Y1767667D02*
Y1768455D01*
G01Y1770817D02*
Y1771604D01*
G01Y1764518D02*
Y1765305D01*
G01Y1758218D02*
Y1759006D01*
G01Y1761368D02*
Y1762155D01*
G01Y1755069D02*
Y1755856D01*
G01Y1748770D02*
Y1749557D01*
G01Y1751919D02*
Y1752707D01*
G01Y1745620D02*
Y1746407D01*
G01Y1742470D02*
Y1743258D01*
G01Y1736171D02*
Y1736959D01*
G01Y1739321D02*
Y1740108D01*
G01Y1733022D02*
Y1733809D01*
G01Y1726722D02*
Y1727510D01*
G01Y1729872D02*
Y1730659D01*
G01X1608598Y1792864D02*
Y1793651D01*
G01Y1786565D02*
Y1787352D01*
G01Y1789714D02*
Y1790502D01*
G01Y1783415D02*
Y1784203D01*
G01Y1777116D02*
Y1777903D01*
G01Y1780266D02*
Y1781053D01*
G01Y1773966D02*
Y1774754D01*
G01Y1767667D02*
Y1768455D01*
G01Y1770817D02*
Y1771604D01*
G01Y1764518D02*
Y1765305D01*
G01Y1758218D02*
Y1759006D01*
G01Y1761368D02*
Y1762155D01*
G01Y1755069D02*
Y1755856D01*
G01Y1748770D02*
Y1749557D01*
G01Y1751919D02*
Y1752707D01*
G01Y1745620D02*
Y1746407D01*
G01Y1742470D02*
Y1743258D01*
G01Y1736171D02*
Y1736959D01*
G01Y1739321D02*
Y1740108D01*
G01Y1733022D02*
Y1733809D01*
G01Y1726722D02*
Y1727510D01*
G01Y1729872D02*
Y1730659D01*
G01X1592555Y1775777D02*
Y1755699D01*
G01X1588618Y1762392D02*
Y1761407D01*
G01Y1764951D02*
Y1763966D01*
G01Y1767510D02*
Y1766525D01*
G01Y1770069D02*
Y1769085D01*
G01X1626590Y1794852D02*
G03X1626984Y1795246I0J394D01*
G01X1615931Y1796801D02*
X1608598D01*
G01X1628087D02*
X1616078D01*
G01Y1796014D02*
X1628087D01*
G01X1608598D02*
X1615931D01*
G01X1624543Y1795640D02*
X1623559D01*
G01X1624543Y1795443D02*
X1623559D01*
G01X1624543Y1795049D02*
X1623559D01*
G01X1619425Y1794852D02*
X1626590D01*
G01X1626145Y1796014D02*
Y1796801D01*
G01X1626118Y1796014D02*
Y1796801D01*
G01X1625742Y1796014D02*
Y1796801D01*
G01X1622380D02*
Y1796014D01*
G01X1620396Y1796801D02*
Y1796014D01*
G01X1618745D02*
Y1796801D01*
G01X1617016Y1799163D02*
Y1796801D01*
G01X1616078Y1796014D02*
Y1796801D01*
G01X1615931Y1796014D02*
Y1796801D01*
G01X1614338Y1796014D02*
Y1796801D01*
G01X1613397D02*
Y1796014D01*
G01X1610560Y1796801D02*
Y1796014D01*
G01X1610372D02*
Y1796801D01*
G01X1608598Y1796014D02*
Y1796801D01*
G01X1629774Y1832225D02*
G03X1631205I716J0D01*
G01X1626884D02*
G03X1628315I716J0D01*
G01X1630646Y1841604D02*
G03Y1844754I0J1575D01*
G01X1625786Y1831150D02*
G03X1628421Y1831294I1248J1351D01*
G01D02*
G03X1631202Y1831300I1388J1207D01*
G01X1626590Y1819852D02*
G03X1626984Y1820246I0J394D01*
G01Y1817884D02*
G03X1626590Y1818277I-393J0D01*
G01Y1809852D02*
G03X1626984Y1810246I0J394D01*
G01Y1807884D02*
G03X1626590Y1808277I-393J0D01*
G01Y1814852D02*
G03X1626984Y1815246I0J394D01*
G01Y1812884D02*
G03X1626590Y1813277I-393J0D01*
G01X1623285Y1833641D02*
G03X1621812I-736J-278D01*
G01Y1831956D02*
G03X1623285I737J278D01*
G01X1625492Y1831821D02*
G03X1625786Y1831149I913J-1D01*
G01X1624558Y1833976D02*
G03X1624036Y1834541I-1351J-724D01*
G01X1624038Y1831097D02*
G03X1624558Y1831662I-832J1287D01*
G01X1626315Y1844754D02*
G03Y1841604I0J-1575D01*
G01X1621812Y1833641D02*
G03Y1831956I2237J-842D01*
G01X1624558Y1831662D02*
G03Y1833976I-2162J1157D01*
G01X1620470Y1833974D02*
G03Y1831662I2163J-1156D01*
G01X1624037Y1834541D02*
G03X1620990Y1834539I-1522J-2362D01*
G01X1620991Y1831096D02*
G03X1624038Y1831097I1523J2362D01*
G01X1626590Y1799852D02*
G03X1626984Y1800246I0J394D01*
G01Y1797884D02*
G03X1626590Y1798277I-393J0D01*
G01X1620990Y1834539D02*
G03X1620470Y1833974I832J-1287D01*
G01Y1831662D02*
G03X1620991Y1831096I1352J722D01*
G01X1623285Y1831956D02*
G03Y1833641I-2236J842D01*
G01X1621394Y1831368D02*
G03I-2166J0D01*
G01X1617274Y1834085D02*
G03Y1828651I1954J-2717D01*
G01X1621183D02*
G03Y1834085I-1954J2717D01*
G01X1622732Y1831368D02*
G03I-3504J0D01*
G01X1621532Y1827470D02*
G03Y1835266I-2304J3898D01*
G01X1616925D02*
G03Y1827470I2303J-3898D01*
G01X1615312Y1833959D02*
G03X1614721Y1833594I-9J-646D01*
G01X1616085Y1833151D02*
G03X1615312Y1833959I-792J17D01*
G01X1614060Y1834663D02*
G03X1613217Y1833594I704J-1422D01*
G01X1613426Y1831708D02*
G03X1614660Y1830734I1735J930D01*
G01X1616303Y1830778D02*
G03X1617467Y1831916I-730J1911D01*
G01X1617381Y1833932D02*
G03X1615642Y1834950I-1807J-1093D01*
G01X1614660Y1830734D02*
G03X1616303Y1830778I756J2475D01*
G01X1617641Y1833072D02*
G03X1617380Y1833935I-2971J-428D01*
G01X1613087Y1833150D02*
G03X1613426Y1831708I3015J-52D01*
G01X1617641Y1832577D02*
G03Y1833074I-3524J249D01*
G01X1617468Y1831916D02*
G03X1617641Y1832577I-4020J1405D01*
G01X1614660Y1832325D02*
G03X1616085I713J-83D01*
G01X1615646Y1834949D02*
G03X1614060Y1834663I-265J-3073D01*
G01X1636669Y1849085D02*
X1620291D01*
G01X1626315Y1844754D02*
X1630646D01*
G01X1625689Y1843966D02*
X1631271D01*
G01Y1842392D02*
X1625689D01*
G01X1630646Y1841604D02*
X1626315D01*
G01X1636669Y1838907D02*
X1620291D01*
G01X1606827Y1836151D02*
X1660764D01*
G01X1621532Y1835266D02*
X1616925D01*
G01X1660764Y1834970D02*
X1634386D01*
G01X1610117Y1834750D02*
X1608567D01*
G01X1613061D02*
X1611653D01*
G01X1619693D02*
X1618232D01*
G01X1629774D02*
X1628315D01*
G01X1626884D02*
X1625492D01*
G01X1632645D02*
X1631205D01*
G01X1630449Y1834183D02*
X1606827D01*
G01X1617274Y1834085D02*
X1621183D01*
G01X1614721Y1833594D02*
X1613217D01*
G01X1616087Y1833150D02*
X1613087D01*
G01X1616086Y1832325D02*
X1614660D01*
G01X1609975Y1830743D02*
X1608593D01*
G01X1612887D02*
X1611270D01*
G01X1632645D02*
X1631202D01*
G01X1630449Y1830403D02*
X1606827D01*
G01X1619693Y1828996D02*
X1618232D01*
G01X1621183Y1828651D02*
X1617274D01*
G01X1630449Y1828435D02*
X1606827D01*
G01X1656827Y1827805D02*
X1606827D01*
G01X1616925Y1827470D02*
X1621532D01*
G01X1606827Y1826033D02*
X1630449D01*
G01X1621987Y1825502D02*
X1628087D01*
G01X1621987Y1825443D02*
X1628087D01*
G01X1607619Y1825049D02*
X1628087D01*
G01X1626984Y1823868D02*
X1636354D01*
G01X1658795Y1823277D02*
X1628087D01*
G01X1656827Y1822884D02*
X1638323D01*
G01X1636669Y1822687D02*
X1630134D01*
G01X1606827Y1822274D02*
X1626984D01*
G01Y1822096D02*
X1636354D01*
G01X1624543Y1820640D02*
X1623559D01*
G01X1622968Y1820522D02*
X1613984D01*
G01X1624543Y1820443D02*
X1623559D01*
G01X1624543Y1820049D02*
X1623559D01*
G01X1619425Y1819852D02*
X1626590D01*
G01X1615931Y1818848D02*
X1608598D01*
G01X1628087D02*
X1616078D01*
G01X1619425Y1818277D02*
X1626590D01*
G01X1624543Y1818081D02*
X1623559D01*
G01X1616078Y1818061D02*
X1628087D01*
G01X1608598D02*
X1615931D01*
G01X1624543Y1817687D02*
X1623559D01*
G01X1624543Y1817490D02*
X1623559D01*
G01X1615931Y1815699D02*
X1608598D01*
G01X1628087D02*
X1616078D01*
G01X1624543Y1815640D02*
X1623559D01*
G01X1624543Y1815443D02*
X1623559D01*
G01X1624543Y1815049D02*
X1623559D01*
G01X1616078Y1814911D02*
X1628087D01*
G01X1608598D02*
X1615931D01*
G01X1619425Y1814852D02*
X1626590D01*
G01X1619425Y1813277D02*
X1626590D01*
G01X1624543Y1813081D02*
X1623559D01*
G01X1624543Y1812687D02*
X1623559D01*
G01X1615931Y1812549D02*
X1608598D01*
G01X1628087D02*
X1616078D01*
G01X1624543Y1812490D02*
X1623559D01*
G01X1616078Y1811762D02*
X1628087D01*
G01X1608598D02*
X1615931D01*
G01X1624543Y1810640D02*
X1623559D01*
G01X1624543Y1810443D02*
X1623559D01*
G01X1624543Y1810049D02*
X1623559D01*
G01X1619425Y1809852D02*
X1626590D01*
G01X1615931Y1809400D02*
X1608598D01*
G01X1628087D02*
X1616078D01*
G01Y1808612D02*
X1628087D01*
G01X1608598D02*
X1615931D01*
G01X1619425Y1808277D02*
X1626590D01*
G01X1624543Y1808081D02*
X1623559D01*
G01X1624543Y1807687D02*
X1623559D01*
G01X1624543Y1807490D02*
X1623559D01*
G01X1628087Y1806270D02*
X1626984D01*
G01X1615931Y1806250D02*
X1608598D01*
G01X1628087D02*
X1616078D01*
G01X1626512Y1805640D02*
X1625527D01*
G01X1616078Y1805463D02*
X1628087D01*
G01X1608598D02*
X1615931D01*
G01X1626512Y1805443D02*
X1625527D01*
G01X1656827Y1805167D02*
X1630134D01*
G01X1626512Y1805049D02*
X1625527D01*
G01X1626984Y1804852D02*
X1621394D01*
G01X1626984Y1803277D02*
X1621394D01*
G01X1615931Y1803100D02*
X1608598D01*
G01X1628087D02*
X1616078D01*
G01X1626512Y1803081D02*
X1625527D01*
G01X1656827Y1802805D02*
X1630134D01*
G01X1626512Y1802687D02*
X1625527D01*
G01X1626512Y1802490D02*
X1625527D01*
G01X1616078Y1802313D02*
X1628087D01*
G01X1608598D02*
X1615931D01*
G01X1628087Y1801860D02*
X1626984D01*
G01X1624543Y1800640D02*
X1623559D01*
G01X1624543Y1800443D02*
X1623559D01*
G01X1624543Y1800049D02*
X1623559D01*
G01X1615931Y1799951D02*
X1608598D01*
G01X1628087D02*
X1616078D01*
G01X1619425Y1799852D02*
X1626590D01*
G01X1616078Y1799163D02*
X1628087D01*
G01X1608598D02*
X1615931D01*
G01X1619425Y1798277D02*
X1626590D01*
G01X1624543Y1798081D02*
X1623559D01*
G01X1624543Y1797687D02*
X1623559D01*
G01X1624543Y1797490D02*
X1623559D01*
G01X1611618Y1832603D02*
X1612887Y1830743D01*
G01X1610117Y1834750D02*
X1610862Y1833472D01*
G01X1608567Y1834750D02*
X1609888Y1832594D01*
G01X1610665Y1831729D02*
X1611270Y1830743D01*
G01X1621183Y1828651D02*
X1621200Y1828596D01*
X1621253Y1828430D01*
X1621332Y1828171D01*
X1621427Y1827844D01*
X1621532Y1827470D01*
G01X1617274Y1834085D02*
X1617256Y1834140D01*
X1617204Y1834306D01*
X1617125Y1834565D01*
X1617029Y1834892D01*
X1616925Y1835266D01*
G01X1636669Y1822687D02*
Y1849085D01*
G01X1636354Y1823868D02*
Y1822096D01*
G01X1634386Y1836151D02*
Y1827805D01*
G01X1632645Y1834750D02*
Y1830743D01*
G01X1632102Y1805167D02*
Y1822687D01*
G01X1631271Y1842392D02*
Y1843966D01*
G01X1631236D02*
Y1842392D01*
G01X1631212Y1843966D02*
Y1842392D01*
G01X1631205Y1832225D02*
Y1834750D01*
G01X1631202Y1831300D02*
Y1830743D01*
G01X1630449Y1828435D02*
Y1826033D01*
G01Y1834183D02*
Y1830403D01*
G01X1629889Y1842392D02*
Y1843966D01*
G01X1629774Y1834750D02*
Y1832225D01*
G01X1629519Y1843966D02*
Y1842392D01*
G01X1628315Y1832225D02*
Y1834750D01*
G01X1627442Y1842392D02*
Y1843966D01*
G01X1627072D02*
Y1842392D01*
G01X1626884Y1834750D02*
Y1832225D01*
G01X1626512Y1805640D02*
Y1802490D01*
G01X1626145Y1814911D02*
Y1815699D01*
G01Y1818061D02*
Y1818848D01*
G01Y1811762D02*
Y1812549D01*
G01Y1805463D02*
Y1806250D01*
G01Y1808612D02*
Y1809400D01*
G01Y1802313D02*
Y1803100D01*
G01Y1799163D02*
Y1799951D01*
G01X1626118Y1814911D02*
Y1815699D01*
G01Y1818061D02*
Y1818848D01*
G01Y1811762D02*
Y1812549D01*
G01Y1805463D02*
Y1806250D01*
G01Y1808612D02*
Y1809400D01*
G01Y1802313D02*
Y1803100D01*
G01Y1799163D02*
Y1799951D01*
G01X1625748Y1842392D02*
Y1843966D01*
G01X1625742Y1814911D02*
Y1815699D01*
G01Y1818061D02*
Y1818848D01*
G01Y1811762D02*
Y1812549D01*
G01Y1805463D02*
Y1806250D01*
G01Y1808612D02*
Y1809400D01*
G01Y1802313D02*
Y1803100D01*
G01Y1799163D02*
Y1799951D01*
G01X1625724Y1842392D02*
Y1843966D01*
G01X1625689D02*
Y1842392D01*
G01X1625527Y1799852D02*
Y1798277D01*
G01Y1805640D02*
Y1802490D01*
G01Y1809852D02*
Y1808277D01*
G01Y1814852D02*
Y1813277D01*
G01Y1819852D02*
Y1818277D01*
G01X1625492Y1834750D02*
Y1831821D01*
G01X1624543Y1800640D02*
Y1797490D01*
G01Y1804852D02*
Y1803277D01*
G01Y1810640D02*
Y1807490D01*
G01Y1815640D02*
Y1812490D01*
G01Y1820640D02*
Y1817490D01*
G01Y1827805D02*
Y1825502D01*
G01X1623559Y1800640D02*
Y1797490D01*
G01Y1810640D02*
Y1807490D01*
G01Y1815640D02*
Y1812490D01*
G01Y1820640D02*
Y1817490D01*
G01X1622575Y1799852D02*
Y1798277D01*
G01Y1809852D02*
Y1808277D01*
G01Y1814852D02*
Y1813277D01*
G01Y1819852D02*
Y1818277D01*
G01X1622380Y1799951D02*
Y1799163D01*
G01Y1803100D02*
Y1802313D01*
G01Y1806250D02*
Y1805463D01*
G01Y1809400D02*
Y1808612D01*
G01Y1812549D02*
Y1811762D01*
G01Y1815699D02*
Y1814911D01*
G01Y1818848D02*
Y1818061D01*
G01X1621987Y1825502D02*
Y1825443D01*
G01X1621394Y1804852D02*
Y1803277D01*
G01X1621348Y1825049D02*
Y1827805D01*
G01X1620396Y1799951D02*
Y1799163D01*
G01Y1803100D02*
Y1802313D01*
G01Y1806250D02*
Y1805463D01*
G01Y1809400D02*
Y1808612D01*
G01Y1812549D02*
Y1811762D01*
G01Y1815699D02*
Y1814911D01*
G01Y1818848D02*
Y1818061D01*
G01X1620291Y1849085D02*
Y1836151D01*
G01X1619693Y1834750D02*
Y1828996D01*
G01X1619425Y1799852D02*
Y1798277D01*
G01Y1809852D02*
Y1808277D01*
G01Y1814852D02*
Y1813277D01*
G01Y1819852D02*
Y1818277D01*
G01X1618745Y1814911D02*
Y1815699D01*
G01Y1818061D02*
Y1818848D01*
G01Y1811762D02*
Y1812549D01*
G01Y1805463D02*
Y1806250D01*
G01Y1808612D02*
Y1809400D01*
G01Y1802313D02*
Y1803100D01*
G01Y1799163D02*
Y1799951D01*
G01X1618232Y1834750D02*
Y1828996D01*
G01X1617016Y1802313D02*
Y1799951D01*
G01Y1805463D02*
Y1803100D01*
G01Y1808612D02*
Y1806250D01*
G01Y1811762D02*
Y1809400D01*
G01Y1814911D02*
Y1812549D01*
G01Y1818061D02*
Y1815699D01*
G01Y1820522D02*
Y1818848D01*
G01X1616078Y1814911D02*
Y1815699D01*
G01Y1818061D02*
Y1818848D01*
G01Y1811762D02*
Y1812549D01*
G01Y1805463D02*
Y1806250D01*
G01Y1808612D02*
Y1809400D01*
G01Y1802313D02*
Y1803100D01*
G01Y1799163D02*
Y1799951D01*
G01X1615931Y1814911D02*
Y1815699D01*
G01Y1818061D02*
Y1818848D01*
G01Y1811762D02*
Y1812549D01*
G01Y1805463D02*
Y1806250D01*
G01Y1808612D02*
Y1809400D01*
G01Y1802313D02*
Y1803100D01*
G01Y1799163D02*
Y1799951D01*
G01X1614338Y1814911D02*
Y1815699D01*
G01Y1818061D02*
Y1818848D01*
G01Y1811762D02*
Y1812549D01*
G01Y1805463D02*
Y1806250D01*
G01Y1808612D02*
Y1809400D01*
G01Y1802313D02*
Y1803100D01*
G01Y1799163D02*
Y1799951D01*
G01X1613474Y1825049D02*
Y1827805D01*
G01X1613397Y1799951D02*
Y1799163D01*
G01Y1803100D02*
Y1802313D01*
G01Y1806250D02*
Y1805463D01*
G01Y1809400D02*
Y1808612D01*
G01Y1812549D02*
Y1811762D01*
G01Y1815699D02*
Y1814911D01*
G01Y1818848D02*
Y1818061D01*
G01X1610560Y1799951D02*
Y1799163D01*
G01Y1803100D02*
Y1802313D01*
G01Y1806250D02*
Y1805463D01*
G01Y1809400D02*
Y1808612D01*
G01Y1812549D02*
Y1811762D01*
G01Y1815699D02*
Y1814911D01*
G01Y1818848D02*
Y1818061D01*
G01X1610372Y1814911D02*
Y1815699D01*
G01Y1818061D02*
Y1818848D01*
G01Y1811762D02*
Y1812549D01*
G01Y1805463D02*
Y1806250D01*
G01Y1808612D02*
Y1809400D01*
G01Y1802313D02*
Y1803100D01*
G01Y1799163D02*
Y1799951D01*
G01X1608598Y1814911D02*
Y1815699D01*
G01Y1818061D02*
Y1818848D01*
G01Y1811762D02*
Y1812549D01*
G01Y1805463D02*
Y1806250D01*
G01Y1808612D02*
Y1809400D01*
G01Y1802313D02*
Y1803100D01*
G01Y1799163D02*
Y1799951D01*
G01X1607619Y1825049D02*
Y1822274D01*
G01X1607144Y1827805D02*
Y1822274D01*
G01X1606827Y1836151D02*
Y1822274D01*
G01X1617274Y1828651D02*
X1617256Y1828596D01*
X1617204Y1828431D01*
X1617125Y1828172D01*
X1617029Y1827845D01*
X1616925Y1827470D01*
G01X1621532Y1835266D02*
X1621429Y1834897D01*
X1621332Y1834567D01*
X1621252Y1834305D01*
X1621200Y1834139D01*
X1621183Y1834085D01*
G01X1621987Y1825443D02*
X1621731Y1825049D01*
G01X1611653Y1834750D02*
X1610862Y1833472D01*
G01X1609888Y1832594D02*
X1608593Y1830743D01*
G01X1610665Y1831729D02*
X1609975Y1830743D01*
G01X1613061Y1834750D02*
X1611618Y1832603D01*
G01X1631630Y2056683D02*
G03Y2055502I0J-591D01*
G01Y2059439D02*
G03Y2058258I0J-590D01*
G01X1630646Y2073888D02*
G03Y2077037I0J1574D01*
G01X1624887Y2085977D02*
G03X1623817Y2084153I2810J-2874D01*
G01X1631864Y2088878D02*
G03X1629649Y2083711I6937J-6032D01*
G01X1632749Y2088952D02*
G03X1630535Y2083711I7143J-6105D01*
G01X1625331Y2055502D02*
G03Y2056683I0J590D01*
G01Y2058258D02*
G03Y2059439I0J590D01*
G01X1626315Y2077037D02*
G03Y2073888I0J-1574D01*
G01X1625392Y2085433D02*
G03X1624851Y2084449I1277J-1343D01*
G01X1622575Y2087274D02*
G03I-3347J0D01*
G01X1622732D02*
G03I-3504J0D01*
G01X1623756D02*
G03I-4528J0D01*
G01X1611416Y2088878D02*
G03X1609201Y2083711I6937J-6032D01*
G01X1612301Y2088952D02*
G03X1610087Y2083711I7143J-6105D01*
G01X1630449Y2084459D02*
X1606827D01*
G01X1627730Y2084449D02*
X1624851D01*
G01X1629649Y2083711D02*
X1630535D01*
G01X1623817D02*
X1627730D01*
G01X1609201D02*
X1610087D01*
G01X1634386Y2083671D02*
X1660764D01*
G01Y2082490D02*
X1606827D01*
G01X1636669Y2079734D02*
X1620291D01*
G01X1626315Y2077037D02*
X1630646D01*
G01X1625689Y2076250D02*
X1631271D01*
G01Y2074675D02*
X1625689D01*
G01X1630646Y2073888D02*
X1626315D01*
G01X1636669Y2069557D02*
X1620291D01*
G01X1631630Y2060029D02*
X1625331D01*
G01X1630055Y2059734D02*
X1633205D01*
G01X1626905D02*
X1623756D01*
G01Y2057766D02*
X1626905D01*
G01X1633205D02*
X1630055D01*
G01X1623756Y2057175D02*
X1626905D01*
G01X1633205D02*
X1630055D01*
G01X1625341Y2056431D02*
X1625435D01*
G01Y2055683D02*
X1625341D01*
G01X1630055Y2055207D02*
X1633205D01*
G01X1626905D02*
X1623756D01*
G01X1625331Y2054911D02*
X1631630D01*
G01X1621066Y2086512D02*
X1621426Y2086276D01*
X1621665Y2085925D01*
X1621750Y2085522D01*
X1621668Y2085120D01*
X1621431Y2084767D01*
X1621068Y2084527D01*
X1620643Y2084443D01*
G01X1620220Y2084527D02*
X1619860Y2084763D01*
X1619621Y2085113D01*
X1619536Y2085516D01*
X1619618Y2085919D01*
X1619855Y2086271D01*
X1620218Y2086511D01*
X1620643Y2086596D01*
G01X1615899Y2086512D02*
X1616259Y2086276D01*
X1616498Y2085925D01*
X1616583Y2085522D01*
X1616500Y2085120D01*
X1616264Y2084767D01*
X1615901Y2084527D01*
X1615476Y2084443D01*
G01X1615053Y2084527D02*
X1614692Y2084763D01*
X1614454Y2085113D01*
X1614369Y2085516D01*
X1614451Y2085919D01*
X1614688Y2086271D01*
X1615051Y2086511D01*
X1615476Y2086596D01*
G01X1621841Y2086967D02*
X1622293Y2086527D01*
X1622563Y2085991D01*
X1622633Y2085421D01*
X1622491Y2084857D01*
X1622145Y2084332D01*
X1621617Y2083939D01*
X1620975Y2083735D01*
X1620295Y2083738D01*
X1619655Y2083946D01*
X1619132Y2084342D01*
X1618791Y2084866D01*
X1618653Y2085427D01*
X1618725Y2085994D01*
X1618995Y2086528D01*
G01X1616674Y2086967D02*
X1617125Y2086527D01*
X1617395Y2085991D01*
X1617466Y2085421D01*
X1617324Y2084857D01*
X1616977Y2084332D01*
X1616450Y2083939D01*
X1615807Y2083735D01*
X1615128Y2083738D01*
X1614488Y2083946D01*
X1613965Y2084342D01*
X1613624Y2084866D01*
X1613486Y2085427D01*
X1613557Y2085994D01*
X1613828Y2086528D01*
G01X1636669Y2069557D02*
Y2095955D01*
G01X1634386Y2082490D02*
Y2090837D01*
G01X1633205Y2055207D02*
Y2057175D01*
G01Y2059734D02*
Y2057766D01*
G01X1631630Y2059439D02*
Y2060029D01*
G01Y2056683D02*
Y2058258D01*
G01Y2054911D02*
Y2055502D01*
G01X1631271Y2074675D02*
Y2076250D01*
G01X1631236D02*
Y2074675D01*
G01X1631212Y2076250D02*
Y2074675D01*
G01X1630646Y2054911D02*
Y2060029D01*
G01X1630449D02*
Y2054911D01*
G01Y2088238D02*
Y2084459D01*
G01X1630055Y2057766D02*
Y2059734D01*
G01Y2057175D02*
Y2055207D01*
G01X1629889Y2074675D02*
Y2076250D01*
G01X1629519D02*
Y2074675D01*
G01X1627730Y2083711D02*
Y2084449D01*
G01X1627442Y2074675D02*
Y2076250D01*
G01X1627072D02*
Y2074675D01*
G01X1626905Y2057766D02*
Y2059734D01*
G01Y2057175D02*
Y2055207D01*
G01X1626512Y2060029D02*
Y2054911D01*
G01X1626315D02*
Y2060029D01*
G01X1625748Y2074675D02*
Y2076250D01*
G01X1625724Y2074675D02*
Y2076250D01*
G01X1625689D02*
Y2074675D01*
G01X1625435Y2056431D02*
Y2055683D01*
G01X1625341D02*
Y2056304D01*
G01X1625331Y2055502D02*
Y2054911D01*
G01Y2058258D02*
Y2056683D01*
G01Y2060029D02*
Y2059439D01*
G01X1625248Y2056192D02*
Y2056320D01*
G01X1623817Y2084153D02*
Y2083711D01*
G01X1623756Y2055207D02*
Y2057175D01*
G01Y2059734D02*
Y2057766D01*
G01X1620291Y2082490D02*
Y2069557D01*
G01X1606827Y2096171D02*
Y2082490D01*
G01X1600921Y2256565D02*
Y2034124D01*
G01X1619445Y2086967D02*
X1618994Y2086527D01*
X1618724Y2085991D01*
X1618653Y2085421D01*
X1618795Y2084857D01*
X1619142Y2084332D01*
X1619669Y2083939D01*
X1620312Y2083735D01*
X1620991Y2083738D01*
X1621631Y2083946D01*
X1622154Y2084342D01*
X1622495Y2084866D01*
X1622633Y2085427D01*
X1622562Y2085994D01*
X1622291Y2086528D01*
G01X1625341Y2056304D02*
X1625248Y2056192D01*
G01Y2056320D02*
X1625341Y2056431D01*
G01X1621066Y2084527D02*
X1621426Y2084763D01*
X1621665Y2085113D01*
X1621750Y2085516D01*
X1621668Y2085919D01*
X1621431Y2086271D01*
X1621068Y2086511D01*
X1620643Y2086596D01*
G01X1620220Y2086512D02*
X1619860Y2086276D01*
X1619621Y2085925D01*
X1619536Y2085522D01*
X1619618Y2085120D01*
X1619855Y2084767D01*
X1620218Y2084527D01*
X1620643Y2084443D01*
G01X1615899Y2084527D02*
X1616259Y2084763D01*
X1616498Y2085113D01*
X1616583Y2085516D01*
X1616500Y2085919D01*
X1616264Y2086271D01*
X1615901Y2086511D01*
X1615476Y2086596D01*
G01X1615053Y2086512D02*
X1614692Y2086276D01*
X1614454Y2085925D01*
X1614369Y2085522D01*
X1614451Y2085120D01*
X1614688Y2084767D01*
X1615051Y2084527D01*
X1615476Y2084443D01*
G01X1614278Y2086967D02*
X1613826Y2086527D01*
X1613556Y2085991D01*
X1613486Y2085421D01*
X1613628Y2084857D01*
X1613974Y2084332D01*
X1614502Y2083939D01*
X1615144Y2083735D01*
X1615824Y2083738D01*
X1616464Y2083946D01*
X1616986Y2084342D01*
X1617328Y2084866D01*
X1617466Y2085427D01*
X1617394Y2085994D01*
X1617124Y2086528D01*
G01X1567951Y2158446D02*
X1567616Y2157462D01*
G01D02*
X1566946Y2156805D01*
G01X1621394Y2087274D02*
G03I-2166J0D01*
G01X1630449Y2088238D02*
X1606827D01*
G01X1624113Y2087918D02*
X1624925D01*
G01X1620992Y2088813D02*
X1621275Y2088635D01*
X1621462Y2088370D01*
X1621529Y2088068D01*
X1621464Y2087768D01*
X1621279Y2087501D01*
X1620994Y2087319D01*
X1620643Y2087254D01*
G01X1620294Y2087319D02*
X1620012Y2087497D01*
X1619824Y2087762D01*
X1619757Y2088064D01*
X1619822Y2088364D01*
X1620007Y2088631D01*
X1620293Y2088812D01*
X1620643Y2088878D01*
G01X1615825Y2088813D02*
X1616107Y2088635D01*
X1616294Y2088370D01*
X1616361Y2088068D01*
X1616297Y2087768D01*
X1616112Y2087501D01*
X1615826Y2087319D01*
X1615476Y2087254D01*
G01X1615127Y2087319D02*
X1614844Y2087497D01*
X1614657Y2087762D01*
X1614590Y2088064D01*
X1614654Y2088364D01*
X1614840Y2088631D01*
X1615125Y2088812D01*
X1615476Y2088878D01*
G01X1626449Y2088628D02*
X1626632Y2088363D01*
X1626696Y2088064D01*
X1626632Y2087768D01*
G01X1619445Y2086967D02*
X1619123Y2087386D01*
X1618960Y2087870D01*
X1618982Y2088375D01*
X1619185Y2088851D01*
X1619552Y2089255D01*
X1620058Y2089522D01*
X1620649Y2089616D01*
X1621238Y2089519D01*
X1621740Y2089250D01*
X1622105Y2088846D01*
X1622306Y2088368D01*
X1622325Y2087863D01*
X1622161Y2087382D01*
X1621841Y2086967D01*
G01X1614278D02*
X1613955Y2087386D01*
X1613793Y2087870D01*
X1613815Y2088375D01*
X1614017Y2088851D01*
X1614384Y2089255D01*
X1614890Y2089522D01*
X1615482Y2089616D01*
X1616071Y2089519D01*
X1616573Y2089250D01*
X1616937Y2088846D01*
X1617139Y2088368D01*
X1617158Y2087863D01*
X1616994Y2087382D01*
X1616674Y2086967D01*
G01X1624925Y2087918D02*
Y2088066D01*
G01X1624113D02*
Y2087918D01*
G01X1624992Y2088370D02*
X1624925Y2088066D01*
G01X1624113D02*
X1624199Y2088543D01*
X1624447Y2088985D01*
X1624835Y2089337D01*
X1625342Y2089557D01*
X1625919Y2089613D01*
X1626483Y2089491D01*
X1626959Y2089208D01*
X1627298Y2088804D01*
X1627478Y2088347D01*
X1627493Y2087867D01*
X1627336Y2087396D01*
X1627021Y2086979D01*
G01X1625182Y2088638D02*
X1624992Y2088370D01*
G01X1626450Y2087504D02*
X1626633Y2087770D01*
X1626696Y2088067D01*
X1626631Y2088365D01*
G01X1627021Y2086979D02*
X1625392Y2085433D01*
G01X1626450Y2087504D02*
X1624887Y2085977D01*
G01X1621841Y2086967D02*
X1622164Y2087386D01*
X1622326Y2087870D01*
X1622304Y2088375D01*
X1622101Y2088851D01*
X1621735Y2089255D01*
X1621228Y2089522D01*
X1620637Y2089616D01*
X1620048Y2089519D01*
X1619546Y2089250D01*
X1619182Y2088846D01*
X1618980Y2088368D01*
X1618961Y2087863D01*
X1619125Y2087382D01*
X1619445Y2086967D01*
G01X1616674D02*
X1616996Y2087386D01*
X1617159Y2087870D01*
X1617137Y2088375D01*
X1616934Y2088851D01*
X1616567Y2089255D01*
X1616061Y2089522D01*
X1615470Y2089616D01*
X1614881Y2089519D01*
X1614378Y2089250D01*
X1614014Y2088846D01*
X1613813Y2088368D01*
X1613794Y2087863D01*
X1613958Y2087382D01*
X1614278Y2086967D01*
G01X1627021Y2086979D02*
X1627358Y2087441D01*
X1627504Y2087959D01*
X1627444Y2088477D01*
X1627193Y2088961D01*
X1626756Y2089356D01*
X1626183Y2089579D01*
X1625548Y2089598D01*
X1624964Y2089412D01*
X1624509Y2089059D01*
X1624216Y2088587D01*
X1624113Y2088066D01*
G01X1620992Y2087319D02*
X1621275Y2087497D01*
X1621462Y2087762D01*
X1621529Y2088064D01*
X1621464Y2088364D01*
X1621279Y2088631D01*
X1620994Y2088812D01*
X1620643Y2088878D01*
G01X1620294Y2088813D02*
X1620012Y2088635D01*
X1619824Y2088370D01*
X1619757Y2088068D01*
X1619822Y2087768D01*
X1620007Y2087501D01*
X1620293Y2087319D01*
X1620643Y2087254D01*
G01X1615825Y2087319D02*
X1616107Y2087497D01*
X1616294Y2087762D01*
X1616361Y2088064D01*
X1616297Y2088364D01*
X1616112Y2088631D01*
X1615826Y2088812D01*
X1615476Y2088878D01*
G01X1615127Y2088813D02*
X1614844Y2088635D01*
X1614657Y2088370D01*
X1614590Y2088068D01*
X1614654Y2087768D01*
X1614840Y2087501D01*
X1615125Y2087319D01*
X1615476Y2087254D01*
G01X1626590Y2155364D02*
G03X1626984Y2155758I0J394D01*
G01Y2153396D02*
G03X1626590Y2153789I-394J-1D01*
G01Y2100364D02*
G03X1626984Y2100758I0J394D01*
G01Y2098396D02*
G03X1626590Y2098789I-394J-1D01*
G01Y2130364D02*
G03X1626984Y2130758I0J394D01*
G01Y2128396D02*
G03X1626590Y2128789I-394J-1D01*
G01Y2125364D02*
G03X1626984Y2125758I0J394D01*
G01Y2123396D02*
G03X1626590Y2123789I-394J-1D01*
G01Y2120364D02*
G03X1626984Y2120758I0J394D01*
G01Y2118396D02*
G03X1626590Y2118789I-394J-1D01*
G01Y2110364D02*
G03X1626984Y2110758I0J394D01*
G01Y2108396D02*
G03X1626590Y2108789I-394J-1D01*
G01Y2115364D02*
G03X1626984Y2115758I0J394D01*
G01Y2113396D02*
G03X1626590Y2113789I-394J-1D01*
G01Y2105364D02*
G03X1626984Y2105758I0J394D01*
G01Y2103396D02*
G03X1626590Y2103789I-394J-1D01*
G01X1616078Y2157431D02*
X1628087D01*
G01X1608598D02*
X1615931D01*
G01X1624543Y2156151D02*
X1623559D01*
G01X1624543Y2155955D02*
X1623559D01*
G01X1624543Y2155561D02*
X1623559D01*
G01X1619425Y2155364D02*
X1626590D01*
G01X1615931Y2155069D02*
X1608598D01*
G01X1628087D02*
X1616078D01*
G01Y2154281D02*
X1628087D01*
G01X1608598D02*
X1615931D01*
G01X1656827Y2154183D02*
X1630134D01*
G01X1619425Y2153789D02*
X1626590D01*
G01X1624543Y2153592D02*
X1623559D01*
G01X1624543Y2153199D02*
X1623559D01*
G01X1624543Y2153002D02*
X1623559D01*
G01X1615931Y2151919D02*
X1608598D01*
G01X1628087D02*
X1616078D01*
G01X1638323Y2151840D02*
X1656827D01*
G01X1628087D02*
X1626984D01*
G01X1652326Y2151821D02*
X1630134D01*
G01X1628087Y2151722D02*
X1620552D01*
G01X1625093Y2151230D02*
X1622968D01*
G01X1616078Y2151132D02*
X1628087D01*
G01X1608598D02*
X1615931D01*
G01X1626077Y2150935D02*
X1625093D01*
G01X1626077Y2150738D02*
X1625093D01*
G01X1626984Y2150541D02*
X1620959D01*
G01X1626984Y2149360D02*
X1620959D01*
G01X1626077Y2149163D02*
X1625093D01*
G01X1626077Y2148966D02*
X1625093D01*
G01X1615931Y2148770D02*
X1608598D01*
G01X1628087D02*
X1616078D01*
G01Y2147982D02*
X1628087D01*
G01X1608598D02*
X1615931D01*
G01X1620978Y2147903D02*
X1619095D01*
G01X1626077Y2147785D02*
X1625093D01*
G01X1626077Y2147588D02*
X1625093D01*
G01X1626984Y2147392D02*
X1620959D01*
G01X1626984Y2146211D02*
X1620959D01*
G01X1626077Y2146014D02*
X1625093D01*
G01X1626077Y2145817D02*
X1625093D01*
G01X1619095Y2145699D02*
X1620978D01*
G01X1615931Y2145620D02*
X1608598D01*
G01X1628087D02*
X1616078D01*
G01Y2144833D02*
X1628087D01*
G01X1608598D02*
X1615931D01*
G01X1626077Y2144636D02*
X1625093D01*
G01X1626077Y2144439D02*
X1625093D01*
G01X1626984Y2144242D02*
X1620959D01*
G01X1626984Y2143061D02*
X1620959D01*
G01X1626077Y2142864D02*
X1625093D01*
G01X1626077Y2142667D02*
X1625093D01*
G01X1615931Y2142470D02*
X1608598D01*
G01X1628087D02*
X1616078D01*
G01Y2141683D02*
X1628087D01*
G01X1608598D02*
X1615931D01*
G01X1626077Y2141486D02*
X1625093D01*
G01X1626077Y2141289D02*
X1625093D01*
G01X1626984Y2141092D02*
X1620959D01*
G01X1626984Y2139911D02*
X1620959D01*
G01X1626077Y2139714D02*
X1625093D01*
G01X1626077Y2139518D02*
X1625093D01*
G01X1615931Y2139321D02*
X1608598D01*
G01X1628087D02*
X1616078D01*
G01Y2138533D02*
X1628087D01*
G01X1608598D02*
X1615931D01*
G01X1620978Y2138455D02*
X1619095D01*
G01X1626077Y2138337D02*
X1625093D01*
G01X1626077Y2138140D02*
X1625093D01*
G01X1626984Y2137943D02*
X1620959D01*
G01X1626984Y2136762D02*
X1620959D01*
G01X1626077Y2136565D02*
X1625093D01*
G01X1626077Y2136368D02*
X1625093D01*
G01X1619095Y2136250D02*
X1620978D01*
G01X1615931Y2136171D02*
X1608598D01*
G01X1628087D02*
X1616078D01*
G01Y2135384D02*
X1628087D01*
G01X1608598D02*
X1615931D01*
G01X1626077Y2135187D02*
X1625093D01*
G01X1626077Y2134990D02*
X1625093D01*
G01X1626984Y2134793D02*
X1620959D01*
G01X1626984Y2133612D02*
X1620959D01*
G01X1626077Y2133415D02*
X1625093D01*
G01X1626077Y2133218D02*
X1625093D01*
G01X1615931Y2133022D02*
X1608598D01*
G01X1628087D02*
X1616078D01*
G01X1625093Y2132923D02*
X1622968D01*
G01X1620552Y2132431D02*
X1628087D01*
G01X1652326Y2132333D02*
X1630134D01*
G01X1628087Y2132313D02*
X1626984D01*
G01X1656827D02*
X1638323D01*
G01X1616078Y2132234D02*
X1628087D01*
G01X1608598D02*
X1615931D01*
G01X1624543Y2131151D02*
X1623559D01*
G01X1624543Y2130955D02*
X1623559D01*
G01X1624543Y2130561D02*
X1623559D01*
G01X1619425Y2130364D02*
X1626590D01*
G01X1656827Y2129970D02*
X1630134D01*
G01X1615931Y2129872D02*
X1608598D01*
G01X1628087D02*
X1616078D01*
G01Y2129085D02*
X1628087D01*
G01X1608598D02*
X1615931D01*
G01X1619425Y2128789D02*
X1626590D01*
G01X1624543Y2128592D02*
X1623559D01*
G01X1624543Y2128199D02*
X1623559D01*
G01X1624543Y2128002D02*
X1623559D01*
G01X1615931Y2126722D02*
X1608598D01*
G01X1628087D02*
X1616078D01*
G01X1624543Y2126151D02*
X1623559D01*
G01X1657784Y2125974D02*
X1638323D01*
G01X1624543Y2125955D02*
X1623559D01*
G01X1616078Y2125935D02*
X1628087D01*
G01X1608598D02*
X1615931D01*
G01X1624543Y2125561D02*
X1623559D01*
G01X1619425Y2125364D02*
X1626590D01*
G01X1619425Y2123789D02*
X1626590D01*
G01X1624543Y2123592D02*
X1623559D01*
G01X1615931Y2123573D02*
X1608598D01*
G01X1628087D02*
X1616078D01*
G01X1624543Y2123199D02*
X1623559D01*
G01X1624543Y2123002D02*
X1623559D01*
G01X1616078Y2122785D02*
X1628087D01*
G01X1608598D02*
X1615931D01*
G01X1624543Y2121151D02*
X1623559D01*
G01X1624543Y2120955D02*
X1623559D01*
G01X1624543Y2120561D02*
X1623559D01*
G01X1630358Y2097333D02*
X1630706Y2097418D01*
G01X1632013Y2097077D02*
X1632362Y2097162D01*
G01X1615931Y2120423D02*
X1608598D01*
G01X1628087D02*
X1616078D01*
G01X1619425Y2120364D02*
X1626590D01*
G01X1616078Y2119636D02*
X1628087D01*
G01X1608598D02*
X1615931D01*
G01X1619425Y2118789D02*
X1626590D01*
G01X1624543Y2118592D02*
X1623559D01*
G01X1624543Y2118199D02*
X1623559D01*
G01X1624543Y2118002D02*
X1623559D01*
G01X1615931Y2117274D02*
X1608598D01*
G01X1628087D02*
X1616078D01*
G01Y2116486D02*
X1628087D01*
G01X1608598D02*
X1615931D01*
G01X1624543Y2116151D02*
X1623559D01*
G01X1624543Y2115955D02*
X1623559D01*
G01X1624543Y2115561D02*
X1623559D01*
G01X1619425Y2115364D02*
X1626590D01*
G01X1656827Y2114734D02*
X1630134D01*
G01X1615931Y2114124D02*
X1608598D01*
G01X1628087D02*
X1616078D01*
G01X1619425Y2113789D02*
X1626590D01*
G01X1624543Y2113592D02*
X1623559D01*
G01X1616078Y2113337D02*
X1628087D01*
G01X1608598D02*
X1615931D01*
G01X1624543Y2113199D02*
X1623559D01*
G01X1624543Y2113002D02*
X1623559D01*
G01X1656827Y2112372D02*
X1630134D01*
G01X1624543Y2111151D02*
X1623559D01*
G01X1615931Y2110974D02*
X1608598D01*
G01X1628087D02*
X1616078D01*
G01X1624543Y2110955D02*
X1623559D01*
G01X1624543Y2110561D02*
X1623559D01*
G01X1619425Y2110364D02*
X1626590D01*
G01X1616078Y2110187D02*
X1628087D01*
G01X1608598D02*
X1615931D01*
G01X1619425Y2108789D02*
X1626590D01*
G01X1624543Y2108592D02*
X1623559D01*
G01X1624543Y2108199D02*
X1623559D01*
G01X1624543Y2108002D02*
X1623559D01*
G01X1615931Y2107825D02*
X1608598D01*
G01X1628087D02*
X1616078D01*
G01Y2107037D02*
X1628087D01*
G01X1608598D02*
X1615931D01*
G01X1624543Y2106151D02*
X1623559D01*
G01X1624543Y2105955D02*
X1623559D01*
G01X1624543Y2105561D02*
X1623559D01*
G01X1619425Y2105364D02*
X1626590D01*
G01X1615931Y2104675D02*
X1608598D01*
G01X1628087D02*
X1616078D01*
G01Y2103888D02*
X1628087D01*
G01X1608598D02*
X1615931D01*
G01X1619425Y2103789D02*
X1626590D01*
G01X1624543Y2103592D02*
X1623559D01*
G01X1624543Y2103199D02*
X1623559D01*
G01X1624543Y2103002D02*
X1623559D01*
G01X1629051Y2101939D02*
X1633146D01*
G01X1615931Y2101525D02*
X1608598D01*
G01X1628087D02*
X1616078D01*
G01X1633146Y2101427D02*
X1629748D01*
G01X1624543Y2101151D02*
X1623559D01*
G01X1624543Y2100955D02*
X1623559D01*
G01X1630358Y2100915D02*
X1629661D01*
G01X1616078Y2100738D02*
X1628087D01*
G01X1608598D02*
X1615931D01*
G01X1626531Y2100581D02*
X1618461D01*
G01X1624543Y2100561D02*
X1623559D01*
G01X1619425Y2100364D02*
X1626590D01*
G01X1632187Y2100233D02*
X1631752D01*
G01X1631839Y2099721D02*
X1632100D01*
G01X1619425Y2098789D02*
X1626590D01*
G01X1618461Y2098612D02*
X1626531D01*
G01X1624543Y2098592D02*
X1623559D01*
G01X1624543Y2098199D02*
X1623559D01*
G01X1622968Y2098159D02*
X1613984D01*
G01X1624543Y2098002D02*
X1623559D01*
G01X1630271Y2097844D02*
X1630096D01*
G01X1630009Y2097333D02*
X1630358D01*
G01X1626984Y2096545D02*
X1636354D01*
G01X1626984Y2096171D02*
X1606827D01*
G01X1636669Y2095955D02*
X1630134D01*
G01X1656827Y2095758D02*
X1638323D01*
G01X1628087Y2095364D02*
X1658795D01*
G01X1626984Y2094774D02*
X1636354D01*
G01X1607619Y2093592D02*
X1628087D01*
G01X1621987Y2093199D02*
X1628087D01*
G01Y2093140D02*
X1621987D01*
G01X1630449Y2092648D02*
X1606827D01*
G01X1656827Y2090837D02*
X1606827D01*
G01Y2090207D02*
X1630449D01*
G01X1612302Y2089616D02*
X1608463D01*
G01X1632749D02*
X1628911D01*
G01Y2088878D02*
X1631864D01*
G01X1608463D02*
X1611416D01*
G01X1629661Y2097418D02*
X1630009Y2097333D01*
G01X1625823Y2088878D02*
X1626170Y2088809D01*
G01X1630096Y2097844D02*
X1629835Y2097930D01*
G01X1632536Y2100062D02*
X1632187Y2100233D01*
G01X1632100Y2099721D02*
X1632362Y2099550D01*
G01X1626170Y2088809D02*
X1626450Y2088628D01*
G01X1629748Y2101427D02*
X1630358Y2100915D01*
G01X1629661D02*
X1629051Y2101427D01*
G01X1632884Y2099721D02*
X1632536Y2100062D01*
G01X1629312Y2097759D02*
X1629661Y2097418D01*
G01X1632362Y2099550D02*
X1632536Y2099295D01*
G01X1629835Y2097930D02*
X1629661Y2098186D01*
G01X1621731Y2093592D02*
X1621987Y2093199D01*
G01X1633058Y2099380D02*
X1632884Y2099721D01*
G01X1629138Y2098100D02*
X1629312Y2097759D01*
G01X1629661Y2098186D02*
X1629574Y2098442D01*
G01X1632536Y2099295D02*
X1632623Y2098953D01*
G01X1629051Y2098442D02*
X1629138Y2098100D01*
G01X1633146Y2098953D02*
X1633058Y2099380D01*
G01X1638323Y2228396D02*
Y2095758D01*
G01X1636354Y2096545D02*
Y2094774D01*
G01X1633146Y2098271D02*
Y2098953D01*
G01Y2101939D02*
Y2101427D01*
G01X1632749Y2088952D02*
Y2089616D01*
G01X1632623Y2098953D02*
Y2098271D01*
G01X1632102Y2154183D02*
Y2170522D01*
G01Y2112372D02*
Y2095955D01*
G01Y2129970D02*
Y2114734D01*
G01Y2151821D02*
Y2132333D01*
G01X1632013Y2097588D02*
Y2097077D01*
G01X1631316Y2098442D02*
Y2098953D01*
G01X1630793D02*
Y2098442D01*
G01X1630449Y2092648D02*
Y2090207D01*
G01X1630134Y2095955D02*
Y2228199D01*
G01X1630009Y2099465D02*
Y2099977D01*
G01X1629574Y2098442D02*
Y2098953D01*
G01X1629051Y2101427D02*
Y2101939D01*
G01Y2098868D02*
Y2098442D01*
G01X1628911Y2089616D02*
Y2088878D01*
G01X1628087Y2231014D02*
Y2093140D01*
G01X1626984Y2093592D02*
Y2230561D01*
G01X1626905Y2151722D02*
Y2132431D01*
G01X1626590D02*
Y2151722D01*
G01X1626531Y2098612D02*
Y2100581D01*
G01X1626145Y2157431D02*
Y2158218D01*
G01Y2154281D02*
Y2155069D01*
G01Y2147982D02*
Y2148770D01*
G01Y2151132D02*
Y2151919D01*
G01Y2144833D02*
Y2145620D01*
G01Y2138533D02*
Y2139321D01*
G01Y2141683D02*
Y2142470D01*
G01Y2135384D02*
Y2136171D01*
G01Y2129085D02*
Y2129872D01*
G01Y2132234D02*
Y2133022D01*
G01Y2125935D02*
Y2126722D01*
G01Y2119636D02*
Y2120423D01*
G01Y2122785D02*
Y2123573D01*
G01Y2116486D02*
Y2117274D01*
G01Y2110187D02*
Y2110974D01*
G01Y2113337D02*
Y2114124D01*
G01Y2107037D02*
Y2107825D01*
G01Y2100738D02*
Y2101525D01*
G01Y2103888D02*
Y2104675D01*
G01X1626118Y2157431D02*
Y2158218D01*
G01Y2154281D02*
Y2155069D01*
G01Y2147982D02*
Y2148770D01*
G01Y2151132D02*
Y2151919D01*
G01Y2144833D02*
Y2145620D01*
G01Y2138533D02*
Y2139321D01*
G01Y2141683D02*
Y2142470D01*
G01Y2135384D02*
Y2136171D01*
G01Y2129085D02*
Y2129872D01*
G01Y2132234D02*
Y2133022D01*
G01Y2125935D02*
Y2126722D01*
G01Y2119636D02*
Y2120423D01*
G01Y2122785D02*
Y2123573D01*
G01Y2116486D02*
Y2117274D01*
G01Y2110187D02*
Y2110974D01*
G01Y2113337D02*
Y2114124D01*
G01Y2107037D02*
Y2107825D01*
G01Y2100738D02*
Y2101525D01*
G01Y2103888D02*
Y2104675D01*
G01X1626077Y2135384D02*
Y2133022D01*
G01Y2138533D02*
Y2136171D01*
G01Y2141683D02*
Y2139321D01*
G01Y2144833D02*
Y2142470D01*
G01Y2147982D02*
Y2145620D01*
G01Y2151132D02*
Y2148770D01*
G01X1625803Y2151722D02*
Y2132431D01*
G01X1625742Y2157431D02*
Y2158218D01*
G01Y2154281D02*
Y2155069D01*
G01Y2147982D02*
Y2148770D01*
G01Y2151132D02*
Y2151919D01*
G01Y2144833D02*
Y2145620D01*
G01Y2138533D02*
Y2139321D01*
G01Y2141683D02*
Y2142470D01*
G01Y2135384D02*
Y2136171D01*
G01Y2129085D02*
Y2129872D01*
G01Y2132234D02*
Y2133022D01*
G01Y2125935D02*
Y2126722D01*
G01Y2119636D02*
Y2120423D01*
G01Y2122785D02*
Y2123573D01*
G01Y2116486D02*
Y2117274D01*
G01Y2110187D02*
Y2110974D01*
G01Y2113337D02*
Y2114124D01*
G01Y2107037D02*
Y2107825D01*
G01Y2100738D02*
Y2101525D01*
G01Y2103888D02*
Y2104675D01*
G01X1625527Y2100364D02*
Y2098789D01*
G01Y2105364D02*
Y2103789D01*
G01Y2110364D02*
Y2108789D01*
G01Y2115364D02*
Y2113789D01*
G01Y2120364D02*
Y2118789D01*
G01Y2125364D02*
Y2123789D01*
G01Y2130364D02*
Y2128789D01*
G01Y2155364D02*
Y2153789D01*
G01X1625303Y2151722D02*
Y2132431D01*
G01X1625093Y2132923D02*
Y2151230D01*
G01X1624543Y2093140D02*
Y2090837D01*
G01Y2101151D02*
Y2098002D01*
G01Y2106151D02*
Y2103002D01*
G01Y2111151D02*
Y2108002D01*
G01Y2116151D02*
Y2113002D01*
G01Y2121151D02*
Y2118002D01*
G01Y2126151D02*
Y2123002D01*
G01Y2131151D02*
Y2128002D01*
G01Y2156151D02*
Y2153002D01*
G01X1624386Y2132431D02*
Y2151722D01*
G01X1624109Y2134793D02*
Y2133612D01*
G01Y2137943D02*
Y2136762D01*
G01Y2141092D02*
Y2139911D01*
G01Y2144242D02*
Y2143061D01*
G01Y2147392D02*
Y2146211D01*
G01Y2150541D02*
Y2149360D01*
G01X1623559Y2101151D02*
Y2098002D01*
G01Y2106151D02*
Y2103002D01*
G01Y2111151D02*
Y2108002D01*
G01Y2116151D02*
Y2113002D01*
G01Y2121151D02*
Y2118002D01*
G01Y2126151D02*
Y2123002D01*
G01Y2131151D02*
Y2128002D01*
G01Y2156151D02*
Y2153002D01*
G01X1622968Y2093592D02*
Y2230561D01*
G01X1622575Y2100364D02*
Y2098789D01*
G01Y2105364D02*
Y2103789D01*
G01Y2110364D02*
Y2108789D01*
G01Y2115364D02*
Y2113789D01*
G01Y2120364D02*
Y2118789D01*
G01Y2125364D02*
Y2123789D01*
G01Y2130364D02*
Y2128789D01*
G01Y2155364D02*
Y2153789D01*
G01X1622514Y2096171D02*
Y2227785D01*
G01X1622380Y2101525D02*
Y2100738D01*
G01Y2104675D02*
Y2103888D01*
G01Y2107825D02*
Y2107037D01*
G01Y2110974D02*
Y2110187D01*
G01Y2114124D02*
Y2113337D01*
G01Y2117274D02*
Y2116486D01*
G01Y2120423D02*
Y2119636D01*
G01Y2123573D02*
Y2122785D01*
G01Y2126722D02*
Y2125935D01*
G01Y2129872D02*
Y2129085D01*
G01Y2133022D02*
Y2132234D01*
G01Y2136171D02*
Y2135384D01*
G01Y2139321D02*
Y2138533D01*
G01Y2142470D02*
Y2141683D01*
G01Y2145620D02*
Y2144833D01*
G01Y2148770D02*
Y2147982D01*
G01Y2151919D02*
Y2151132D01*
G01Y2155069D02*
Y2154281D01*
G01Y2158218D02*
Y2157431D01*
G01X1621987Y2093199D02*
Y2093140D01*
G01X1621348Y2090837D02*
Y2093592D01*
G01X1621030Y2132431D02*
Y2151722D01*
G01X1620978Y2138455D02*
Y2136250D01*
G01Y2147903D02*
Y2145699D01*
G01X1620959Y2134793D02*
Y2133612D01*
G01Y2137943D02*
Y2136762D01*
G01Y2141092D02*
Y2139911D01*
G01Y2144242D02*
Y2143061D01*
G01Y2147392D02*
Y2146211D01*
G01Y2150541D02*
Y2149360D01*
G01X1620552Y2147903D02*
Y2151722D01*
G01Y2138455D02*
Y2145699D01*
G01Y2132431D02*
Y2136250D01*
G01X1620396Y2101525D02*
Y2100738D01*
G01Y2104675D02*
Y2103888D01*
G01Y2107825D02*
Y2107037D01*
G01Y2110974D02*
Y2110187D01*
G01Y2114124D02*
Y2113337D01*
G01Y2117274D02*
Y2116486D01*
G01Y2120423D02*
Y2119636D01*
G01Y2123573D02*
Y2122785D01*
G01Y2126722D02*
Y2125935D01*
G01Y2129872D02*
Y2129085D01*
G01Y2133022D02*
Y2132234D01*
G01Y2136171D02*
Y2135384D01*
G01Y2139321D02*
Y2138533D01*
G01Y2142470D02*
Y2141683D01*
G01Y2145620D02*
Y2144833D01*
G01Y2148770D02*
Y2147982D01*
G01Y2151919D02*
Y2151132D01*
G01Y2155069D02*
Y2154281D01*
G01Y2158218D02*
Y2157431D01*
G01X1619425Y2100364D02*
Y2098789D01*
G01Y2105364D02*
Y2103789D01*
G01Y2110364D02*
Y2108789D01*
G01Y2115364D02*
Y2113789D01*
G01Y2120364D02*
Y2118789D01*
G01Y2125364D02*
Y2123789D01*
G01Y2130364D02*
Y2128789D01*
G01Y2155364D02*
Y2153789D01*
G01X1619095Y2145699D02*
Y2147903D01*
G01Y2136250D02*
Y2138455D01*
G01X1618745Y2157431D02*
Y2158218D01*
G01Y2154281D02*
Y2155069D01*
G01Y2147982D02*
Y2148770D01*
G01Y2151132D02*
Y2151919D01*
G01Y2144833D02*
Y2145620D01*
G01Y2138533D02*
Y2139321D01*
G01Y2141683D02*
Y2142470D01*
G01Y2135384D02*
Y2136171D01*
G01Y2129085D02*
Y2129872D01*
G01Y2132234D02*
Y2133022D01*
G01Y2125935D02*
Y2126722D01*
G01Y2119636D02*
Y2120423D01*
G01Y2122785D02*
Y2123573D01*
G01Y2116486D02*
Y2117274D01*
G01Y2110187D02*
Y2110974D01*
G01Y2113337D02*
Y2114124D01*
G01Y2107037D02*
Y2107825D01*
G01Y2100738D02*
Y2101525D01*
G01Y2103888D02*
Y2104675D01*
G01X1618461Y2100581D02*
Y2098612D01*
G01X1617016Y2103888D02*
Y2101525D01*
G01Y2100738D02*
Y2098159D01*
G01Y2107037D02*
Y2104675D01*
G01Y2110187D02*
Y2107825D01*
G01Y2113337D02*
Y2110974D01*
G01Y2116486D02*
Y2114124D01*
G01Y2119636D02*
Y2117274D01*
G01Y2122785D02*
Y2120423D01*
G01Y2125935D02*
Y2123573D01*
G01Y2129085D02*
Y2126722D01*
G01Y2132234D02*
Y2129872D01*
G01Y2135384D02*
Y2133022D01*
G01Y2138533D02*
Y2136171D01*
G01Y2141683D02*
Y2139321D01*
G01Y2144833D02*
Y2142470D01*
G01Y2147982D02*
Y2145620D01*
G01Y2151132D02*
Y2148770D01*
G01Y2154281D02*
Y2151919D01*
G01Y2157431D02*
Y2155069D01*
G01X1616078Y2157431D02*
Y2158218D01*
G01Y2154281D02*
Y2155069D01*
G01Y2147982D02*
Y2148770D01*
G01Y2151132D02*
Y2151919D01*
G01Y2144833D02*
Y2145620D01*
G01Y2138533D02*
Y2139321D01*
G01Y2141683D02*
Y2142470D01*
G01Y2135384D02*
Y2136171D01*
G01Y2129085D02*
Y2129872D01*
G01Y2132234D02*
Y2133022D01*
G01Y2125935D02*
Y2126722D01*
G01Y2119636D02*
Y2120423D01*
G01Y2122785D02*
Y2123573D01*
G01Y2116486D02*
Y2117274D01*
G01Y2110187D02*
Y2110974D01*
G01Y2113337D02*
Y2114124D01*
G01Y2107037D02*
Y2107825D01*
G01Y2100738D02*
Y2101525D01*
G01Y2103888D02*
Y2104675D01*
G01X1615931Y2157431D02*
Y2158218D01*
G01Y2154281D02*
Y2155069D01*
G01Y2147982D02*
Y2148770D01*
G01Y2151132D02*
Y2151919D01*
G01Y2144833D02*
Y2145620D01*
G01Y2138533D02*
Y2139321D01*
G01Y2141683D02*
Y2142470D01*
G01Y2135384D02*
Y2136171D01*
G01Y2129085D02*
Y2129872D01*
G01Y2132234D02*
Y2133022D01*
G01Y2125935D02*
Y2126722D01*
G01Y2119636D02*
Y2120423D01*
G01Y2122785D02*
Y2123573D01*
G01Y2116486D02*
Y2117274D01*
G01Y2110187D02*
Y2110974D01*
G01Y2113337D02*
Y2114124D01*
G01Y2107037D02*
Y2107825D01*
G01Y2100738D02*
Y2101525D01*
G01Y2103888D02*
Y2104675D01*
G01X1614338Y2157431D02*
Y2158218D01*
G01Y2154281D02*
Y2155069D01*
G01Y2147982D02*
Y2148770D01*
G01Y2151132D02*
Y2151919D01*
G01Y2144833D02*
Y2145620D01*
G01Y2138533D02*
Y2139321D01*
G01Y2141683D02*
Y2142470D01*
G01Y2135384D02*
Y2136171D01*
G01Y2129085D02*
Y2129872D01*
G01Y2132234D02*
Y2133022D01*
G01Y2125935D02*
Y2126722D01*
G01Y2119636D02*
Y2120423D01*
G01Y2122785D02*
Y2123573D01*
G01Y2116486D02*
Y2117274D01*
G01Y2110187D02*
Y2110974D01*
G01Y2113337D02*
Y2114124D01*
G01Y2107037D02*
Y2107825D01*
G01Y2100738D02*
Y2101525D01*
G01Y2103888D02*
Y2104675D01*
G01X1613984Y2230561D02*
Y2093592D01*
G01X1613474Y2090837D02*
Y2093592D01*
G01X1613397Y2101525D02*
Y2100738D01*
G01Y2104675D02*
Y2103888D01*
G01Y2107825D02*
Y2107037D01*
G01Y2110974D02*
Y2110187D01*
G01Y2114124D02*
Y2113337D01*
G01Y2117274D02*
Y2116486D01*
G01Y2120423D02*
Y2119636D01*
G01Y2123573D02*
Y2122785D01*
G01Y2126722D02*
Y2125935D01*
G01Y2129872D02*
Y2129085D01*
G01Y2133022D02*
Y2132234D01*
G01Y2136171D02*
Y2135384D01*
G01Y2139321D02*
Y2138533D01*
G01Y2142470D02*
Y2141683D01*
G01Y2145620D02*
Y2144833D01*
G01Y2148770D02*
Y2147982D01*
G01Y2151919D02*
Y2151132D01*
G01Y2155069D02*
Y2154281D01*
G01Y2158218D02*
Y2157431D01*
G01X1612302Y2088952D02*
Y2089616D01*
G01X1610560Y2101525D02*
Y2100738D01*
G01Y2104675D02*
Y2103888D01*
G01Y2107825D02*
Y2107037D01*
G01Y2110974D02*
Y2110187D01*
G01Y2114124D02*
Y2113337D01*
G01Y2117274D02*
Y2116486D01*
G01Y2120423D02*
Y2119636D01*
G01Y2123573D02*
Y2122785D01*
G01Y2126722D02*
Y2125935D01*
G01Y2129872D02*
Y2129085D01*
G01Y2133022D02*
Y2132234D01*
G01Y2136171D02*
Y2135384D01*
G01Y2139321D02*
Y2138533D01*
G01Y2142470D02*
Y2141683D01*
G01Y2145620D02*
Y2144833D01*
G01Y2148770D02*
Y2147982D01*
G01Y2151919D02*
Y2151132D01*
G01Y2155069D02*
Y2154281D01*
G01Y2158218D02*
Y2157431D01*
G01X1610372D02*
Y2158218D01*
G01Y2154281D02*
Y2155069D01*
G01Y2147982D02*
Y2148770D01*
G01Y2151132D02*
Y2151919D01*
G01Y2144833D02*
Y2145620D01*
G01Y2138533D02*
Y2139321D01*
G01Y2141683D02*
Y2142470D01*
G01Y2135384D02*
Y2136171D01*
G01Y2129085D02*
Y2129872D01*
G01Y2132234D02*
Y2133022D01*
G01Y2125935D02*
Y2126722D01*
G01Y2119636D02*
Y2120423D01*
G01Y2122785D02*
Y2123573D01*
G01Y2116486D02*
Y2117274D01*
G01Y2110187D02*
Y2110974D01*
G01Y2113337D02*
Y2114124D01*
G01Y2107037D02*
Y2107825D01*
G01Y2100738D02*
Y2101525D01*
G01Y2103888D02*
Y2104675D01*
G01X1608598Y2157431D02*
Y2158218D01*
G01Y2154281D02*
Y2155069D01*
G01Y2147982D02*
Y2148770D01*
G01Y2151132D02*
Y2151919D01*
G01Y2144833D02*
Y2145620D01*
G01Y2138533D02*
Y2139321D01*
G01Y2141683D02*
Y2142470D01*
G01Y2135384D02*
Y2136171D01*
G01Y2129085D02*
Y2129872D01*
G01Y2132234D02*
Y2133022D01*
G01Y2125935D02*
Y2126722D01*
G01Y2119636D02*
Y2120423D01*
G01Y2122785D02*
Y2123573D01*
G01Y2116486D02*
Y2117274D01*
G01Y2110187D02*
Y2110974D01*
G01Y2113337D02*
Y2114124D01*
G01Y2107037D02*
Y2107825D01*
G01Y2100738D02*
Y2101525D01*
G01Y2103888D02*
Y2104675D01*
G01X1608463Y2089616D02*
Y2088878D01*
G01X1607619Y2096171D02*
Y2093592D01*
G01X1607144Y2096171D02*
Y2090837D01*
G01X1633058Y2097844D02*
X1633146Y2098271D01*
G01X1630881Y2099380D02*
X1630793Y2098953D01*
G01X1629138Y2099295D02*
X1629051Y2098868D01*
G01X1630793Y2098442D02*
X1630706Y2098186D01*
G01X1629574Y2098953D02*
X1629661Y2099209D01*
G01X1632623Y2098271D02*
X1632536Y2097930D01*
G01X1631229Y2098100D02*
X1631316Y2098442D01*
G01Y2098953D02*
X1631403Y2099295D01*
G01X1631055Y2097759D02*
X1631229Y2098100D01*
G01X1631055Y2099721D02*
X1630881Y2099380D01*
G01X1630706Y2098186D02*
X1630532Y2097930D01*
G01X1631403Y2099295D02*
X1631577Y2099550D01*
G01X1632797Y2097418D02*
X1633058Y2097844D01*
G01X1632536Y2097930D02*
X1632274Y2097674D01*
G01X1630706Y2097418D02*
X1631055Y2097759D01*
G01X1631403Y2100062D02*
X1631055Y2099721D01*
G01X1629661Y2099209D02*
X1629835Y2099380D01*
G01X1629400Y2099636D02*
X1629138Y2099295D01*
G01X1632274Y2097674D02*
X1632013Y2097588D01*
G01X1630532Y2097930D02*
X1630271Y2097844D01*
G01X1630009Y2099977D02*
X1629748Y2099892D01*
G01X1631752Y2100233D02*
X1631403Y2100062D01*
G01X1629835Y2099380D02*
X1630009Y2099465D01*
G01X1632362Y2097162D02*
X1632797Y2097418D01*
G01X1625181Y2088637D02*
X1625469Y2088816D01*
X1625823Y2088878D01*
G01X1631577Y2099550D02*
X1631839Y2099721D01*
G01X1629748Y2099892D02*
X1629400Y2099636D01*
G01X1567616Y2160742D02*
X1567951Y2159758D01*
G01D02*
Y2158446D01*
G01X1566611Y2159102D02*
Y2160086D01*
G01X1572977Y2206018D02*
X1566611D01*
G01Y2196832D02*
X1572977D01*
G01X1571301Y2171569D02*
X1572977D01*
G01X1567951Y2166648D02*
X1566946D01*
G01D02*
X1567616Y2165992D01*
G01D02*
X1567951Y2165007D01*
G01X1567281Y2177803D02*
X1566946Y2179443D01*
G01X1572977Y2171569D02*
Y2182724D01*
G01Y2196832D02*
Y2194863D01*
G01Y2207986D02*
Y2206018D01*
G01X1571301Y2181084D02*
Y2171569D01*
G01X1567951Y2165007D02*
Y2163695D01*
G01Y2168288D02*
Y2166648D01*
G01X1567281Y2175834D02*
Y2177803D01*
G01X1566611Y2164351D02*
Y2165007D01*
G01Y2206018D02*
Y2196832D01*
G01X1566946Y2174194D02*
X1567281Y2175834D01*
G01X1567951Y2163695D02*
X1567616Y2162711D01*
G01X1568621Y2186005D02*
X1567616Y2185349D01*
G01X1626590Y2160364D02*
G03X1626984Y2160758I0J394D01*
G01Y2158396D02*
G03X1626590Y2158789I-394J-1D01*
G01X1615931Y2161368D02*
X1608598D01*
G01X1628087D02*
X1616078D01*
G01X1624543Y2161151D02*
X1623559D01*
G01X1624543Y2160955D02*
X1623559D01*
G01X1616078Y2160581D02*
X1628087D01*
G01X1608598D02*
X1615931D01*
G01X1624543Y2160561D02*
X1623559D01*
G01X1619425Y2160364D02*
X1626590D01*
G01X1619425Y2158789D02*
X1626590D01*
G01X1624543Y2158592D02*
X1623559D01*
G01X1657784Y2158277D02*
X1638323D01*
G01X1615931Y2158218D02*
X1608598D01*
G01X1628087D02*
X1616078D01*
G01X1624543Y2158199D02*
X1623559D01*
G01X1624543Y2158002D02*
X1623559D01*
G01X1626145Y2160581D02*
Y2161368D01*
G01X1626118Y2160581D02*
Y2161368D01*
G01X1625742Y2160581D02*
Y2161368D01*
G01X1625527Y2160364D02*
Y2158789D01*
G01X1624543Y2161151D02*
Y2158002D01*
G01X1623559Y2161151D02*
Y2158002D01*
G01X1622575Y2160364D02*
Y2158789D01*
G01X1622380Y2161368D02*
Y2160581D01*
G01X1620396Y2161368D02*
Y2160581D01*
G01X1619425Y2160364D02*
Y2158789D01*
G01X1618745Y2160581D02*
Y2161368D01*
G01X1617016Y2160581D02*
Y2158218D01*
G01Y2163730D02*
Y2161368D01*
G01X1616078Y2160581D02*
Y2161368D01*
G01X1615931Y2160581D02*
Y2161368D01*
G01X1614338Y2160581D02*
Y2161368D01*
G01X1613397D02*
Y2160581D01*
G01X1610560Y2161368D02*
Y2160581D01*
G01X1610372D02*
Y2161368D01*
G01X1608598Y2160581D02*
Y2161368D01*
G01X1626590Y2205364D02*
G03X1626984Y2205758I0J394D01*
G01Y2203396D02*
G03X1626590Y2203789I-394J-1D01*
G01Y2225364D02*
G03X1626984Y2225758I0J394D01*
G01Y2223396D02*
G03X1626590Y2223789I-394J-1D01*
G01Y2215364D02*
G03X1626984Y2215758I0J394D01*
G01Y2213396D02*
G03X1626590Y2213789I-394J-1D01*
G01Y2220364D02*
G03X1626984Y2220758I0J394D01*
G01Y2218396D02*
G03X1626590Y2218789I-394J-1D01*
G01Y2175364D02*
G03X1626984Y2175758I0J394D01*
G01Y2173396D02*
G03X1626590Y2173789I-394J-1D01*
G01Y2165364D02*
G03X1626984Y2165758I0J394D01*
G01Y2163396D02*
G03X1626590Y2163789I-394J-1D01*
G01Y2185364D02*
G03X1626984Y2185758I0J394D01*
G01Y2183396D02*
G03X1626590Y2183789I-394J-1D01*
G01Y2190364D02*
G03X1626984Y2190758I0J394D01*
G01Y2188396D02*
G03X1626590Y2188789I-394J-1D01*
G01Y2200364D02*
G03X1626984Y2200758I0J394D01*
G01Y2198396D02*
G03X1626590Y2198789I-394J-1D01*
G01Y2195364D02*
G03X1626984Y2195758I0J394D01*
G01Y2193396D02*
G03X1626590Y2193789I-394J-1D01*
G01Y2180364D02*
G03X1626984Y2180758I0J394D01*
G01Y2178396D02*
G03X1626590Y2178789I-394J-1D01*
G01X1626984Y2229380D02*
X1636354D01*
G01X1658795Y2228789D02*
X1628087D01*
G01X1656827Y2228396D02*
X1638323D01*
G01X1636669Y2228199D02*
X1630134D01*
G01X1606827Y2227785D02*
X1626984D01*
G01Y2227608D02*
X1636354D01*
G01X1624543Y2226151D02*
X1623559D01*
G01X1622968Y2226033D02*
X1613984D01*
G01X1624543Y2225955D02*
X1623559D01*
G01X1624543Y2225561D02*
X1623559D01*
G01X1619425Y2225364D02*
X1626590D01*
G01X1615931Y2224360D02*
X1608598D01*
G01X1628087D02*
X1616078D01*
G01X1619425Y2223789D02*
X1626590D01*
G01X1624543Y2223592D02*
X1623559D01*
G01X1616078Y2223573D02*
X1628087D01*
G01X1608598D02*
X1615931D01*
G01X1624543Y2223199D02*
X1623559D01*
G01X1624543Y2223002D02*
X1623559D01*
G01X1615931Y2221211D02*
X1608598D01*
G01X1628087D02*
X1616078D01*
G01X1624543Y2221151D02*
X1623559D01*
G01X1624543Y2220955D02*
X1623559D01*
G01X1624543Y2220561D02*
X1623559D01*
G01X1616078Y2220423D02*
X1628087D01*
G01X1608598D02*
X1615931D01*
G01X1619425Y2220364D02*
X1626590D01*
G01X1619425Y2218789D02*
X1626590D01*
G01X1624543Y2218592D02*
X1623559D01*
G01X1624543Y2218199D02*
X1623559D01*
G01X1615931Y2218061D02*
X1608598D01*
G01X1628087D02*
X1616078D01*
G01X1624543Y2218002D02*
X1623559D01*
G01X1616078Y2217274D02*
X1628087D01*
G01X1608598D02*
X1615931D01*
G01X1624543Y2216151D02*
X1623559D01*
G01X1624543Y2215955D02*
X1623559D01*
G01X1624543Y2215561D02*
X1623559D01*
G01X1619425Y2215364D02*
X1626590D01*
G01X1615931Y2214911D02*
X1608598D01*
G01X1628087D02*
X1616078D01*
G01Y2214124D02*
X1628087D01*
G01X1608598D02*
X1615931D01*
G01X1619425Y2213789D02*
X1626590D01*
G01X1624543Y2213592D02*
X1623559D01*
G01X1624543Y2213199D02*
X1623559D01*
G01X1624543Y2213002D02*
X1623559D01*
G01X1628087Y2211781D02*
X1626984D01*
G01X1615931Y2211762D02*
X1608598D01*
G01X1628087D02*
X1616078D01*
G01X1626512Y2211151D02*
X1625527D01*
G01X1616078Y2210974D02*
X1628087D01*
G01X1608598D02*
X1615931D01*
G01X1626512Y2210955D02*
X1625527D01*
G01X1656827Y2210679D02*
X1630134D01*
G01X1626512Y2210561D02*
X1625527D01*
G01X1626984Y2210364D02*
X1621394D01*
G01X1626984Y2208789D02*
X1621394D01*
G01X1615931Y2208612D02*
X1608598D01*
G01X1628087D02*
X1616078D01*
G01X1626512Y2208592D02*
X1625527D01*
G01X1656827Y2208317D02*
X1630134D01*
G01X1626512Y2208199D02*
X1625527D01*
G01X1626512Y2208002D02*
X1625527D01*
G01X1616078Y2207825D02*
X1628087D01*
G01X1608598D02*
X1615931D01*
G01X1628087Y2207372D02*
X1626984D01*
G01X1624543Y2206151D02*
X1623559D01*
G01X1624543Y2205955D02*
X1623559D01*
G01X1624543Y2205561D02*
X1623559D01*
G01X1615931Y2205463D02*
X1608598D01*
G01X1628087D02*
X1616078D01*
G01X1619425Y2205364D02*
X1626590D01*
G01X1616078Y2204675D02*
X1628087D01*
G01X1608598D02*
X1615931D01*
G01X1619425Y2203789D02*
X1626590D01*
G01X1624543Y2203592D02*
X1623559D01*
G01X1624543Y2203199D02*
X1623559D01*
G01X1624543Y2203002D02*
X1623559D01*
G01X1615931Y2202313D02*
X1608598D01*
G01X1628087D02*
X1616078D01*
G01Y2201525D02*
X1628087D01*
G01X1608598D02*
X1615931D01*
G01X1624543Y2201151D02*
X1623559D01*
G01X1624543Y2200955D02*
X1623559D01*
G01X1624543Y2200561D02*
X1623559D01*
G01X1619425Y2200364D02*
X1626590D01*
G01X1615931Y2199163D02*
X1608598D01*
G01X1628087D02*
X1616078D01*
G01X1619425Y2198789D02*
X1626590D01*
G01X1624543Y2198592D02*
X1623559D01*
G01X1616078Y2198376D02*
X1628087D01*
G01X1608598D02*
X1615931D01*
G01X1624543Y2198199D02*
X1623559D01*
G01X1624543Y2198002D02*
X1623559D01*
G01X1624543Y2196151D02*
X1623559D01*
G01X1615931Y2196014D02*
X1608598D01*
G01X1628087D02*
X1616078D01*
G01X1624543Y2195955D02*
X1623559D01*
G01X1624543Y2195561D02*
X1623559D01*
G01X1619425Y2195364D02*
X1626590D01*
G01X1616078Y2195226D02*
X1628087D01*
G01X1608598D02*
X1615931D01*
G01X1619425Y2193789D02*
X1626590D01*
G01X1624543Y2193592D02*
X1623559D01*
G01X1624543Y2193199D02*
X1623559D01*
G01X1624543Y2193002D02*
X1623559D01*
G01X1615931Y2192864D02*
X1608598D01*
G01X1628087D02*
X1616078D01*
G01Y2192077D02*
X1628087D01*
G01X1608598D02*
X1615931D01*
G01X1656827Y2191781D02*
X1630134D01*
G01X1624543Y2191151D02*
X1623559D01*
G01X1624543Y2190955D02*
X1623559D01*
G01X1624543Y2190561D02*
X1623559D01*
G01X1619425Y2190364D02*
X1626590D01*
G01X1615931Y2189714D02*
X1608598D01*
G01X1628087D02*
X1616078D01*
G01X1656827Y2189419D02*
X1630134D01*
G01X1616078Y2188927D02*
X1628087D01*
G01X1608598D02*
X1615931D01*
G01X1619425Y2188789D02*
X1626590D01*
G01X1624543Y2188592D02*
X1623559D01*
G01X1624543Y2188199D02*
X1623559D01*
G01X1624543Y2188002D02*
X1623559D01*
G01X1615931Y2186565D02*
X1608598D01*
G01X1628087D02*
X1616078D01*
G01X1624543Y2186151D02*
X1623559D01*
G01X1624543Y2185955D02*
X1623559D01*
G01X1616078Y2185777D02*
X1628087D01*
G01X1608598D02*
X1615931D01*
G01X1624543Y2185561D02*
X1623559D01*
G01X1619425Y2185364D02*
X1626590D01*
G01X1619425Y2183789D02*
X1626590D01*
G01X1624543Y2183592D02*
X1623559D01*
G01X1615931Y2183415D02*
X1608598D01*
G01X1628087D02*
X1616078D01*
G01X1624543Y2183199D02*
X1623559D01*
G01X1624543Y2183002D02*
X1623559D01*
G01X1616078Y2182628D02*
X1628087D01*
G01X1608598D02*
X1615931D01*
G01X1624543Y2181151D02*
X1623559D01*
G01X1624543Y2180955D02*
X1623559D01*
G01X1624543Y2180561D02*
X1623559D01*
G01X1619425Y2180364D02*
X1626590D01*
G01X1615931Y2180266D02*
X1608598D01*
G01X1628087D02*
X1616078D01*
G01Y2179478D02*
X1628087D01*
G01X1608598D02*
X1615931D01*
G01X1619425Y2178789D02*
X1626590D01*
G01X1624543Y2178592D02*
X1623559D01*
G01X1624543Y2178199D02*
X1623559D01*
G01X1624543Y2178002D02*
X1623559D01*
G01X1615931Y2177116D02*
X1608598D01*
G01X1628087D02*
X1616078D01*
G01Y2176329D02*
X1628087D01*
G01X1608598D02*
X1615931D01*
G01X1624543Y2176151D02*
X1623559D01*
G01X1624543Y2175955D02*
X1623559D01*
G01X1624543Y2175561D02*
X1623559D01*
G01X1619425Y2175364D02*
X1626590D01*
G01X1615931Y2173966D02*
X1608598D01*
G01X1628087D02*
X1616078D01*
G01X1619425Y2173789D02*
X1626590D01*
G01X1624543Y2173592D02*
X1623559D01*
G01X1624543Y2173199D02*
X1623559D01*
G01X1616078Y2173179D02*
X1628087D01*
G01X1608598D02*
X1615931D01*
G01X1624543Y2173002D02*
X1623559D01*
G01X1656827Y2172884D02*
X1630134D01*
G01X1626984Y2171781D02*
X1628087D01*
G01X1626512Y2171151D02*
X1625527D01*
G01X1626512Y2170955D02*
X1625527D01*
G01X1615931Y2170817D02*
X1608598D01*
G01X1628087D02*
X1616078D01*
G01X1626512Y2170561D02*
X1625527D01*
G01X1656827Y2170522D02*
X1630134D01*
G01X1626984Y2170364D02*
X1621394D01*
G01X1616078Y2170029D02*
X1628087D01*
G01X1608598D02*
X1615931D01*
G01X1626984Y2168789D02*
X1621394D01*
G01X1626512Y2168592D02*
X1625527D01*
G01X1626512Y2168199D02*
X1625527D01*
G01X1626512Y2168002D02*
X1625527D01*
G01X1615931Y2167667D02*
X1608598D01*
G01X1628087D02*
X1616078D01*
G01X1628087Y2167372D02*
X1626984D01*
G01X1616078Y2166880D02*
X1628087D01*
G01X1608598D02*
X1615931D01*
G01X1624543Y2166151D02*
X1623559D01*
G01X1624543Y2165955D02*
X1623559D01*
G01X1624543Y2165561D02*
X1623559D01*
G01X1619425Y2165364D02*
X1626590D01*
G01X1615931Y2164518D02*
X1608598D01*
G01X1628087D02*
X1616078D01*
G01X1619425Y2163789D02*
X1626590D01*
G01X1616078Y2163730D02*
X1628087D01*
G01X1608598D02*
X1615931D01*
G01X1624543Y2163592D02*
X1623559D01*
G01X1624543Y2163199D02*
X1623559D01*
G01X1624543Y2163002D02*
X1623559D01*
G01X1636669Y2228199D02*
Y2254596D01*
G01X1636354Y2229380D02*
Y2227608D01*
G01X1632102Y2210679D02*
Y2228199D01*
G01Y2191781D02*
Y2208317D01*
G01Y2172884D02*
Y2189419D01*
G01X1626512Y2171151D02*
Y2168002D01*
G01Y2211151D02*
Y2208002D01*
G01X1626145Y2223573D02*
Y2224360D01*
G01Y2217274D02*
Y2218061D01*
G01Y2220423D02*
Y2221211D01*
G01Y2214124D02*
Y2214911D01*
G01Y2207825D02*
Y2208612D01*
G01Y2210974D02*
Y2211762D01*
G01Y2204675D02*
Y2205463D01*
G01Y2198376D02*
Y2199163D01*
G01Y2201525D02*
Y2202313D01*
G01Y2195226D02*
Y2196014D01*
G01Y2188927D02*
Y2189714D01*
G01Y2192077D02*
Y2192864D01*
G01Y2185777D02*
Y2186565D01*
G01Y2179478D02*
Y2180266D01*
G01Y2182628D02*
Y2183415D01*
G01Y2176329D02*
Y2177116D01*
G01Y2173179D02*
Y2173966D01*
G01Y2166880D02*
Y2167667D01*
G01Y2170029D02*
Y2170817D01*
G01Y2163730D02*
Y2164518D01*
G01X1626118Y2223573D02*
Y2224360D01*
G01Y2217274D02*
Y2218061D01*
G01Y2220423D02*
Y2221211D01*
G01Y2214124D02*
Y2214911D01*
G01Y2207825D02*
Y2208612D01*
G01Y2210974D02*
Y2211762D01*
G01Y2204675D02*
Y2205463D01*
G01Y2198376D02*
Y2199163D01*
G01Y2201525D02*
Y2202313D01*
G01Y2195226D02*
Y2196014D01*
G01Y2188927D02*
Y2189714D01*
G01Y2192077D02*
Y2192864D01*
G01Y2185777D02*
Y2186565D01*
G01Y2179478D02*
Y2180266D01*
G01Y2182628D02*
Y2183415D01*
G01Y2176329D02*
Y2177116D01*
G01Y2173179D02*
Y2173966D01*
G01Y2166880D02*
Y2167667D01*
G01Y2170029D02*
Y2170817D01*
G01Y2163730D02*
Y2164518D01*
G01X1625742Y2223573D02*
Y2224360D01*
G01Y2217274D02*
Y2218061D01*
G01Y2220423D02*
Y2221211D01*
G01Y2214124D02*
Y2214911D01*
G01Y2207825D02*
Y2208612D01*
G01Y2210974D02*
Y2211762D01*
G01Y2204675D02*
Y2205463D01*
G01Y2198376D02*
Y2199163D01*
G01Y2201525D02*
Y2202313D01*
G01Y2195226D02*
Y2196014D01*
G01Y2188927D02*
Y2189714D01*
G01Y2192077D02*
Y2192864D01*
G01Y2185777D02*
Y2186565D01*
G01Y2179478D02*
Y2180266D01*
G01Y2182628D02*
Y2183415D01*
G01Y2176329D02*
Y2177116D01*
G01Y2173179D02*
Y2173966D01*
G01Y2166880D02*
Y2167667D01*
G01Y2170029D02*
Y2170817D01*
G01Y2163730D02*
Y2164518D01*
G01X1625527Y2165364D02*
Y2163789D01*
G01Y2175364D02*
Y2173789D01*
G01Y2171151D02*
Y2168002D01*
G01Y2180364D02*
Y2178789D01*
G01Y2185364D02*
Y2183789D01*
G01Y2190364D02*
Y2188789D01*
G01Y2195364D02*
Y2193789D01*
G01Y2200364D02*
Y2198789D01*
G01Y2205364D02*
Y2203789D01*
G01Y2211151D02*
Y2208002D01*
G01Y2215364D02*
Y2213789D01*
G01Y2220364D02*
Y2218789D01*
G01Y2225364D02*
Y2223789D01*
G01X1624543Y2166151D02*
Y2163002D01*
G01Y2170364D02*
Y2168789D01*
G01Y2176151D02*
Y2173002D01*
G01Y2181151D02*
Y2178002D01*
G01Y2186151D02*
Y2183002D01*
G01Y2191151D02*
Y2188002D01*
G01Y2196151D02*
Y2193002D01*
G01Y2201151D02*
Y2198002D01*
G01Y2206151D02*
Y2203002D01*
G01Y2210364D02*
Y2208789D01*
G01Y2216151D02*
Y2213002D01*
G01Y2221151D02*
Y2218002D01*
G01Y2226151D02*
Y2223002D01*
G01X1623559Y2166151D02*
Y2163002D01*
G01Y2176151D02*
Y2173002D01*
G01Y2181151D02*
Y2178002D01*
G01Y2186151D02*
Y2183002D01*
G01Y2191151D02*
Y2188002D01*
G01Y2196151D02*
Y2193002D01*
G01Y2201151D02*
Y2198002D01*
G01Y2206151D02*
Y2203002D01*
G01Y2216151D02*
Y2213002D01*
G01Y2221151D02*
Y2218002D01*
G01Y2226151D02*
Y2223002D01*
G01X1622575Y2165364D02*
Y2163789D01*
G01Y2175364D02*
Y2173789D01*
G01Y2180364D02*
Y2178789D01*
G01Y2185364D02*
Y2183789D01*
G01Y2190364D02*
Y2188789D01*
G01Y2195364D02*
Y2193789D01*
G01Y2200364D02*
Y2198789D01*
G01Y2205364D02*
Y2203789D01*
G01Y2215364D02*
Y2213789D01*
G01Y2220364D02*
Y2218789D01*
G01Y2225364D02*
Y2223789D01*
G01X1622380Y2164518D02*
Y2163730D01*
G01Y2167667D02*
Y2166880D01*
G01Y2170817D02*
Y2170029D01*
G01Y2173966D02*
Y2173179D01*
G01Y2177116D02*
Y2176329D01*
G01Y2180266D02*
Y2179478D01*
G01Y2183415D02*
Y2182628D01*
G01Y2186565D02*
Y2185777D01*
G01Y2189714D02*
Y2188927D01*
G01Y2192864D02*
Y2192077D01*
G01Y2196014D02*
Y2195226D01*
G01Y2199163D02*
Y2198376D01*
G01Y2202313D02*
Y2201525D01*
G01Y2205463D02*
Y2204675D01*
G01Y2208612D02*
Y2207825D01*
G01Y2211762D02*
Y2210974D01*
G01Y2214911D02*
Y2214124D01*
G01Y2218061D02*
Y2217274D01*
G01Y2221211D02*
Y2220423D01*
G01Y2224360D02*
Y2223573D01*
G01X1621394Y2170364D02*
Y2168789D01*
G01Y2210364D02*
Y2208789D01*
G01X1620396Y2164518D02*
Y2163730D01*
G01Y2167667D02*
Y2166880D01*
G01Y2170817D02*
Y2170029D01*
G01Y2173966D02*
Y2173179D01*
G01Y2177116D02*
Y2176329D01*
G01Y2180266D02*
Y2179478D01*
G01Y2183415D02*
Y2182628D01*
G01Y2186565D02*
Y2185777D01*
G01Y2189714D02*
Y2188927D01*
G01Y2192864D02*
Y2192077D01*
G01Y2196014D02*
Y2195226D01*
G01Y2199163D02*
Y2198376D01*
G01Y2202313D02*
Y2201525D01*
G01Y2205463D02*
Y2204675D01*
G01Y2208612D02*
Y2207825D01*
G01Y2211762D02*
Y2210974D01*
G01Y2214911D02*
Y2214124D01*
G01Y2218061D02*
Y2217274D01*
G01Y2221211D02*
Y2220423D01*
G01Y2224360D02*
Y2223573D01*
G01X1619425Y2165364D02*
Y2163789D01*
G01Y2175364D02*
Y2173789D01*
G01Y2180364D02*
Y2178789D01*
G01Y2185364D02*
Y2183789D01*
G01Y2190364D02*
Y2188789D01*
G01Y2195364D02*
Y2193789D01*
G01Y2200364D02*
Y2198789D01*
G01Y2205364D02*
Y2203789D01*
G01Y2215364D02*
Y2213789D01*
G01Y2220364D02*
Y2218789D01*
G01Y2225364D02*
Y2223789D01*
G01X1618745Y2223573D02*
Y2224360D01*
G01Y2217274D02*
Y2218061D01*
G01Y2220423D02*
Y2221211D01*
G01Y2214124D02*
Y2214911D01*
G01Y2207825D02*
Y2208612D01*
G01Y2210974D02*
Y2211762D01*
G01Y2204675D02*
Y2205463D01*
G01Y2198376D02*
Y2199163D01*
G01Y2201525D02*
Y2202313D01*
G01Y2195226D02*
Y2196014D01*
G01Y2188927D02*
Y2189714D01*
G01Y2192077D02*
Y2192864D01*
G01Y2185777D02*
Y2186565D01*
G01Y2179478D02*
Y2180266D01*
G01Y2182628D02*
Y2183415D01*
G01Y2176329D02*
Y2177116D01*
G01Y2173179D02*
Y2173966D01*
G01Y2166880D02*
Y2167667D01*
G01Y2170029D02*
Y2170817D01*
G01Y2163730D02*
Y2164518D01*
G01X1617016Y2166880D02*
Y2164518D01*
G01Y2170029D02*
Y2167667D01*
G01Y2173179D02*
Y2170817D01*
G01Y2176329D02*
Y2173966D01*
G01Y2179478D02*
Y2177116D01*
G01Y2182628D02*
Y2180266D01*
G01Y2185777D02*
Y2183415D01*
G01Y2188927D02*
Y2186565D01*
G01Y2192077D02*
Y2189714D01*
G01Y2195226D02*
Y2192864D01*
G01Y2198376D02*
Y2196014D01*
G01Y2201525D02*
Y2199163D01*
G01Y2204675D02*
Y2202313D01*
G01Y2207825D02*
Y2205463D01*
G01Y2210974D02*
Y2208612D01*
G01Y2214124D02*
Y2211762D01*
G01Y2217274D02*
Y2214911D01*
G01Y2220423D02*
Y2218061D01*
G01Y2223573D02*
Y2221211D01*
G01Y2226033D02*
Y2224360D01*
G01X1616078Y2223573D02*
Y2224360D01*
G01Y2217274D02*
Y2218061D01*
G01Y2220423D02*
Y2221211D01*
G01Y2214124D02*
Y2214911D01*
G01Y2207825D02*
Y2208612D01*
G01Y2210974D02*
Y2211762D01*
G01Y2204675D02*
Y2205463D01*
G01Y2198376D02*
Y2199163D01*
G01Y2201525D02*
Y2202313D01*
G01Y2195226D02*
Y2196014D01*
G01Y2188927D02*
Y2189714D01*
G01Y2192077D02*
Y2192864D01*
G01Y2185777D02*
Y2186565D01*
G01Y2179478D02*
Y2180266D01*
G01Y2182628D02*
Y2183415D01*
G01Y2176329D02*
Y2177116D01*
G01Y2173179D02*
Y2173966D01*
G01Y2166880D02*
Y2167667D01*
G01Y2170029D02*
Y2170817D01*
G01Y2163730D02*
Y2164518D01*
G01X1615931Y2223573D02*
Y2224360D01*
G01Y2217274D02*
Y2218061D01*
G01Y2220423D02*
Y2221211D01*
G01Y2214124D02*
Y2214911D01*
G01Y2207825D02*
Y2208612D01*
G01Y2210974D02*
Y2211762D01*
G01Y2204675D02*
Y2205463D01*
G01Y2198376D02*
Y2199163D01*
G01Y2201525D02*
Y2202313D01*
G01Y2195226D02*
Y2196014D01*
G01Y2188927D02*
Y2189714D01*
G01Y2192077D02*
Y2192864D01*
G01Y2185777D02*
Y2186565D01*
G01Y2179478D02*
Y2180266D01*
G01Y2182628D02*
Y2183415D01*
G01Y2176329D02*
Y2177116D01*
G01Y2173179D02*
Y2173966D01*
G01Y2166880D02*
Y2167667D01*
G01Y2170029D02*
Y2170817D01*
G01Y2163730D02*
Y2164518D01*
G01X1614338Y2223573D02*
Y2224360D01*
G01Y2217274D02*
Y2218061D01*
G01Y2220423D02*
Y2221211D01*
G01Y2214124D02*
Y2214911D01*
G01Y2207825D02*
Y2208612D01*
G01Y2210974D02*
Y2211762D01*
G01Y2204675D02*
Y2205463D01*
G01Y2198376D02*
Y2199163D01*
G01Y2201525D02*
Y2202313D01*
G01Y2195226D02*
Y2196014D01*
G01Y2188927D02*
Y2189714D01*
G01Y2192077D02*
Y2192864D01*
G01Y2185777D02*
Y2186565D01*
G01Y2179478D02*
Y2180266D01*
G01Y2182628D02*
Y2183415D01*
G01Y2176329D02*
Y2177116D01*
G01Y2173179D02*
Y2173966D01*
G01Y2166880D02*
Y2167667D01*
G01Y2170029D02*
Y2170817D01*
G01Y2163730D02*
Y2164518D01*
G01X1613397D02*
Y2163730D01*
G01Y2167667D02*
Y2166880D01*
G01Y2170817D02*
Y2170029D01*
G01Y2173966D02*
Y2173179D01*
G01Y2177116D02*
Y2176329D01*
G01Y2180266D02*
Y2179478D01*
G01Y2183415D02*
Y2182628D01*
G01Y2186565D02*
Y2185777D01*
G01Y2189714D02*
Y2188927D01*
G01Y2192864D02*
Y2192077D01*
G01Y2196014D02*
Y2195226D01*
G01Y2199163D02*
Y2198376D01*
G01Y2202313D02*
Y2201525D01*
G01Y2205463D02*
Y2204675D01*
G01Y2208612D02*
Y2207825D01*
G01Y2211762D02*
Y2210974D01*
G01Y2214911D02*
Y2214124D01*
G01Y2218061D02*
Y2217274D01*
G01Y2221211D02*
Y2220423D01*
G01Y2224360D02*
Y2223573D01*
G01X1610560Y2164518D02*
Y2163730D01*
G01Y2167667D02*
Y2166880D01*
G01Y2170817D02*
Y2170029D01*
G01Y2173966D02*
Y2173179D01*
G01Y2177116D02*
Y2176329D01*
G01Y2180266D02*
Y2179478D01*
G01Y2183415D02*
Y2182628D01*
G01Y2186565D02*
Y2185777D01*
G01Y2189714D02*
Y2188927D01*
G01Y2192864D02*
Y2192077D01*
G01Y2196014D02*
Y2195226D01*
G01Y2199163D02*
Y2198376D01*
G01Y2202313D02*
Y2201525D01*
G01Y2205463D02*
Y2204675D01*
G01Y2208612D02*
Y2207825D01*
G01Y2211762D02*
Y2210974D01*
G01Y2214911D02*
Y2214124D01*
G01Y2218061D02*
Y2217274D01*
G01Y2221211D02*
Y2220423D01*
G01Y2224360D02*
Y2223573D01*
G01X1610372D02*
Y2224360D01*
G01Y2217274D02*
Y2218061D01*
G01Y2220423D02*
Y2221211D01*
G01Y2214124D02*
Y2214911D01*
G01Y2207825D02*
Y2208612D01*
G01Y2210974D02*
Y2211762D01*
G01Y2204675D02*
Y2205463D01*
G01Y2198376D02*
Y2199163D01*
G01Y2201525D02*
Y2202313D01*
G01Y2195226D02*
Y2196014D01*
G01Y2188927D02*
Y2189714D01*
G01Y2192077D02*
Y2192864D01*
G01Y2185777D02*
Y2186565D01*
G01Y2179478D02*
Y2180266D01*
G01Y2182628D02*
Y2183415D01*
G01Y2176329D02*
Y2177116D01*
G01Y2173179D02*
Y2173966D01*
G01Y2166880D02*
Y2167667D01*
G01Y2170029D02*
Y2170817D01*
G01Y2163730D02*
Y2164518D01*
G01X1608598Y2223573D02*
Y2224360D01*
G01Y2217274D02*
Y2218061D01*
G01Y2220423D02*
Y2221211D01*
G01Y2214124D02*
Y2214911D01*
G01Y2207825D02*
Y2208612D01*
G01Y2210974D02*
Y2211762D01*
G01Y2204675D02*
Y2205463D01*
G01Y2198376D02*
Y2199163D01*
G01Y2201525D02*
Y2202313D01*
G01Y2195226D02*
Y2196014D01*
G01Y2188927D02*
Y2189714D01*
G01Y2192077D02*
Y2192864D01*
G01Y2185777D02*
Y2186565D01*
G01Y2179478D02*
Y2180266D01*
G01Y2182628D02*
Y2183415D01*
G01Y2176329D02*
Y2177116D01*
G01Y2173179D02*
Y2173966D01*
G01Y2166880D02*
Y2167667D01*
G01Y2170029D02*
Y2170817D01*
G01Y2163730D02*
Y2164518D01*
G01X1607619Y2230561D02*
Y2227785D01*
G01X1607144Y2233317D02*
Y2227785D01*
G01X1606827Y2241663D02*
Y2227785D01*
G01X1617274Y2239596D02*
G03Y2234163I1954J-2717D01*
G01X1621183D02*
G03Y2239596I-1955J2716D01*
G01X1622732Y2236880D02*
G03I-3504J0D01*
G01X1621532Y2232982D02*
G03Y2240777I-2304J3897D01*
G01X1616925D02*
G03Y2232982I2303J-3898D01*
G01X1621183Y2234163D02*
X1617274D01*
G01X1630449Y2233947D02*
X1606827D01*
G01X1656827Y2233317D02*
X1606827D01*
G01X1616925Y2232982D02*
X1621532D01*
G01X1606827Y2231545D02*
X1630449D01*
G01X1621987Y2231014D02*
X1628087D01*
G01X1621987Y2230955D02*
X1628087D01*
G01X1607619Y2230561D02*
X1628087D01*
G01X1621183Y2234163D02*
X1621200Y2234107D01*
X1621253Y2233942D01*
X1621332Y2233683D01*
X1621427Y2233356D01*
X1621532Y2232982D01*
G01X1634386Y2241663D02*
Y2233317D01*
G01X1630449Y2233947D02*
Y2231545D01*
G01X1624543Y2233317D02*
Y2231014D01*
G01X1621987D02*
Y2230955D01*
G01X1621348Y2230561D02*
Y2233317D01*
G01X1613474Y2230561D02*
Y2233317D01*
G01X1617274Y2234163D02*
X1617256Y2234107D01*
X1617204Y2233942D01*
X1617125Y2233684D01*
X1617029Y2233357D01*
X1616925Y2232982D01*
G01X1621987Y2230955D02*
X1621731Y2230561D01*
G01X1629774Y2237737D02*
G03X1631205I716J0D01*
G01X1626884D02*
G03X1628315I716J0D01*
G01X1630646Y2247116D02*
G03Y2250266I0J1575D01*
G01X1625786Y2236661D02*
G03X1628421Y2236806I1247J1352D01*
G01D02*
G03X1631202Y2236811I1388J1207D01*
G01X1625492Y2237332D02*
G03X1625786Y2236661I913J0D01*
G01X1626315Y2250266D02*
G03Y2247116I0J-1575D01*
G01X1621812Y2239152D02*
G03Y2237468I2237J-842D01*
G01X1623285Y2239153D02*
G03X1621812I-736J-278D01*
G01Y2237468D02*
G03X1623285I737J277D01*
G01X1624558Y2239487D02*
G03X1624036Y2240053I-1352J-723D01*
G01X1620990Y2240051D02*
G03X1620470Y2239486I832J-1287D01*
G01Y2237173D02*
G03X1620991Y2236608I1351J724D01*
G01X1624038Y2236609D02*
G03X1624558Y2237174I-832J1287D01*
G01X1623285Y2237468D02*
G03Y2239152I-2236J842D01*
G01X1624558Y2237174D02*
G03Y2239487I-2162J1156D01*
G01X1620470Y2239486D02*
G03Y2237173I2163J-1157D01*
G01X1624037Y2240053D02*
G03X1620990Y2240051I-1522J-2363D01*
G01X1620991Y2236608D02*
G03X1624038I1524J2362D01*
G01X1621394Y2236880D02*
G03I-2166J0D01*
G01X1615312Y2239470D02*
G03X1614721Y2239105I-10J-645D01*
G01X1616085Y2238662D02*
G03X1615312Y2239470I-791J17D01*
G01X1614060Y2240175D02*
G03X1613217Y2239106I704J-1422D01*
G01X1613426Y2237219D02*
G03X1614660Y2236246I1735J931D01*
G01X1616303Y2236290D02*
G03X1617467Y2237428I-730J1910D01*
G01X1617381Y2239444D02*
G03X1615642Y2240461I-1806J-1094D01*
G01X1614660Y2236246D02*
G03X1616303Y2236290I756J2475D01*
G01X1617641Y2238584D02*
G03X1617380Y2239447I-2971J-428D01*
G01X1613087Y2238662D02*
G03X1613426Y2237219I3015J-53D01*
G01X1617641Y2238089D02*
G03Y2238586I-3524J249D01*
G01X1617468Y2237428D02*
G03X1617641Y2238089I-4020J1405D01*
G01X1614660Y2237837D02*
G03X1616085I713J-83D01*
G01X1615646Y2240461D02*
G03X1614060Y2240175I-265J-3073D01*
G01X1636669Y2254596D02*
X1620291D01*
G01X1626315Y2250266D02*
X1630646D01*
G01X1625689Y2249478D02*
X1631271D01*
G01Y2247903D02*
X1625689D01*
G01X1630646Y2247116D02*
X1626315D01*
G01X1636669Y2244419D02*
X1620291D01*
G01X1606827Y2241663D02*
X1660764D01*
G01X1621532Y2240777D02*
X1616925D01*
G01X1660764Y2240482D02*
X1634386D01*
G01X1610117Y2240262D02*
X1608567D01*
G01X1613061D02*
X1611653D01*
G01X1619693D02*
X1618232D01*
G01X1629774D02*
X1628315D01*
G01X1626884D02*
X1625492D01*
G01X1632645D02*
X1631205D01*
G01X1630449Y2239695D02*
X1606827D01*
G01X1617274Y2239596D02*
X1621183D01*
G01X1614721Y2239106D02*
X1613217D01*
G01X1616087Y2238662D02*
X1613087D01*
G01X1616086Y2237837D02*
X1614660D01*
G01X1609975Y2236255D02*
X1608593D01*
G01X1612887D02*
X1611270D01*
G01X1632645D02*
X1631202D01*
G01X1630449Y2235915D02*
X1606827D01*
G01X1619693Y2234508D02*
X1618232D01*
G01X1611618Y2238115D02*
X1612887Y2236255D01*
G01X1610117Y2240262D02*
X1610862Y2238984D01*
G01X1608567Y2240262D02*
X1609888Y2238106D01*
G01X1610665Y2237241D02*
X1611270Y2236255D01*
G01X1617274Y2239596D02*
X1617256Y2239652D01*
X1617204Y2239818D01*
X1617125Y2240076D01*
X1617029Y2240404D01*
X1616925Y2240777D01*
G01X1632645Y2240262D02*
Y2236255D01*
G01X1631271Y2247903D02*
Y2249478D01*
G01X1631236D02*
Y2247903D01*
G01X1631212Y2249478D02*
Y2247903D01*
G01X1631205Y2237737D02*
Y2240262D01*
G01X1631202Y2236811D02*
Y2236255D01*
G01X1630449Y2239695D02*
Y2235915D01*
G01X1629889Y2247903D02*
Y2249478D01*
G01X1629774Y2240262D02*
Y2237737D01*
G01X1629519Y2249478D02*
Y2247903D01*
G01X1628315Y2237737D02*
Y2240262D01*
G01X1627442Y2247903D02*
Y2249478D01*
G01X1627072D02*
Y2247903D01*
G01X1626884Y2240262D02*
Y2237737D01*
G01X1625748Y2247903D02*
Y2249478D01*
G01X1625724Y2247903D02*
Y2249478D01*
G01X1625689D02*
Y2247903D01*
G01X1625492Y2240262D02*
Y2237332D01*
G01X1620291Y2254596D02*
Y2241663D01*
G01X1619693Y2240262D02*
Y2234508D01*
G01X1618232Y2240262D02*
Y2234508D01*
G01X1621532Y2240777D02*
X1621429Y2240408D01*
X1621332Y2240079D01*
X1621252Y2239817D01*
X1621200Y2239651D01*
X1621183Y2239596D01*
G01X1611653Y2240262D02*
X1610862Y2238984D01*
G01X1609888Y2238106D02*
X1608593Y2236255D01*
G01X1610665Y2237241D02*
X1609975Y2236255D01*
G01X1613061Y2240262D02*
X1611618Y2238115D01*
G01X1600921Y2260502D02*
Y2300777D01*
G01X1598034Y2310467D02*
X1598756Y2309493D01*
Y2308519D01*
X1598034Y2307544D01*
X1597312Y2307057D01*
G01X1595869Y2311442D02*
X1596590D01*
X1598034Y2310467D01*
G01X1595869Y2314852D02*
X1594425Y2315339D01*
X1593703Y2316801D01*
X1594425Y2318263D01*
X1595869Y2318750D01*
X1597312Y2318263D01*
X1598034Y2317776D01*
X1598756Y2316801D01*
X1598034Y2315827D01*
X1597312Y2315339D01*
X1595869Y2314852D01*
X1592982D01*
X1591538Y2315339D01*
X1590816Y2315827D01*
X1590094Y2316801D01*
X1590816Y2317776D01*
X1591538Y2318263D01*
G01X1590816Y2307544D02*
X1590094Y2308519D01*
Y2309493D01*
X1590816Y2310467D01*
X1591538Y2310955D01*
X1592260D01*
X1592982Y2310467D01*
X1593703Y2309493D01*
X1594425Y2310467D01*
X1595869Y2311442D01*
G01X1598756Y2324596D02*
Y2324109D01*
X1598034D01*
X1598756Y2324596D01*
G01X1593703Y2308519D02*
Y2309493D01*
G01X1590094Y2334340D02*
Y2331417D01*
X1593703Y2330930D01*
X1592982Y2331904D01*
Y2332879D01*
X1593703Y2333853D01*
X1594425Y2334340D01*
X1595869Y2334828D01*
X1597312Y2334340D01*
X1598034Y2333853D01*
X1598756Y2332879D01*
Y2331904D01*
X1598034Y2330930D01*
X1597312Y2330443D01*
G01X1598756Y2340187D02*
X1598034Y2339213D01*
X1597312Y2338725D01*
X1595869Y2338238D01*
X1592982D01*
X1591538Y2338725D01*
X1590816Y2339213D01*
X1590094Y2340187D01*
X1590816Y2341161D01*
X1591538Y2341649D01*
X1592982Y2342136D01*
X1595869D01*
X1597312Y2341649D01*
X1598034Y2341161D01*
X1598756Y2340187D01*
G01X1668151Y293494D02*
Y302155D01*
X1664741Y295659D01*
X1669126D01*
G01X1690076Y293494D02*
X1689101Y294216D01*
X1688614Y294938D01*
X1688127Y296381D01*
Y299268D01*
X1688614Y300712D01*
X1689101Y301434D01*
X1690076Y302155D01*
X1691050Y301434D01*
X1691537Y300712D01*
X1692024Y299268D01*
Y296381D01*
X1691537Y294938D01*
X1691050Y294216D01*
X1690076Y293494D01*
G01X1684229Y302155D02*
X1681306D01*
X1680819Y298547D01*
X1681793Y299268D01*
X1682768D01*
X1683742Y298547D01*
X1684229Y297825D01*
X1684716Y296381D01*
X1684229Y294938D01*
X1683742Y294216D01*
X1682768Y293494D01*
X1681793D01*
X1680819Y294216D01*
X1680331Y294938D01*
G01X1674485Y293494D02*
X1673998D01*
Y294216D01*
X1674485Y293494D01*
G01X1648786Y483317D02*
X1648359Y482726D01*
G01X1654531Y481742D02*
X1654670Y481938D01*
X1654808Y482135D01*
X1654945Y482333D01*
G01X1649203Y482726D02*
X1649476Y483317D01*
G01X1650328Y482726D02*
X1650405Y483317D01*
G01X1649887Y482431D02*
X1649897Y482529D01*
X1649925Y482601D01*
X1649964Y482628D01*
G01X1658795Y468789D02*
Y611270D01*
G01X1657673Y606742D02*
Y473317D01*
G01X1657614Y503927D02*
Y472923D01*
G01X1656827Y473711D02*
Y606348D01*
G01X1654945Y482726D02*
Y482333D01*
G01X1654809Y482037D02*
Y482431D01*
G01X1650328Y482726D02*
Y482333D01*
G01X1649887Y482037D02*
Y482431D01*
G01X1649374D02*
Y482037D01*
G01X1649203Y482333D02*
Y482726D01*
G01X1648359Y482333D02*
Y482726D01*
G01X1648197Y482431D02*
Y482037D01*
G01X1649374D02*
X1649377Y481999D01*
X1649385Y481962D01*
X1649397Y481928D01*
X1649415Y481898D01*
X1649436Y481874D01*
X1649459Y481856D01*
X1649485Y481844D01*
X1649513Y481840D01*
G01X1650328Y482333D02*
X1650405Y481742D01*
G01X1654809Y482431D02*
X1654777Y482528D01*
X1654689Y482600D01*
X1654561Y482628D01*
G01X1649476Y481742D02*
X1649203Y482333D01*
G01X1654945Y482726D02*
X1654808Y482924D01*
X1654670Y483121D01*
X1654531Y483317D01*
G01X1648786Y481742D02*
X1648359Y482333D01*
G01X1649513Y482628D02*
X1649486Y482624D01*
X1649460Y482613D01*
X1649436Y482595D01*
X1649415Y482570D01*
X1649397Y482541D01*
X1649385Y482507D01*
X1649377Y482470D01*
X1649374Y482431D01*
G01X1654561Y481840D02*
X1654689Y481868D01*
X1654777Y481941D01*
X1654809Y482037D01*
G01X1649964Y481840D02*
X1649925Y481867D01*
X1649897Y481939D01*
X1649887Y482037D01*
G01X1654531Y483317D02*
X1648786D01*
G01X1648359Y482726D02*
X1654945D01*
G01X1654561Y482628D02*
X1648477D01*
G01X1648197Y482431D02*
X1654809D01*
G01X1648359Y482333D02*
X1654945D01*
G01X1654809Y482037D02*
X1648197D01*
G01X1654561Y481840D02*
X1648477D01*
G01X1654531Y481742D02*
X1648786D01*
G01X1649964Y479478D02*
X1649925Y479452D01*
X1649897Y479380D01*
X1649887Y479281D01*
G01X1658795Y470758D02*
X1656827Y468789D01*
G01X1648786Y478317D02*
X1648359Y477726D01*
G01X1654531Y476742D02*
X1654670Y476938D01*
X1654808Y477135D01*
X1654945Y477333D01*
G01X1649203Y477726D02*
X1649476Y478317D01*
G01X1650328Y477726D02*
X1650405Y478317D01*
G01X1654945Y477726D02*
Y477333D01*
G01X1654809Y478888D02*
Y479281D01*
G01X1650328Y477726D02*
Y477333D01*
G01X1649887Y478888D02*
Y479281D01*
G01X1649374D02*
Y478888D01*
G01X1649203Y477333D02*
Y477726D01*
G01X1648359Y477333D02*
Y477726D01*
G01X1648197Y479281D02*
Y478888D01*
G01X1649374D02*
X1649377Y478849D01*
X1649385Y478813D01*
X1649397Y478779D01*
X1649415Y478749D01*
X1649436Y478724D01*
X1649459Y478706D01*
X1649485Y478695D01*
X1649513Y478691D01*
G01X1650328Y477333D02*
X1650405Y476742D01*
G01X1654809Y479281D02*
X1654777Y479378D01*
X1654689Y479451D01*
X1654561Y479478D01*
G01X1649476Y476742D02*
X1649203Y477333D01*
G01X1654945Y477726D02*
X1654808Y477924D01*
X1654670Y478121D01*
X1654531Y478317D01*
G01X1648786Y476742D02*
X1648359Y477333D01*
G01X1649513Y479478D02*
X1649486Y479475D01*
X1649460Y479463D01*
X1649436Y479445D01*
X1649415Y479421D01*
X1649397Y479391D01*
X1649385Y479357D01*
X1649377Y479320D01*
X1649374Y479281D01*
G01X1654561Y478691D02*
X1654689Y478719D01*
X1654777Y478791D01*
X1654809Y478888D01*
G01X1658795Y471742D02*
X1656827Y473711D01*
G01X1649964Y478691D02*
X1649925Y478717D01*
X1649897Y478789D01*
X1649887Y478888D01*
G01X1654561Y479478D02*
X1648477D01*
G01X1648197Y479281D02*
X1654809D01*
G01Y478888D02*
X1648197D01*
G01X1654561Y478691D02*
X1648477D01*
G01X1654531Y478317D02*
X1648786D01*
G01X1648359Y477726D02*
X1654945D01*
G01X1648359Y477333D02*
X1654945D01*
G01X1654531Y476742D02*
X1648786D01*
G01X1662079Y468789D02*
X1658795D01*
G01X1665488Y465088D02*
X1660764Y460443D01*
G01X1665488Y466192D02*
X1660768Y461550D01*
G01X1682425Y447372D02*
X1681451Y445928D01*
X1680963Y443763D01*
X1684861D01*
G01X1680963Y450981D02*
X1681451Y451702D01*
X1682425Y452424D01*
X1683399D01*
X1684374Y451702D01*
X1684861Y450981D01*
Y449537D01*
X1684374Y448815D01*
X1682425Y447372D01*
G01X1660795Y460474D02*
X1660852Y460609D01*
X1660858Y460844D01*
X1660822Y461173D01*
G01X1660795Y460474D02*
X1660853Y460614D01*
X1660858Y460854D01*
G01X1707272Y449537D02*
X1708247Y452424D01*
X1704349D01*
G01X1696554Y446650D02*
X1697041Y448093D01*
X1698503Y448815D01*
X1699964Y448093D01*
X1700452Y446650D01*
X1699964Y445206D01*
X1699477Y444485D01*
X1698503Y443763D01*
X1697528Y444485D01*
X1697041Y445206D01*
X1696554Y446650D01*
Y449537D01*
X1697041Y450981D01*
X1697528Y451702D01*
X1698503Y452424D01*
X1699477Y451702D01*
X1699964Y450981D01*
G01X1706298Y443763D02*
X1706785Y447372D01*
X1707272Y449537D01*
G01X1676579Y443763D02*
Y452424D01*
X1673168Y445928D01*
X1677553D01*
G01X1665488Y466821D02*
Y465088D01*
G01X1660764Y461624D02*
Y468789D01*
G01X1660823Y461165D02*
X1660768Y461550D01*
G01X1690707Y443763D02*
X1690220D01*
Y444485D01*
X1690707Y443763D01*
G01X1662079Y468789D02*
X1665488Y466821D01*
G01X1654809Y485187D02*
Y485581D01*
G01X1649887Y485187D02*
Y485581D01*
G01X1649374D02*
Y485187D01*
G01X1648197Y485581D02*
Y485187D01*
G01X1649374D02*
X1649377Y485149D01*
X1649385Y485112D01*
X1649397Y485078D01*
X1649415Y485048D01*
X1649436Y485023D01*
X1649459Y485005D01*
X1649485Y484994D01*
X1649513Y484990D01*
G01X1654561D02*
X1654689Y485018D01*
X1654777Y485091D01*
X1654809Y485187D01*
G01X1649964Y484990D02*
X1649925Y485016D01*
X1649897Y485089D01*
X1649887Y485187D01*
G01X1654809D02*
X1648197D01*
G01X1654561Y484990D02*
X1648477D01*
G01X1649964Y488927D02*
X1649925Y488901D01*
X1649897Y488829D01*
X1649887Y488730D01*
G01X1649964Y492077D02*
X1649925Y492050D01*
X1649897Y491978D01*
X1649887Y491880D01*
G01X1649964Y495226D02*
X1649925Y495200D01*
X1649897Y495128D01*
X1649887Y495029D01*
G01X1649964Y504675D02*
X1649925Y504649D01*
X1649897Y504577D01*
X1649887Y504478D01*
G01X1649964Y507825D02*
X1649925Y507798D01*
X1649897Y507726D01*
X1649887Y507628D01*
G01X1649964Y523573D02*
X1649925Y523546D01*
X1649897Y523474D01*
X1649887Y523376D01*
G01X1658795Y531762D02*
X1656827Y529793D01*
G01X1648786Y488317D02*
X1648359Y487726D01*
G01X1648786Y493317D02*
X1648359Y492726D01*
G01X1648786Y498317D02*
X1648359Y497726D01*
G01X1648786Y503317D02*
X1648359Y502726D01*
G01X1648786Y538317D02*
X1648359Y537726D01*
G01X1648718Y508317D02*
X1648294Y507726D01*
G01X1648718Y533317D02*
X1648294Y532726D01*
G01X1654531Y486742D02*
X1654670Y486938D01*
X1654808Y487135D01*
X1654945Y487333D01*
G01X1654531Y491742D02*
X1654670Y491938D01*
X1654808Y492135D01*
X1654945Y492333D01*
G01X1654531Y496742D02*
X1654670Y496938D01*
X1654808Y497135D01*
X1654945Y497333D01*
G01X1654531Y501742D02*
X1654670Y501938D01*
X1654808Y502135D01*
X1654945Y502333D01*
G01X1654531Y536742D02*
X1654670Y536938D01*
X1654808Y537135D01*
X1654945Y537333D01*
G01X1654631Y506742D02*
X1654767Y506938D01*
X1654902Y507135D01*
X1655036Y507333D01*
G01X1648786Y543317D02*
X1648359Y542726D01*
G01X1650754Y548317D02*
X1650328Y547726D01*
G01X1648786Y553317D02*
X1648359Y552726D01*
G01X1654531Y541742D02*
X1654670Y541938D01*
X1654808Y542135D01*
X1654945Y542333D01*
G01X1656500Y546742D02*
X1656639Y546938D01*
X1656777Y547135D01*
X1656914Y547333D01*
G01X1654531Y551742D02*
X1654670Y551938D01*
X1654808Y552135D01*
X1654945Y552333D01*
G01X1654531Y556742D02*
X1654670Y556938D01*
X1654808Y557135D01*
X1654945Y557333D01*
G01X1654631Y531742D02*
X1654767Y531938D01*
X1654902Y532135D01*
X1655036Y532333D01*
G01X1649203Y487726D02*
X1649476Y488317D01*
G01X1649203Y492726D02*
X1649476Y493317D01*
G01X1649203Y497726D02*
X1649476Y498317D01*
G01X1649203Y502726D02*
X1649476Y503317D01*
G01X1649203Y507726D02*
X1649476Y508317D01*
G01X1649203Y532726D02*
X1649476Y533317D01*
G01X1649203Y537726D02*
X1649476Y538317D01*
G01X1649203Y542726D02*
X1649476Y543317D01*
G01X1651172Y547726D02*
X1651444Y548317D01*
G01X1649203Y552726D02*
X1649476Y553317D01*
G01X1650328Y487726D02*
X1650405Y488317D01*
G01X1650328Y492726D02*
X1650405Y493317D01*
G01X1650328Y497726D02*
X1650405Y498317D01*
G01X1650328Y502726D02*
X1650405Y503317D01*
G01X1650328Y507726D02*
X1650405Y508317D01*
G01X1650328Y532726D02*
X1650405Y533317D01*
G01X1652296Y547726D02*
X1652374Y548317D01*
G01X1650328Y537726D02*
X1650405Y538317D01*
G01X1650328Y542726D02*
X1650405Y543317D01*
G01X1650328Y552726D02*
X1650405Y553317D01*
G01X1649887Y485581D02*
X1649897Y485679D01*
X1649925Y485751D01*
X1649964Y485777D01*
G01X1649887Y498179D02*
X1649897Y498277D01*
X1649925Y498349D01*
X1649964Y498376D01*
G01X1649887Y501329D02*
X1649897Y501427D01*
X1649925Y501499D01*
X1649964Y501525D01*
G01X1649887Y510777D02*
X1649897Y510876D01*
X1649925Y510948D01*
X1649964Y510974D01*
G01X1649887Y513927D02*
X1649897Y514025D01*
X1649925Y514097D01*
X1649964Y514124D01*
G01X1649887Y517077D02*
X1649897Y517175D01*
X1649925Y517247D01*
X1649964Y517274D01*
G01X1649887Y520226D02*
X1649897Y520325D01*
X1649925Y520397D01*
X1649964Y520423D01*
G01X1649887Y526525D02*
X1649897Y526624D01*
X1649925Y526696D01*
X1649964Y526722D01*
G01X1649887Y529675D02*
X1649897Y529773D01*
X1649925Y529846D01*
X1649964Y529872D01*
G01X1649887Y532825D02*
X1649897Y532923D01*
X1649925Y532995D01*
X1649964Y533022D01*
G01X1649887Y535974D02*
X1649897Y536073D01*
X1649925Y536145D01*
X1649964Y536171D01*
G01X1649887Y539124D02*
X1649897Y539222D01*
X1649925Y539294D01*
X1649964Y539321D01*
G01X1649887Y542274D02*
X1649897Y542372D01*
X1649925Y542444D01*
X1649964Y542470D01*
G01X1649887Y545423D02*
X1649897Y545521D01*
X1649925Y545594D01*
X1649964Y545620D01*
G01X1649887Y548573D02*
X1649897Y548671D01*
X1649925Y548743D01*
X1649964Y548770D01*
G01X1649887Y551722D02*
X1649897Y551821D01*
X1649925Y551893D01*
X1649964Y551919D01*
G01X1649887Y554872D02*
X1649897Y554970D01*
X1649925Y555042D01*
X1649964Y555069D01*
G01X1649443Y512650D02*
X1649445Y512688D01*
X1649454Y512725D01*
X1649467Y512759D01*
X1649486Y512789D01*
X1649508Y512813D01*
X1649534Y512831D01*
X1649561Y512843D01*
X1649590Y512847D01*
G01X1649443Y515799D02*
X1649445Y515838D01*
X1649454Y515874D01*
X1649467Y515908D01*
X1649486Y515939D01*
X1649508Y515963D01*
X1649534Y515981D01*
X1649561Y515992D01*
X1649590Y515996D01*
G01X1649443Y518949D02*
X1649445Y518987D01*
X1649454Y519024D01*
X1649467Y519058D01*
X1649486Y519088D01*
X1649508Y519112D01*
X1649534Y519131D01*
X1649561Y519142D01*
X1649590Y519146D01*
G01X1649443Y522099D02*
X1649445Y522137D01*
X1649454Y522174D01*
X1649467Y522207D01*
X1649486Y522238D01*
X1649508Y522262D01*
X1649534Y522280D01*
X1649561Y522291D01*
X1649590Y522295D01*
G01X1649443Y525248D02*
X1649445Y525286D01*
X1649454Y525323D01*
X1649467Y525357D01*
X1649486Y525387D01*
X1649508Y525412D01*
X1649534Y525430D01*
X1649561Y525441D01*
X1649590Y525445D01*
G01X1649443Y528398D02*
X1649445Y528436D01*
X1649454Y528473D01*
X1649467Y528507D01*
X1649486Y528537D01*
X1649508Y528561D01*
X1649534Y528579D01*
X1649561Y528591D01*
X1649590Y528595D01*
G01X1650595Y512650D02*
Y512688D01*
X1650597Y512725D01*
X1650600Y512759D01*
X1650604Y512789D01*
X1650609Y512813D01*
X1650615Y512831D01*
X1650621Y512843D01*
X1650627Y512847D01*
G01X1650595Y515799D02*
Y515838D01*
X1650597Y515874D01*
X1650600Y515908D01*
X1650604Y515939D01*
X1650609Y515963D01*
X1650615Y515981D01*
X1650621Y515992D01*
X1650627Y515996D01*
G01X1650595Y518949D02*
Y518987D01*
X1650597Y519024D01*
X1650600Y519058D01*
X1650604Y519088D01*
X1650609Y519112D01*
X1650615Y519131D01*
X1650621Y519142D01*
X1650627Y519146D01*
G01X1650595Y522099D02*
Y522137D01*
X1650597Y522174D01*
X1650600Y522207D01*
X1650604Y522238D01*
X1650609Y522262D01*
X1650615Y522280D01*
X1650621Y522291D01*
X1650627Y522295D01*
G01X1650595Y525248D02*
Y525286D01*
X1650597Y525323D01*
X1650600Y525357D01*
X1650604Y525387D01*
X1650609Y525412D01*
X1650615Y525430D01*
X1650621Y525441D01*
X1650627Y525445D01*
G01X1650595Y528398D02*
Y528436D01*
X1650597Y528473D01*
X1650600Y528507D01*
X1650604Y528537D01*
X1650609Y528561D01*
X1650615Y528579D01*
X1650621Y528591D01*
X1650627Y528595D01*
G01X1657784Y509308D02*
Y503927D01*
G01Y536230D02*
Y530750D01*
G01X1657614Y509104D02*
Y530955D01*
G01Y607136D02*
Y536230D01*
G01X1656914Y547726D02*
Y547333D01*
G01X1655036Y507726D02*
Y507333D01*
G01Y532726D02*
Y532333D01*
G01X1654945Y487726D02*
Y487333D01*
G01Y492726D02*
Y492333D01*
G01Y497726D02*
Y497333D01*
G01Y502726D02*
Y502333D01*
G01Y537726D02*
Y537333D01*
G01Y542726D02*
Y542333D01*
G01Y552726D02*
Y552333D01*
G01X1654819Y512650D02*
Y511665D01*
G01Y515799D02*
Y514815D01*
G01Y518949D02*
Y517965D01*
G01Y522099D02*
Y521114D01*
G01Y525248D02*
Y524264D01*
G01Y528398D02*
Y527413D01*
G01X1654809Y551329D02*
Y551722D01*
G01Y554478D02*
Y554872D01*
G01Y548179D02*
Y548573D01*
G01Y541880D02*
Y542274D01*
G01Y545029D02*
Y545423D01*
G01Y538730D02*
Y539124D01*
G01Y532431D02*
Y532825D01*
G01Y535581D02*
Y535974D01*
G01Y529281D02*
Y529675D01*
G01Y522982D02*
Y523376D01*
G01Y526132D02*
Y526525D01*
G01Y519833D02*
Y520226D01*
G01Y513533D02*
Y513927D01*
G01Y516683D02*
Y517077D01*
G01Y510384D02*
Y510777D01*
G01Y507234D02*
Y507628D01*
G01Y504085D02*
Y504478D01*
G01Y500935D02*
Y501329D01*
G01Y497785D02*
Y498179D01*
G01Y494636D02*
Y495029D01*
G01Y491486D02*
Y491880D01*
G01Y488337D02*
Y488730D01*
G01X1652326Y510285D02*
Y509104D01*
G01Y530955D02*
Y529774D01*
G01X1652296Y547726D02*
Y547333D01*
G01X1651172D02*
Y547726D01*
G01X1650595Y527413D02*
Y528398D01*
G01Y524264D02*
Y525248D01*
G01Y517965D02*
Y518949D01*
G01Y521114D02*
Y522099D01*
G01Y514815D02*
Y515799D01*
G01Y511665D02*
Y512650D01*
G01X1650328Y547333D02*
Y547726D01*
G01Y487726D02*
Y487333D01*
G01Y492726D02*
Y492333D01*
G01Y497726D02*
Y497333D01*
G01Y502726D02*
Y502333D01*
G01Y507726D02*
Y507333D01*
G01Y532726D02*
Y532333D01*
G01Y537726D02*
Y537333D01*
G01Y542726D02*
Y542333D01*
G01Y552726D02*
Y552333D01*
G01X1649887Y551329D02*
Y551722D01*
G01Y554478D02*
Y554872D01*
G01Y548179D02*
Y548573D01*
G01Y541880D02*
Y542274D01*
G01Y545029D02*
Y545423D01*
G01Y538730D02*
Y539124D01*
G01Y532431D02*
Y532825D01*
G01Y535581D02*
Y535974D01*
G01Y529281D02*
Y529675D01*
G01Y522982D02*
Y523376D01*
G01Y526132D02*
Y526525D01*
G01Y519833D02*
Y520226D01*
G01Y513533D02*
Y513927D01*
G01Y516683D02*
Y517077D01*
G01Y510384D02*
Y510777D01*
G01Y507234D02*
Y507628D01*
G01Y504085D02*
Y504478D01*
G01Y500935D02*
Y501329D01*
G01Y497785D02*
Y498179D01*
G01Y494636D02*
Y495029D01*
G01Y491486D02*
Y491880D01*
G01Y488337D02*
Y488730D01*
G01X1649443Y527413D02*
Y528398D01*
G01Y524264D02*
Y525248D01*
G01Y517965D02*
Y518949D01*
G01Y521114D02*
Y522099D01*
G01Y514815D02*
Y515799D01*
G01Y511665D02*
Y512650D01*
G01X1649374Y488730D02*
Y488337D01*
G01Y491880D02*
Y491486D01*
G01Y498179D02*
Y497785D01*
G01Y495029D02*
Y494636D01*
G01Y501329D02*
Y500935D01*
G01Y507628D02*
Y507234D01*
G01Y504478D02*
Y504085D01*
G01Y510777D02*
Y510384D01*
G01Y513927D02*
Y513533D01*
G01Y517077D02*
Y516683D01*
G01Y520226D02*
Y519833D01*
G01Y523376D02*
Y522982D01*
G01Y526525D02*
Y526132D01*
G01Y529675D02*
Y529281D01*
G01Y532825D02*
Y532431D01*
G01Y535974D02*
Y535581D01*
G01Y539124D02*
Y538730D01*
G01Y542274D02*
Y541880D01*
G01Y545423D02*
Y545029D01*
G01Y548573D02*
Y548179D01*
G01Y551722D02*
Y551329D01*
G01Y554872D02*
Y554478D01*
G01X1649203Y552333D02*
Y552726D01*
G01Y542333D02*
Y542726D01*
G01Y537333D02*
Y537726D01*
G01Y532333D02*
Y532726D01*
G01Y507333D02*
Y507726D01*
G01Y502333D02*
Y502726D01*
G01Y497333D02*
Y497726D01*
G01Y492333D02*
Y492726D01*
G01Y487333D02*
Y487726D01*
G01X1648501Y527413D02*
Y528398D01*
G01Y524264D02*
Y525248D01*
G01Y517965D02*
Y518949D01*
G01Y521114D02*
Y522099D01*
G01Y514815D02*
Y515799D01*
G01Y511665D02*
Y512650D01*
G01X1648359Y552333D02*
Y552726D01*
G01Y542333D02*
Y542726D01*
G01Y537333D02*
Y537726D01*
G01Y502333D02*
Y502726D01*
G01Y497333D02*
Y497726D01*
G01Y492333D02*
Y492726D01*
G01Y487333D02*
Y487726D01*
G01X1648294Y532333D02*
Y532726D01*
G01Y507333D02*
Y507726D01*
G01X1648197Y488730D02*
Y488337D01*
G01Y491880D02*
Y491486D01*
G01Y498179D02*
Y497785D01*
G01Y495029D02*
Y494636D01*
G01Y501329D02*
Y500935D01*
G01Y507628D02*
Y507234D01*
G01Y504478D02*
Y504085D01*
G01Y510777D02*
Y510384D01*
G01Y513927D02*
Y513533D01*
G01Y517077D02*
Y516683D01*
G01Y520226D02*
Y519833D01*
G01Y523376D02*
Y522982D01*
G01Y526525D02*
Y526132D01*
G01Y529675D02*
Y529281D01*
G01Y532825D02*
Y532431D01*
G01Y535974D02*
Y535581D01*
G01Y539124D02*
Y538730D01*
G01Y542274D02*
Y541880D01*
G01Y545423D02*
Y545029D01*
G01Y548573D02*
Y548179D01*
G01Y551722D02*
Y551329D01*
G01Y554872D02*
Y554478D01*
G01X1649374D02*
X1649377Y554440D01*
X1649385Y554403D01*
X1649397Y554369D01*
X1649415Y554339D01*
X1649436Y554315D01*
X1649459Y554297D01*
X1649485Y554285D01*
X1649513Y554281D01*
G01X1649374Y551329D02*
X1649377Y551290D01*
X1649385Y551254D01*
X1649397Y551220D01*
X1649415Y551189D01*
X1649436Y551165D01*
X1649459Y551147D01*
X1649485Y551136D01*
X1649513Y551132D01*
G01X1649374Y548179D02*
X1649377Y548141D01*
X1649385Y548104D01*
X1649397Y548070D01*
X1649415Y548040D01*
X1649436Y548015D01*
X1649459Y547997D01*
X1649485Y547986D01*
X1649513Y547982D01*
G01X1649374Y545029D02*
X1649377Y544991D01*
X1649385Y544954D01*
X1649397Y544921D01*
X1649415Y544890D01*
X1649436Y544866D01*
X1649459Y544848D01*
X1649485Y544836D01*
X1649513Y544833D01*
G01X1649374Y541880D02*
X1649377Y541842D01*
X1649385Y541805D01*
X1649397Y541771D01*
X1649415Y541741D01*
X1649436Y541716D01*
X1649459Y541698D01*
X1649485Y541687D01*
X1649513Y541683D01*
G01X1649374Y538730D02*
X1649377Y538692D01*
X1649385Y538655D01*
X1649397Y538621D01*
X1649415Y538591D01*
X1649436Y538567D01*
X1649459Y538548D01*
X1649485Y538537D01*
X1649513Y538533D01*
G01X1649374Y535581D02*
X1649377Y535542D01*
X1649385Y535506D01*
X1649397Y535472D01*
X1649415Y535441D01*
X1649436Y535417D01*
X1649459Y535399D01*
X1649485Y535388D01*
X1649513Y535384D01*
G01X1649374Y532431D02*
X1649377Y532393D01*
X1649385Y532356D01*
X1649397Y532322D01*
X1649415Y532292D01*
X1649436Y532267D01*
X1649459Y532249D01*
X1649485Y532238D01*
X1649513Y532234D01*
G01X1649374Y529281D02*
X1649377Y529243D01*
X1649385Y529206D01*
X1649397Y529172D01*
X1649415Y529142D01*
X1649436Y529118D01*
X1649459Y529100D01*
X1649485Y529088D01*
X1649513Y529085D01*
G01X1649374Y526132D02*
X1649377Y526094D01*
X1649385Y526057D01*
X1649397Y526023D01*
X1649415Y525993D01*
X1649436Y525968D01*
X1649459Y525950D01*
X1649485Y525939D01*
X1649513Y525935D01*
G01X1649374Y522982D02*
X1649377Y522944D01*
X1649385Y522907D01*
X1649397Y522873D01*
X1649415Y522843D01*
X1649436Y522819D01*
X1649459Y522800D01*
X1649485Y522789D01*
X1649513Y522785D01*
G01X1649374Y519833D02*
X1649377Y519794D01*
X1649385Y519758D01*
X1649397Y519724D01*
X1649415Y519693D01*
X1649436Y519669D01*
X1649459Y519651D01*
X1649485Y519640D01*
X1649513Y519636D01*
G01X1649374Y516683D02*
X1649377Y516645D01*
X1649385Y516608D01*
X1649397Y516574D01*
X1649415Y516544D01*
X1649436Y516519D01*
X1649459Y516501D01*
X1649485Y516490D01*
X1649513Y516486D01*
G01X1649374Y513533D02*
X1649377Y513495D01*
X1649385Y513458D01*
X1649397Y513424D01*
X1649415Y513394D01*
X1649436Y513370D01*
X1649459Y513352D01*
X1649485Y513340D01*
X1649513Y513337D01*
G01X1649374Y510384D02*
X1649377Y510346D01*
X1649385Y510309D01*
X1649397Y510275D01*
X1649415Y510245D01*
X1649436Y510220D01*
X1649459Y510202D01*
X1649485Y510191D01*
X1649513Y510187D01*
G01X1649374Y507234D02*
X1649377Y507196D01*
X1649385Y507159D01*
X1649397Y507125D01*
X1649415Y507095D01*
X1649436Y507071D01*
X1649459Y507052D01*
X1649485Y507041D01*
X1649513Y507037D01*
G01X1649374Y504085D02*
X1649377Y504046D01*
X1649385Y504010D01*
X1649397Y503976D01*
X1649415Y503945D01*
X1649436Y503921D01*
X1649459Y503903D01*
X1649485Y503892D01*
X1649513Y503888D01*
G01X1649374Y500935D02*
X1649377Y500897D01*
X1649385Y500860D01*
X1649397Y500826D01*
X1649415Y500796D01*
X1649436Y500771D01*
X1649459Y500753D01*
X1649485Y500742D01*
X1649513Y500738D01*
G01X1649374Y497785D02*
X1649377Y497747D01*
X1649385Y497710D01*
X1649397Y497676D01*
X1649415Y497646D01*
X1649436Y497622D01*
X1649459Y497604D01*
X1649485Y497592D01*
X1649513Y497588D01*
G01X1649374Y494636D02*
X1649377Y494597D01*
X1649385Y494561D01*
X1649397Y494527D01*
X1649415Y494497D01*
X1649436Y494472D01*
X1649459Y494454D01*
X1649485Y494443D01*
X1649513Y494439D01*
G01X1649374Y491486D02*
X1649377Y491448D01*
X1649385Y491411D01*
X1649397Y491377D01*
X1649415Y491347D01*
X1649436Y491323D01*
X1649459Y491304D01*
X1649485Y491293D01*
X1649513Y491289D01*
G01X1649374Y488337D02*
X1649377Y488298D01*
X1649385Y488262D01*
X1649397Y488228D01*
X1649415Y488197D01*
X1649436Y488173D01*
X1649459Y488155D01*
X1649485Y488144D01*
X1649513Y488140D01*
G01X1652296Y547333D02*
X1652374Y546742D01*
G01X1650328Y557333D02*
X1650405Y556742D01*
G01X1650328Y552333D02*
X1650405Y551742D01*
G01X1650328Y542333D02*
X1650405Y541742D01*
G01X1650328Y537333D02*
X1650405Y536742D01*
G01X1650328Y532333D02*
X1650405Y531742D01*
G01X1650328Y507333D02*
X1650405Y506742D01*
G01X1650328Y502333D02*
X1650405Y501742D01*
G01X1650328Y497333D02*
X1650405Y496742D01*
G01X1650328Y492333D02*
X1650405Y491742D01*
G01X1650328Y487333D02*
X1650405Y486742D01*
G01X1654809Y554872D02*
X1654777Y554969D01*
X1654689Y555041D01*
X1654561Y555069D01*
G01X1654809Y551722D02*
X1654777Y551819D01*
X1654689Y551892D01*
X1654561Y551919D01*
G01X1654809Y548573D02*
X1654777Y548670D01*
X1654689Y548742D01*
X1654561Y548770D01*
G01X1654809Y545423D02*
X1654777Y545520D01*
X1654689Y545592D01*
X1654561Y545620D01*
G01X1654809Y542274D02*
X1654777Y542371D01*
X1654689Y542443D01*
X1654561Y542470D01*
G01X1654809Y539124D02*
X1654777Y539221D01*
X1654689Y539293D01*
X1654561Y539321D01*
G01X1654809Y535974D02*
X1654777Y536071D01*
X1654689Y536144D01*
X1654561Y536171D01*
G01X1654809Y532825D02*
X1654777Y532922D01*
X1654689Y532994D01*
X1654561Y533022D01*
G01X1654809Y529675D02*
X1654777Y529772D01*
X1654689Y529844D01*
X1654561Y529872D01*
G01X1654809Y526525D02*
X1654777Y526623D01*
X1654689Y526695D01*
X1654561Y526722D01*
G01X1654809Y523376D02*
X1654777Y523473D01*
X1654689Y523545D01*
X1654561Y523573D01*
G01X1654809Y520226D02*
X1654777Y520323D01*
X1654689Y520395D01*
X1654561Y520423D01*
G01X1654809Y517077D02*
X1654777Y517174D01*
X1654689Y517246D01*
X1654561Y517274D01*
G01X1654809Y513927D02*
X1654777Y514024D01*
X1654689Y514096D01*
X1654561Y514124D01*
G01X1654809Y510777D02*
X1654777Y510874D01*
X1654689Y510947D01*
X1654561Y510974D01*
G01X1654809Y507628D02*
X1654777Y507725D01*
X1654689Y507797D01*
X1654561Y507825D01*
G01X1654809Y504478D02*
X1654777Y504575D01*
X1654689Y504647D01*
X1654561Y504675D01*
G01X1654809Y501329D02*
X1654777Y501426D01*
X1654689Y501498D01*
X1654561Y501525D01*
G01X1654809Y498179D02*
X1654777Y498276D01*
X1654689Y498348D01*
X1654561Y498376D01*
G01X1654809Y495029D02*
X1654777Y495126D01*
X1654689Y495199D01*
X1654561Y495226D01*
G01X1654809Y491880D02*
X1654777Y491977D01*
X1654689Y492049D01*
X1654561Y492077D01*
G01X1654809Y488730D02*
X1654777Y488827D01*
X1654689Y488899D01*
X1654561Y488927D01*
G01X1654809Y485581D02*
X1654777Y485678D01*
X1654689Y485750D01*
X1654561Y485777D01*
G01X1654819Y528398D02*
X1654785Y528497D01*
X1654697Y528568D01*
X1654571Y528595D01*
G01X1654819Y525248D02*
X1654785Y525347D01*
X1654697Y525418D01*
X1654571Y525445D01*
G01X1654819Y522099D02*
X1654785Y522198D01*
X1654697Y522268D01*
X1654571Y522295D01*
G01X1654819Y518949D02*
X1654785Y519048D01*
X1654697Y519119D01*
X1654571Y519146D01*
G01X1654819Y515799D02*
X1654785Y515898D01*
X1654697Y515969D01*
X1654571Y515996D01*
G01X1654819Y512650D02*
X1654785Y512749D01*
X1654697Y512820D01*
X1654571Y512847D01*
G01X1649476Y556742D02*
X1649203Y557333D01*
G01X1649476Y551742D02*
X1649203Y552333D01*
G01X1651444Y546742D02*
X1651172Y547333D01*
G01X1649476Y541742D02*
X1649203Y542333D01*
G01X1649476Y536742D02*
X1649203Y537333D01*
G01X1649476Y531742D02*
X1649203Y532333D01*
G01X1649476Y506742D02*
X1649203Y507333D01*
G01X1649476Y501742D02*
X1649203Y502333D01*
G01X1649476Y496742D02*
X1649203Y497333D01*
G01X1649476Y491742D02*
X1649203Y492333D01*
G01X1649476Y486742D02*
X1649203Y487333D01*
G01X1655036Y532726D02*
X1654902Y532924D01*
X1654767Y533121D01*
X1654631Y533317D01*
G01X1654945Y552726D02*
X1654808Y552924D01*
X1654670Y553121D01*
X1654531Y553317D01*
G01X1656914Y547726D02*
X1656777Y547924D01*
X1656639Y548121D01*
X1656500Y548317D01*
G01X1654945Y542726D02*
X1654808Y542924D01*
X1654670Y543121D01*
X1654531Y543317D01*
G01X1654945Y537726D02*
X1654808Y537924D01*
X1654670Y538121D01*
X1654531Y538317D01*
G01X1648786Y556742D02*
X1648359Y557333D01*
G01X1648786Y551742D02*
X1648359Y552333D01*
G01X1650754Y546742D02*
X1650328Y547333D01*
G01X1648786Y541742D02*
X1648359Y542333D01*
G01X1649513Y555069D02*
X1649486Y555065D01*
X1649460Y555054D01*
X1649436Y555036D01*
X1649415Y555011D01*
X1649397Y554981D01*
X1649385Y554948D01*
X1649377Y554911D01*
X1649374Y554872D01*
G01X1649513Y551919D02*
X1649486Y551915D01*
X1649460Y551904D01*
X1649436Y551886D01*
X1649415Y551862D01*
X1649397Y551832D01*
X1649385Y551798D01*
X1649377Y551761D01*
X1649374Y551722D01*
G01X1649513Y548770D02*
X1649486Y548766D01*
X1649460Y548755D01*
X1649436Y548737D01*
X1649415Y548712D01*
X1649397Y548682D01*
X1649385Y548648D01*
X1649377Y548612D01*
X1649374Y548573D01*
G01X1649513Y545620D02*
X1649486Y545616D01*
X1649460Y545605D01*
X1649436Y545587D01*
X1649415Y545562D01*
X1649397Y545533D01*
X1649385Y545499D01*
X1649377Y545462D01*
X1649374Y545423D01*
G01X1649513Y542470D02*
X1649486Y542467D01*
X1649460Y542456D01*
X1649436Y542437D01*
X1649415Y542413D01*
X1649397Y542383D01*
X1649385Y542349D01*
X1649377Y542312D01*
X1649374Y542274D01*
G01X1649513Y539321D02*
X1649486Y539317D01*
X1649460Y539306D01*
X1649436Y539288D01*
X1649415Y539263D01*
X1649397Y539233D01*
X1649385Y539200D01*
X1649377Y539163D01*
X1649374Y539124D01*
G01X1649513Y536171D02*
X1649486Y536167D01*
X1649460Y536156D01*
X1649436Y536138D01*
X1649415Y536114D01*
X1649397Y536084D01*
X1649385Y536050D01*
X1649377Y536013D01*
X1649374Y535974D01*
G01X1649513Y533022D02*
X1649486Y533018D01*
X1649460Y533007D01*
X1649436Y532989D01*
X1649415Y532964D01*
X1649397Y532934D01*
X1649385Y532900D01*
X1649377Y532864D01*
X1649374Y532825D01*
G01X1654571Y527217D02*
X1654698Y527244D01*
X1654787Y527317D01*
X1654819Y527413D01*
G01X1654571Y524067D02*
X1654698Y524094D01*
X1654787Y524167D01*
X1654819Y524264D01*
G01X1654571Y520917D02*
X1654698Y520945D01*
X1654787Y521017D01*
X1654819Y521114D01*
G01X1654571Y517768D02*
X1654698Y517795D01*
X1654787Y517868D01*
X1654819Y517965D01*
G01X1654571Y514618D02*
X1654698Y514646D01*
X1654787Y514718D01*
X1654819Y514815D01*
G01X1654571Y511469D02*
X1654698Y511496D01*
X1654787Y511569D01*
X1654819Y511665D01*
G01X1654561Y554281D02*
X1654689Y554309D01*
X1654777Y554382D01*
X1654809Y554478D01*
G01X1654561Y551132D02*
X1654689Y551160D01*
X1654777Y551232D01*
X1654809Y551329D01*
G01X1654561Y547982D02*
X1654689Y548010D01*
X1654777Y548083D01*
X1654809Y548179D01*
G01X1654561Y544833D02*
X1654689Y544860D01*
X1654777Y544933D01*
X1654809Y545029D01*
G01X1654561Y541683D02*
X1654689Y541711D01*
X1654777Y541784D01*
X1654809Y541880D01*
G01X1654561Y538533D02*
X1654689Y538561D01*
X1654777Y538634D01*
X1654809Y538730D01*
G01X1654561Y535384D02*
X1654689Y535412D01*
X1654777Y535484D01*
X1654809Y535581D01*
G01X1654561Y532234D02*
X1654689Y532262D01*
X1654777Y532335D01*
X1654809Y532431D01*
G01X1654561Y529085D02*
X1654689Y529112D01*
X1654777Y529185D01*
X1654809Y529281D01*
G01X1654561Y525935D02*
X1654689Y525963D01*
X1654777Y526036D01*
X1654809Y526132D01*
G01X1654561Y522785D02*
X1654689Y522813D01*
X1654777Y522886D01*
X1654809Y522982D01*
G01X1654561Y519636D02*
X1654689Y519663D01*
X1654777Y519736D01*
X1654809Y519833D01*
G01X1654561Y516486D02*
X1654689Y516514D01*
X1654777Y516587D01*
X1654809Y516683D01*
G01X1654561Y513337D02*
X1654689Y513364D01*
X1654777Y513437D01*
X1654809Y513533D01*
G01X1654561Y510187D02*
X1654689Y510215D01*
X1654777Y510288D01*
X1654809Y510384D01*
G01X1654561Y507037D02*
X1654689Y507065D01*
X1654777Y507138D01*
X1654809Y507234D01*
G01X1654561Y503888D02*
X1654689Y503915D01*
X1654777Y503988D01*
X1654809Y504085D01*
G01X1654561Y500738D02*
X1654689Y500766D01*
X1654777Y500839D01*
X1654809Y500935D01*
G01X1654561Y497588D02*
X1654689Y497616D01*
X1654777Y497689D01*
X1654809Y497785D01*
G01X1655036Y507726D02*
X1654902Y507924D01*
X1654767Y508121D01*
X1654631Y508317D01*
G01X1654945Y502726D02*
X1654808Y502924D01*
X1654670Y503121D01*
X1654531Y503317D01*
G01X1654945Y497726D02*
X1654808Y497924D01*
X1654670Y498121D01*
X1654531Y498317D01*
G01X1654945Y492726D02*
X1654808Y492924D01*
X1654670Y493121D01*
X1654531Y493317D01*
G01X1654945Y487726D02*
X1654808Y487924D01*
X1654670Y488121D01*
X1654531Y488317D01*
G01X1648718Y531742D02*
X1648294Y532333D01*
G01X1648718Y506742D02*
X1648294Y507333D01*
G01X1648786Y536742D02*
X1648359Y537333D01*
G01X1648786Y501742D02*
X1648359Y502333D01*
G01X1648786Y496742D02*
X1648359Y497333D01*
G01X1648786Y491742D02*
X1648359Y492333D01*
G01X1648786Y486742D02*
X1648359Y487333D01*
G01X1656827Y510266D02*
X1658795Y508297D01*
G01X1654531Y556742D02*
X1648786D01*
G01X1654561Y555069D02*
X1648477D01*
G01X1648197Y554872D02*
X1654809D01*
G01Y554478D02*
X1648197D01*
G01X1654561Y554281D02*
X1648477D01*
G01X1654531Y553317D02*
X1648786D01*
G01X1648359Y552726D02*
X1654945D01*
G01X1648359Y552333D02*
X1654945D01*
G01X1654561Y551919D02*
X1648477D01*
G01X1654531Y551742D02*
X1648786D01*
G01X1648197Y551722D02*
X1654809D01*
G01Y551329D02*
X1648197D01*
G01X1654561Y551132D02*
X1648477D01*
G01X1654561Y548770D02*
X1648477D01*
G01X1648197Y548573D02*
X1654809D01*
G01X1656500Y548317D02*
X1650754D01*
G01X1654809Y548179D02*
X1648197D01*
G01X1654561Y547982D02*
X1648477D01*
G01X1650328Y547726D02*
X1656914D01*
G01X1650328Y547333D02*
X1656914D01*
G01X1656500Y546742D02*
X1650754D01*
G01X1654561Y545620D02*
X1648477D01*
G01X1648197Y545423D02*
X1654809D01*
G01Y545029D02*
X1648197D01*
G01X1654561Y544833D02*
X1648477D01*
G01X1654531Y543317D02*
X1648786D01*
G01X1648359Y542726D02*
X1654945D01*
G01X1654561Y542470D02*
X1648477D01*
G01X1648359Y542333D02*
X1654945D01*
G01X1648197Y542274D02*
X1654809D01*
G01Y541880D02*
X1648197D01*
G01X1654531Y541742D02*
X1648786D01*
G01X1654561Y541683D02*
X1648477D01*
G01X1654561Y539321D02*
X1648477D01*
G01X1648197Y539124D02*
X1654809D01*
G01Y538730D02*
X1648197D01*
G01X1654561Y538533D02*
X1648477D01*
G01X1654531Y538317D02*
X1648786D01*
G01X1648359Y537726D02*
X1654945D01*
G01X1648359Y537333D02*
X1654945D01*
G01X1654531Y536742D02*
X1648786D01*
G01X1654561Y536171D02*
X1648477D01*
G01X1648197Y535974D02*
X1654809D01*
G01Y535581D02*
X1648197D01*
G01X1654561Y535384D02*
X1648477D01*
G01X1654631Y533317D02*
X1648718D01*
G01X1654561Y533022D02*
X1648477D01*
G01X1648197Y532825D02*
X1654809D01*
G01X1648294Y532726D02*
X1655036D01*
G01X1654809Y532431D02*
X1648197D01*
G01X1648294Y532333D02*
X1655036D01*
G01X1654561Y532234D02*
X1648477D01*
G01X1654631Y531742D02*
X1648718D01*
G01X1652326Y530955D02*
X1658795D01*
G01X1654561Y529872D02*
X1648477D01*
G01X1648197Y529675D02*
X1654809D01*
G01Y529281D02*
X1648197D01*
G01X1654561Y529085D02*
X1648477D01*
G01X1648763Y528595D02*
X1654571D01*
G01X1654819Y528398D02*
X1648501D01*
G01Y527413D02*
X1654819D01*
G01X1648763Y527217D02*
X1654571D01*
G01X1654561Y526722D02*
X1648477D01*
G01X1648197Y526525D02*
X1654809D01*
G01Y526132D02*
X1648197D01*
G01X1654561Y525935D02*
X1648477D01*
G01X1648763Y525445D02*
X1654571D01*
G01X1654819Y525248D02*
X1648501D01*
G01Y524264D02*
X1654819D01*
G01X1648763Y524067D02*
X1654571D01*
G01X1654561Y523573D02*
X1648477D01*
G01X1648197Y523376D02*
X1654809D01*
G01Y522982D02*
X1648197D01*
G01X1654561Y522785D02*
X1648477D01*
G01X1648763Y522295D02*
X1654571D01*
G01X1654819Y522099D02*
X1648501D01*
G01Y521114D02*
X1654819D01*
G01X1648763Y520917D02*
X1654571D01*
G01X1654561Y520423D02*
X1648477D01*
G01X1648197Y520226D02*
X1654809D01*
G01Y519833D02*
X1648197D01*
G01X1654561Y519636D02*
X1648477D01*
G01X1648763Y519146D02*
X1654571D01*
G01X1654819Y518949D02*
X1648501D01*
G01Y517965D02*
X1654819D01*
G01X1648763Y517768D02*
X1654571D01*
G01X1654561Y517274D02*
X1648477D01*
G01X1648197Y517077D02*
X1654809D01*
G01Y516683D02*
X1648197D01*
G01X1654561Y516486D02*
X1648477D01*
G01X1648763Y515996D02*
X1654571D01*
G01X1654819Y515799D02*
X1648501D01*
G01Y514815D02*
X1654819D01*
G01X1648763Y514618D02*
X1654571D01*
G01X1654561Y514124D02*
X1648477D01*
G01X1648197Y513927D02*
X1654809D01*
G01Y513533D02*
X1648197D01*
G01X1654561Y513337D02*
X1648477D01*
G01X1648763Y512847D02*
X1654571D01*
G01X1654819Y512650D02*
X1648501D01*
G01Y511665D02*
X1654819D01*
G01X1648763Y511469D02*
X1654571D01*
G01X1654561Y510974D02*
X1648477D01*
G01X1648197Y510777D02*
X1654809D01*
G01Y510384D02*
X1648197D01*
G01X1654561Y510187D02*
X1648477D01*
G01X1658795Y509104D02*
X1652326D01*
G01X1654631Y508317D02*
X1648718D01*
G01X1654561Y507825D02*
X1648477D01*
G01X1648294Y507726D02*
X1655036D01*
G01X1648197Y507628D02*
X1654809D01*
G01X1648294Y507333D02*
X1655036D01*
G01X1654809Y507234D02*
X1648197D01*
G01X1654561Y507037D02*
X1648477D01*
G01X1654631Y506742D02*
X1648718D01*
G01X1649513Y529872D02*
X1649486Y529868D01*
X1649460Y529857D01*
X1649436Y529839D01*
X1649415Y529814D01*
X1649397Y529785D01*
X1649385Y529751D01*
X1649377Y529714D01*
X1649374Y529675D01*
G01X1649513Y526722D02*
X1649486Y526719D01*
X1649460Y526707D01*
X1649436Y526689D01*
X1649415Y526665D01*
X1649397Y526635D01*
X1649385Y526601D01*
X1649377Y526564D01*
X1649374Y526525D01*
G01X1649513Y523573D02*
X1649486Y523569D01*
X1649460Y523558D01*
X1649436Y523540D01*
X1649415Y523515D01*
X1649397Y523485D01*
X1649385Y523452D01*
X1649377Y523415D01*
X1649374Y523376D01*
G01X1649513Y520423D02*
X1649486Y520419D01*
X1649460Y520408D01*
X1649436Y520390D01*
X1649415Y520365D01*
X1649397Y520336D01*
X1649385Y520302D01*
X1649377Y520265D01*
X1649374Y520226D01*
G01X1649513Y517274D02*
X1649486Y517270D01*
X1649460Y517259D01*
X1649436Y517241D01*
X1649415Y517216D01*
X1649397Y517186D01*
X1649385Y517152D01*
X1649377Y517116D01*
X1649374Y517077D01*
G01X1649513Y514124D02*
X1649486Y514120D01*
X1649460Y514109D01*
X1649436Y514091D01*
X1649415Y514066D01*
X1649397Y514037D01*
X1649385Y514003D01*
X1649377Y513966D01*
X1649374Y513927D01*
G01X1649513Y510974D02*
X1649486Y510971D01*
X1649460Y510959D01*
X1649436Y510941D01*
X1649415Y510917D01*
X1649397Y510887D01*
X1649385Y510853D01*
X1649377Y510816D01*
X1649374Y510777D01*
G01X1649513Y507825D02*
X1649486Y507821D01*
X1649460Y507810D01*
X1649436Y507792D01*
X1649415Y507767D01*
X1649397Y507737D01*
X1649385Y507704D01*
X1649377Y507667D01*
X1649374Y507628D01*
G01X1649513Y504675D02*
X1649486Y504671D01*
X1649460Y504660D01*
X1649436Y504642D01*
X1649415Y504617D01*
X1649397Y504588D01*
X1649385Y504554D01*
X1649377Y504517D01*
X1649374Y504478D01*
G01X1649513Y501525D02*
X1649486Y501522D01*
X1649460Y501511D01*
X1649436Y501493D01*
X1649415Y501468D01*
X1649397Y501438D01*
X1649385Y501404D01*
X1649377Y501368D01*
X1649374Y501329D01*
G01X1649513Y498376D02*
X1649486Y498372D01*
X1649460Y498361D01*
X1649436Y498343D01*
X1649415Y498318D01*
X1649397Y498289D01*
X1649385Y498255D01*
X1649377Y498218D01*
X1649374Y498179D01*
G01X1649513Y495226D02*
X1649486Y495223D01*
X1649460Y495211D01*
X1649436Y495193D01*
X1649415Y495169D01*
X1649397Y495139D01*
X1649385Y495105D01*
X1649377Y495068D01*
X1649374Y495029D01*
G01X1649513Y492077D02*
X1649486Y492073D01*
X1649460Y492062D01*
X1649436Y492044D01*
X1649415Y492019D01*
X1649397Y491989D01*
X1649385Y491955D01*
X1649377Y491919D01*
X1649374Y491880D01*
G01X1649513Y488927D02*
X1649486Y488923D01*
X1649460Y488912D01*
X1649436Y488894D01*
X1649415Y488869D01*
X1649397Y488840D01*
X1649385Y488806D01*
X1649377Y488769D01*
X1649374Y488730D01*
G01X1649513Y485777D02*
X1649486Y485774D01*
X1649460Y485763D01*
X1649436Y485745D01*
X1649415Y485720D01*
X1649397Y485690D01*
X1649385Y485656D01*
X1649377Y485620D01*
X1649374Y485581D01*
G01X1654561Y494439D02*
X1654689Y494467D01*
X1654777Y494540D01*
X1654809Y494636D01*
G01X1654561Y491289D02*
X1654689Y491317D01*
X1654777Y491390D01*
X1654809Y491486D01*
G01X1654561Y488140D02*
X1654689Y488167D01*
X1654777Y488240D01*
X1654809Y488337D01*
G01X1649964Y554281D02*
X1649925Y554308D01*
X1649897Y554380D01*
X1649887Y554478D01*
G01X1649964Y551132D02*
X1649925Y551158D01*
X1649897Y551230D01*
X1649887Y551329D01*
G01X1649964Y547982D02*
X1649925Y548009D01*
X1649897Y548081D01*
X1649887Y548179D01*
G01X1649964Y544833D02*
X1649925Y544859D01*
X1649897Y544931D01*
X1649887Y545029D01*
G01X1649964Y541683D02*
X1649925Y541709D01*
X1649897Y541781D01*
X1649887Y541880D01*
G01X1649964Y538533D02*
X1649925Y538560D01*
X1649897Y538632D01*
X1649887Y538730D01*
G01X1649964Y535384D02*
X1649925Y535410D01*
X1649897Y535482D01*
X1649887Y535581D01*
G01X1649964Y532234D02*
X1649925Y532261D01*
X1649897Y532333D01*
X1649887Y532431D01*
G01X1649964Y529085D02*
X1649925Y529111D01*
X1649897Y529183D01*
X1649887Y529281D01*
G01X1649964Y525935D02*
X1649925Y525961D01*
X1649897Y526033D01*
X1649887Y526132D01*
G01X1649964Y522785D02*
X1649925Y522812D01*
X1649897Y522884D01*
X1649887Y522982D01*
G01X1649964Y519636D02*
X1649925Y519662D01*
X1649897Y519734D01*
X1649887Y519833D01*
G01X1649964Y516486D02*
X1649925Y516513D01*
X1649897Y516585D01*
X1649887Y516683D01*
G01X1649964Y513337D02*
X1649925Y513363D01*
X1649897Y513435D01*
X1649887Y513533D01*
G01X1649964Y510187D02*
X1649925Y510213D01*
X1649897Y510285D01*
X1649887Y510384D01*
G01X1649964Y507037D02*
X1649925Y507064D01*
X1649897Y507136D01*
X1649887Y507234D01*
G01X1649964Y503888D02*
X1649925Y503914D01*
X1649897Y503986D01*
X1649887Y504085D01*
G01X1649964Y500738D02*
X1649925Y500765D01*
X1649897Y500837D01*
X1649887Y500935D01*
G01X1649964Y497588D02*
X1649925Y497615D01*
X1649897Y497687D01*
X1649887Y497785D01*
G01X1649964Y494439D02*
X1649925Y494465D01*
X1649897Y494537D01*
X1649887Y494636D01*
G01X1649964Y491289D02*
X1649925Y491316D01*
X1649897Y491388D01*
X1649887Y491486D01*
G01X1649964Y488140D02*
X1649925Y488166D01*
X1649897Y488238D01*
X1649887Y488337D01*
G01X1650627Y527217D02*
X1650621Y527220D01*
X1650615Y527231D01*
X1650609Y527250D01*
X1650604Y527274D01*
X1650600Y527304D01*
X1650597Y527338D01*
X1650595Y527375D01*
Y527413D01*
G01X1650627Y524067D02*
X1650621Y524071D01*
X1650615Y524082D01*
X1650609Y524100D01*
X1650604Y524125D01*
X1650600Y524154D01*
X1650597Y524188D01*
X1650595Y524225D01*
Y524264D01*
G01X1650627Y520917D02*
X1650621Y520921D01*
X1650615Y520932D01*
X1650609Y520950D01*
X1650604Y520975D01*
X1650600Y521005D01*
X1650597Y521039D01*
X1650595Y521075D01*
Y521114D01*
G01X1650627Y517768D02*
X1650621Y517772D01*
X1650615Y517783D01*
X1650609Y517801D01*
X1650604Y517825D01*
X1650600Y517855D01*
X1650597Y517889D01*
X1650595Y517926D01*
Y517965D01*
G01X1650627Y514618D02*
X1650621Y514622D01*
X1650615Y514633D01*
X1650609Y514651D01*
X1650604Y514676D01*
X1650600Y514706D01*
X1650597Y514739D01*
X1650595Y514776D01*
Y514815D01*
G01X1650627Y511469D02*
X1650621Y511472D01*
X1650615Y511483D01*
X1650609Y511501D01*
X1650604Y511526D01*
X1650600Y511556D01*
X1650597Y511590D01*
X1650595Y511627D01*
Y511665D01*
G01X1649590Y527217D02*
X1649562Y527220D01*
X1649534Y527231D01*
X1649509Y527250D01*
X1649486Y527274D01*
X1649468Y527304D01*
X1649454Y527338D01*
X1649446Y527375D01*
X1649443Y527413D01*
G01X1649590Y524067D02*
X1649562Y524071D01*
X1649534Y524082D01*
X1649509Y524100D01*
X1649486Y524125D01*
X1649468Y524154D01*
X1649454Y524188D01*
X1649446Y524225D01*
X1649443Y524264D01*
G01X1649590Y520917D02*
X1649562Y520921D01*
X1649534Y520932D01*
X1649509Y520950D01*
X1649486Y520975D01*
X1649468Y521005D01*
X1649454Y521039D01*
X1649446Y521075D01*
X1649443Y521114D01*
G01X1649590Y517768D02*
X1649562Y517772D01*
X1649534Y517783D01*
X1649509Y517801D01*
X1649486Y517825D01*
X1649468Y517855D01*
X1649454Y517889D01*
X1649446Y517926D01*
X1649443Y517965D01*
G01X1649590Y514618D02*
X1649562Y514622D01*
X1649534Y514633D01*
X1649509Y514651D01*
X1649486Y514676D01*
X1649468Y514706D01*
X1649454Y514739D01*
X1649446Y514776D01*
X1649443Y514815D01*
G01X1649590Y511469D02*
X1649562Y511472D01*
X1649534Y511483D01*
X1649509Y511501D01*
X1649486Y511526D01*
X1649468Y511556D01*
X1649454Y511590D01*
X1649446Y511627D01*
X1649443Y511665D01*
G01X1654561Y504675D02*
X1648477D01*
G01X1648197Y504478D02*
X1654809D01*
G01Y504085D02*
X1648197D01*
G01X1654561Y503888D02*
X1648477D01*
G01X1654531Y503317D02*
X1648786D01*
G01X1648359Y502726D02*
X1654945D01*
G01X1648359Y502333D02*
X1654945D01*
G01X1654531Y501742D02*
X1648786D01*
G01X1654561Y501525D02*
X1648477D01*
G01X1648197Y501329D02*
X1654809D01*
G01Y500935D02*
X1648197D01*
G01X1654561Y500738D02*
X1648477D01*
G01X1654561Y498376D02*
X1648477D01*
G01X1654531Y498317D02*
X1648786D01*
G01X1648197Y498179D02*
X1654809D01*
G01Y497785D02*
X1648197D01*
G01X1648359Y497726D02*
X1654945D01*
G01X1654561Y497588D02*
X1648477D01*
G01X1648359Y497333D02*
X1654945D01*
G01X1654531Y496742D02*
X1648786D01*
G01X1654561Y495226D02*
X1648477D01*
G01X1648197Y495029D02*
X1654809D01*
G01Y494636D02*
X1648197D01*
G01X1654561Y494439D02*
X1648477D01*
G01X1654531Y493317D02*
X1648786D01*
G01X1648359Y492726D02*
X1654945D01*
G01X1648359Y492333D02*
X1654945D01*
G01X1654561Y492077D02*
X1648477D01*
G01X1648197Y491880D02*
X1654809D01*
G01X1654531Y491742D02*
X1648786D01*
G01X1654809Y491486D02*
X1648197D01*
G01X1654561Y491289D02*
X1648477D01*
G01X1654561Y488927D02*
X1648477D01*
G01X1648197Y488730D02*
X1654809D01*
G01Y488337D02*
X1648197D01*
G01X1654531Y488317D02*
X1648786D01*
G01X1654561Y488140D02*
X1648477D01*
G01X1648359Y487726D02*
X1654945D01*
G01X1648359Y487333D02*
X1654945D01*
G01X1654531Y486742D02*
X1648786D01*
G01X1654561Y485777D02*
X1648477D01*
G01X1648197Y485581D02*
X1654809D01*
G01X1648786Y558317D02*
X1648359Y557726D01*
G01X1649203D02*
X1649476Y558317D01*
G01X1650328Y557726D02*
X1650405Y558317D01*
G01X1649887Y558022D02*
X1649897Y558120D01*
X1649925Y558192D01*
X1649964Y558218D01*
G01X1654945Y557726D02*
Y557333D01*
G01X1654809Y557628D02*
Y558022D01*
G01X1650328Y557726D02*
Y557333D01*
G01X1649887Y557628D02*
Y558022D01*
G01X1649374D02*
Y557628D01*
G01X1649203Y557333D02*
Y557726D01*
G01X1648359Y557333D02*
Y557726D01*
G01X1648197Y558022D02*
Y557628D01*
G01X1649374D02*
X1649377Y557590D01*
X1649385Y557553D01*
X1649397Y557519D01*
X1649415Y557489D01*
X1649436Y557464D01*
X1649459Y557446D01*
X1649485Y557435D01*
X1649513Y557431D01*
G01X1654809Y558022D02*
X1654777Y558119D01*
X1654689Y558191D01*
X1654561Y558218D01*
G01X1654945Y557726D02*
X1654808Y557924D01*
X1654670Y558121D01*
X1654531Y558317D01*
G01X1649513Y558218D02*
X1649486Y558215D01*
X1649460Y558204D01*
X1649436Y558186D01*
X1649415Y558161D01*
X1649397Y558131D01*
X1649385Y558097D01*
X1649377Y558060D01*
X1649374Y558022D01*
G01X1654561Y557431D02*
X1654689Y557459D01*
X1654777Y557532D01*
X1654809Y557628D01*
G01X1648197Y558022D02*
X1654809D01*
G01X1648359Y557726D02*
X1654945D01*
G01X1654809Y557628D02*
X1648197D01*
G01X1654561Y557431D02*
X1648477D01*
G01X1648359Y557333D02*
X1654945D01*
G01X1649964Y557431D02*
X1649925Y557457D01*
X1649897Y557529D01*
X1649887Y557628D01*
G01X1656827Y606348D02*
X1658795Y608317D01*
G01X1648786Y563317D02*
X1648359Y562726D01*
G01X1648786Y568317D02*
X1648359Y567726D01*
G01X1648786Y573317D02*
X1648359Y572726D01*
G01X1648786Y578317D02*
X1648359Y577726D01*
G01X1648786Y583317D02*
X1648359Y582726D01*
G01X1650754Y588317D02*
X1650328Y587726D01*
G01X1648786Y593317D02*
X1648359Y592726D01*
G01X1648786Y598317D02*
X1648359Y597726D01*
G01X1648786Y603317D02*
X1648359Y602726D01*
G01X1654531Y561742D02*
X1654670Y561938D01*
X1654808Y562135D01*
X1654945Y562333D01*
G01X1654531Y566742D02*
X1654670Y566938D01*
X1654808Y567135D01*
X1654945Y567333D01*
G01X1654531Y571742D02*
X1654670Y571938D01*
X1654808Y572135D01*
X1654945Y572333D01*
G01X1654531Y576742D02*
X1654670Y576938D01*
X1654808Y577135D01*
X1654945Y577333D01*
G01X1654531Y581742D02*
X1654670Y581938D01*
X1654808Y582135D01*
X1654945Y582333D01*
G01X1656500Y586742D02*
X1656639Y586938D01*
X1656777Y587135D01*
X1656914Y587333D01*
G01X1654531Y591742D02*
X1654670Y591938D01*
X1654808Y592135D01*
X1654945Y592333D01*
G01X1654531Y596742D02*
X1654670Y596938D01*
X1654808Y597135D01*
X1654945Y597333D01*
G01X1654531Y601742D02*
X1654670Y601938D01*
X1654808Y602135D01*
X1654945Y602333D01*
G01X1649203Y562726D02*
X1649476Y563317D01*
G01X1649203Y567726D02*
X1649476Y568317D01*
G01X1649203Y572726D02*
X1649476Y573317D01*
G01X1649203Y577726D02*
X1649476Y578317D01*
G01X1649203Y582726D02*
X1649476Y583317D01*
G01X1651172Y587726D02*
X1651444Y588317D01*
G01X1649203Y592726D02*
X1649476Y593317D01*
G01X1649203Y597726D02*
X1649476Y598317D01*
G01X1649203Y602726D02*
X1649476Y603317D01*
G01X1654809Y560777D02*
X1654775Y560678D01*
X1654687Y560608D01*
X1654561Y560581D01*
G01X1654809Y589124D02*
X1654775Y589025D01*
X1654687Y588954D01*
X1654561Y588927D01*
G01X1650328Y562726D02*
X1650405Y563317D01*
G01X1650328Y567726D02*
X1650405Y568317D01*
G01X1650328Y572726D02*
X1650405Y573317D01*
G01X1652296Y587726D02*
X1652374Y588317D01*
G01X1650328Y577726D02*
X1650405Y578317D01*
G01X1650328Y582726D02*
X1650405Y583317D01*
G01X1650328Y592726D02*
X1650405Y593317D01*
G01Y598317D02*
X1650328Y597726D01*
G01Y602726D02*
X1650405Y603317D01*
G01X1649887Y561171D02*
X1649897Y561270D01*
X1649925Y561342D01*
X1649964Y561368D01*
G01X1649887Y564321D02*
X1649897Y564419D01*
X1649925Y564491D01*
X1649964Y564518D01*
G01X1649887Y567470D02*
X1649897Y567569D01*
X1649925Y567641D01*
X1649964Y567667D01*
G01X1649887Y570620D02*
X1649897Y570718D01*
X1649925Y570790D01*
X1649964Y570817D01*
G01X1649887Y573770D02*
X1649897Y573868D01*
X1649925Y573940D01*
X1649964Y573966D01*
G01X1649887Y576919D02*
X1649897Y577018D01*
X1649925Y577090D01*
X1649964Y577116D01*
G01X1649887Y580069D02*
X1649897Y580167D01*
X1649925Y580239D01*
X1649964Y580266D01*
G01X1649887Y583218D02*
X1649897Y583317D01*
X1649925Y583389D01*
X1649964Y583415D01*
G01X1649887Y586368D02*
X1649897Y586466D01*
X1649925Y586538D01*
X1649964Y586565D01*
G01X1649887Y589518D02*
X1649897Y589616D01*
X1649925Y589688D01*
X1649964Y589714D01*
G01X1649887Y592667D02*
X1649897Y592766D01*
X1649925Y592838D01*
X1649964Y592864D01*
G01X1649887Y595817D02*
X1649897Y595915D01*
X1649925Y595987D01*
X1649964Y596014D01*
G01X1649887Y598966D02*
X1649897Y599065D01*
X1649925Y599137D01*
X1649964Y599163D01*
G01X1649887Y602116D02*
X1649897Y602214D01*
X1649925Y602286D01*
X1649964Y602313D01*
G01X1656914Y587726D02*
Y587333D01*
G01X1654945Y562726D02*
Y562333D01*
G01Y567726D02*
Y567333D01*
G01Y572726D02*
Y572333D01*
G01Y577726D02*
Y577333D01*
G01Y582726D02*
Y582333D01*
G01Y592726D02*
Y592333D01*
G01Y597726D02*
Y597333D01*
G01Y602726D02*
Y602333D01*
G01X1654809Y598573D02*
Y598966D01*
G01Y601722D02*
Y602116D01*
G01Y595423D02*
Y595817D01*
G01Y592274D02*
Y592667D01*
G01Y589124D02*
Y589518D01*
G01Y585974D02*
Y586368D01*
G01Y582825D02*
Y583218D01*
G01Y579675D02*
Y580069D01*
G01Y576525D02*
Y576919D01*
G01Y573376D02*
Y573770D01*
G01Y570226D02*
Y570620D01*
G01Y567077D02*
Y567470D01*
G01Y560777D02*
Y561171D01*
G01Y563927D02*
Y564321D01*
G01X1652296Y587726D02*
Y587333D01*
G01X1651172D02*
Y587726D01*
G01X1650328Y587333D02*
Y587726D01*
G01Y597333D02*
Y597726D01*
G01Y562726D02*
Y562333D01*
G01Y567726D02*
Y567333D01*
G01Y572726D02*
Y572333D01*
G01Y577726D02*
Y577333D01*
G01Y582726D02*
Y582333D01*
G01Y592726D02*
Y592333D01*
G01Y602726D02*
Y602333D01*
G01X1649887Y598573D02*
Y598966D01*
G01Y601722D02*
Y602116D01*
G01Y595423D02*
Y595817D01*
G01Y592274D02*
Y592667D01*
G01Y589124D02*
Y589518D01*
G01Y585974D02*
Y586368D01*
G01Y582825D02*
Y583218D01*
G01Y579675D02*
Y580069D01*
G01Y576525D02*
Y576919D01*
G01Y573376D02*
Y573770D01*
G01Y570226D02*
Y570620D01*
G01Y567077D02*
Y567470D01*
G01Y560777D02*
Y561171D01*
G01Y563927D02*
Y564321D01*
G01X1649374Y561171D02*
Y560777D01*
G01Y564321D02*
Y563927D01*
G01Y567470D02*
Y567077D01*
G01Y573770D02*
Y573376D01*
G01Y570620D02*
Y570226D01*
G01Y576919D02*
Y576525D01*
G01Y583218D02*
Y582825D01*
G01Y580069D02*
Y579675D01*
G01Y586368D02*
Y585974D01*
G01Y592667D02*
Y592274D01*
G01Y589518D02*
Y589124D01*
G01Y595817D02*
Y595423D01*
G01Y598966D02*
Y598573D01*
G01Y602116D02*
Y601722D01*
G01X1649203Y602333D02*
Y602726D01*
G01Y597333D02*
Y597726D01*
G01Y592333D02*
Y592726D01*
G01Y582333D02*
Y582726D01*
G01Y577333D02*
Y577726D01*
G01Y572333D02*
Y572726D01*
G01Y567333D02*
Y567726D01*
G01Y562333D02*
Y562726D01*
G01X1648359Y602333D02*
Y602726D01*
G01Y597333D02*
Y597726D01*
G01Y592333D02*
Y592726D01*
G01Y582333D02*
Y582726D01*
G01Y577333D02*
Y577726D01*
G01Y572333D02*
Y572726D01*
G01Y567333D02*
Y567726D01*
G01Y562333D02*
Y562726D01*
G01X1648197Y561171D02*
Y560777D01*
G01Y564321D02*
Y563927D01*
G01Y567470D02*
Y567077D01*
G01Y573770D02*
Y573376D01*
G01Y570620D02*
Y570226D01*
G01Y576919D02*
Y576525D01*
G01Y583218D02*
Y582825D01*
G01Y580069D02*
Y579675D01*
G01Y586368D02*
Y585974D01*
G01Y592667D02*
Y592274D01*
G01Y589518D02*
Y589124D01*
G01Y595817D02*
Y595423D01*
G01Y598966D02*
Y598573D01*
G01Y602116D02*
Y601722D01*
G01X1649374D02*
X1649377Y601684D01*
X1649385Y601647D01*
X1649397Y601613D01*
X1649415Y601583D01*
X1649436Y601559D01*
X1649459Y601541D01*
X1649485Y601529D01*
X1649513Y601525D01*
G01X1649374Y598573D02*
X1649377Y598535D01*
X1649385Y598498D01*
X1649397Y598464D01*
X1649415Y598434D01*
X1649436Y598409D01*
X1649459Y598391D01*
X1649485Y598380D01*
X1649513Y598376D01*
G01X1649374Y595423D02*
X1649377Y595385D01*
X1649385Y595348D01*
X1649397Y595314D01*
X1649415Y595284D01*
X1649436Y595260D01*
X1649459Y595241D01*
X1649485Y595230D01*
X1649513Y595226D01*
G01X1649374Y592274D02*
X1649377Y592235D01*
X1649385Y592199D01*
X1649397Y592165D01*
X1649415Y592134D01*
X1649436Y592110D01*
X1649459Y592092D01*
X1649485Y592081D01*
X1649513Y592077D01*
G01X1649374Y589124D02*
X1649377Y589086D01*
X1649385Y589049D01*
X1649397Y589015D01*
X1649415Y588985D01*
X1649436Y588960D01*
X1649459Y588942D01*
X1649485Y588931D01*
X1649513Y588927D01*
G01X1649374Y585974D02*
X1649377Y585936D01*
X1649385Y585899D01*
X1649397Y585865D01*
X1649415Y585835D01*
X1649436Y585811D01*
X1649459Y585793D01*
X1649485Y585781D01*
X1649513Y585777D01*
G01X1649374Y582825D02*
X1649377Y582786D01*
X1649385Y582750D01*
X1649397Y582716D01*
X1649415Y582686D01*
X1649436Y582661D01*
X1649459Y582643D01*
X1649485Y582632D01*
X1649513Y582628D01*
G01X1649374Y579675D02*
X1649377Y579637D01*
X1649385Y579600D01*
X1649397Y579566D01*
X1649415Y579536D01*
X1649436Y579512D01*
X1649459Y579493D01*
X1649485Y579482D01*
X1649513Y579478D01*
G01X1649374Y576525D02*
X1649377Y576487D01*
X1649385Y576450D01*
X1649397Y576417D01*
X1649415Y576386D01*
X1649436Y576362D01*
X1649459Y576344D01*
X1649485Y576333D01*
X1649513Y576329D01*
G01X1649374Y573376D02*
X1649377Y573338D01*
X1649385Y573301D01*
X1649397Y573267D01*
X1649415Y573237D01*
X1649436Y573212D01*
X1649459Y573194D01*
X1649485Y573183D01*
X1649513Y573179D01*
G01X1649374Y570226D02*
X1649377Y570188D01*
X1649385Y570151D01*
X1649397Y570117D01*
X1649415Y570087D01*
X1649436Y570063D01*
X1649459Y570045D01*
X1649485Y570033D01*
X1649513Y570029D01*
G01X1649374Y567077D02*
X1649377Y567038D01*
X1649385Y567002D01*
X1649397Y566968D01*
X1649415Y566937D01*
X1649436Y566913D01*
X1649459Y566895D01*
X1649485Y566884D01*
X1649513Y566880D01*
G01X1649374Y563927D02*
X1649377Y563889D01*
X1649385Y563852D01*
X1649397Y563818D01*
X1649415Y563788D01*
X1649436Y563763D01*
X1649459Y563745D01*
X1649485Y563734D01*
X1649513Y563730D01*
G01X1649374Y560777D02*
X1649377Y560739D01*
X1649385Y560702D01*
X1649397Y560669D01*
X1649415Y560638D01*
X1649436Y560614D01*
X1649459Y560596D01*
X1649485Y560585D01*
X1649513Y560581D01*
G01X1650328Y602333D02*
X1650405Y601742D01*
G01X1652296Y587333D02*
X1652374Y586742D01*
G01X1650405Y596742D02*
X1650328Y597333D01*
G01Y592333D02*
X1650405Y591742D01*
G01X1650328Y582333D02*
X1650405Y581742D01*
G01X1650328Y577333D02*
X1650405Y576742D01*
G01X1650328Y572333D02*
X1650405Y571742D01*
G01X1650328Y567333D02*
X1650405Y566742D01*
G01X1650328Y562333D02*
X1650405Y561742D01*
G01X1654809Y602116D02*
X1654777Y602213D01*
X1654689Y602285D01*
X1654561Y602313D01*
G01X1654809Y598966D02*
X1654777Y599063D01*
X1654689Y599136D01*
X1654561Y599163D01*
G01X1654809Y595817D02*
X1654777Y595914D01*
X1654689Y595986D01*
X1654561Y596014D01*
G01X1654809Y592667D02*
X1654777Y592764D01*
X1654689Y592836D01*
X1654561Y592864D01*
G01X1654809Y586368D02*
X1654777Y586465D01*
X1654689Y586537D01*
X1654561Y586565D01*
G01X1654809Y583218D02*
X1654777Y583315D01*
X1654689Y583388D01*
X1654561Y583415D01*
G01X1654809Y580069D02*
X1654777Y580166D01*
X1654689Y580238D01*
X1654561Y580266D01*
G01X1654809Y576919D02*
X1654777Y577016D01*
X1654689Y577088D01*
X1654561Y577116D01*
G01X1654809Y573770D02*
X1654777Y573867D01*
X1654689Y573939D01*
X1654561Y573966D01*
G01X1654809Y570620D02*
X1654777Y570717D01*
X1654689Y570789D01*
X1654561Y570817D01*
G01X1654809Y567470D02*
X1654777Y567567D01*
X1654689Y567640D01*
X1654561Y567667D01*
G01X1654809Y564321D02*
X1654777Y564418D01*
X1654689Y564490D01*
X1654561Y564518D01*
G01X1649476Y601742D02*
X1649203Y602333D01*
G01X1649476Y596742D02*
X1649203Y597333D01*
G01X1649476Y591742D02*
X1649203Y592333D01*
G01X1651444Y586742D02*
X1651172Y587333D01*
G01X1649476Y581742D02*
X1649203Y582333D01*
G01X1649476Y576742D02*
X1649203Y577333D01*
G01X1649476Y571742D02*
X1649203Y572333D01*
G01X1649476Y566742D02*
X1649203Y567333D01*
G01X1649476Y561742D02*
X1649203Y562333D01*
G01X1654561Y601525D02*
X1654689Y601553D01*
X1654777Y601626D01*
X1654809Y601722D01*
G01X1654561Y598376D02*
X1654689Y598404D01*
X1654777Y598477D01*
X1654809Y598573D01*
G01X1654561Y595226D02*
X1654689Y595254D01*
X1654777Y595327D01*
X1654809Y595423D01*
G01X1654561Y592077D02*
X1654689Y592104D01*
X1654777Y592177D01*
X1654809Y592274D01*
G01X1654561Y585777D02*
X1654689Y585805D01*
X1654777Y585878D01*
X1654809Y585974D01*
G01X1654561Y582628D02*
X1654689Y582656D01*
X1654777Y582728D01*
X1654809Y582825D01*
G01X1654561Y579478D02*
X1654689Y579506D01*
X1654777Y579579D01*
X1654809Y579675D01*
G01X1654561Y576329D02*
X1654689Y576356D01*
X1654777Y576429D01*
X1654809Y576525D01*
G01X1654945Y602726D02*
X1654808Y602924D01*
X1654670Y603121D01*
X1654531Y603317D01*
G01X1654945Y597726D02*
X1654808Y597924D01*
X1654670Y598121D01*
X1654531Y598317D01*
G01X1654945Y592726D02*
X1654808Y592924D01*
X1654670Y593121D01*
X1654531Y593317D01*
G01X1656914Y587726D02*
X1656777Y587924D01*
X1656639Y588121D01*
X1656500Y588317D01*
G01X1654945Y582726D02*
X1654808Y582924D01*
X1654670Y583121D01*
X1654531Y583317D01*
G01X1654945Y577726D02*
X1654808Y577924D01*
X1654670Y578121D01*
X1654531Y578317D01*
G01X1654945Y572726D02*
X1654808Y572924D01*
X1654670Y573121D01*
X1654531Y573317D01*
G01X1654945Y567726D02*
X1654808Y567924D01*
X1654670Y568121D01*
X1654531Y568317D01*
G01X1654945Y562726D02*
X1654808Y562924D01*
X1654670Y563121D01*
X1654531Y563317D01*
G01X1648786Y601742D02*
X1648359Y602333D01*
G01X1648786Y596742D02*
X1648359Y597333D01*
G01X1648786Y591742D02*
X1648359Y592333D01*
G01X1650754Y586742D02*
X1650328Y587333D01*
G01X1648786Y581742D02*
X1648359Y582333D01*
G01X1648786Y576742D02*
X1648359Y577333D01*
G01X1648786Y571742D02*
X1648359Y572333D01*
G01X1648786Y566742D02*
X1648359Y567333D01*
G01X1648786Y561742D02*
X1648359Y562333D01*
G01X1656827Y611270D02*
X1658795Y609301D01*
G01X1662079Y611270D02*
X1658795D01*
G01X1654531Y603317D02*
X1648786D01*
G01X1648359Y602726D02*
X1654945D01*
G01X1648359Y602333D02*
X1654945D01*
G01X1654561Y602313D02*
X1648477D01*
G01X1648197Y602116D02*
X1654809D01*
G01X1654531Y601742D02*
X1648786D01*
G01X1654809Y601722D02*
X1648197D01*
G01X1654561Y601525D02*
X1648477D01*
G01X1654561Y599163D02*
X1648477D01*
G01X1648197Y598966D02*
X1654809D01*
G01Y598573D02*
X1648197D01*
G01X1654561Y598376D02*
X1648477D01*
G01X1654531Y598317D02*
X1648786D01*
G01X1648359Y597726D02*
X1654945D01*
G01X1648359Y597333D02*
X1654945D01*
G01X1654531Y596742D02*
X1648786D01*
G01X1654561Y596014D02*
X1648477D01*
G01X1648197Y595817D02*
X1654809D01*
G01Y595423D02*
X1648197D01*
G01X1654561Y595226D02*
X1648477D01*
G01X1654531Y593317D02*
X1648786D01*
G01X1654561Y592864D02*
X1648477D01*
G01X1648359Y592726D02*
X1654945D01*
G01X1648197Y592667D02*
X1654809D01*
G01X1648359Y592333D02*
X1654945D01*
G01X1654809Y592274D02*
X1648197D01*
G01X1654561Y592077D02*
X1648477D01*
G01X1654531Y591742D02*
X1648786D01*
G01X1654561Y589714D02*
X1648477D01*
G01X1648197Y589518D02*
X1654809D01*
G01Y589124D02*
X1648197D01*
G01X1654561Y588927D02*
X1648477D01*
G01X1656500Y588317D02*
X1650754D01*
G01X1650328Y587726D02*
X1656914D01*
G01X1650328Y587333D02*
X1656914D01*
G01X1656500Y586742D02*
X1650754D01*
G01X1654561Y586565D02*
X1648477D01*
G01X1648197Y586368D02*
X1654809D01*
G01Y585974D02*
X1648197D01*
G01X1654561Y585777D02*
X1648477D01*
G01X1654561Y583415D02*
X1648477D01*
G01X1654531Y583317D02*
X1648786D01*
G01X1648197Y583218D02*
X1654809D01*
G01Y582825D02*
X1648197D01*
G01X1648359Y582726D02*
X1654945D01*
G01X1654561Y582628D02*
X1648477D01*
G01X1648359Y582333D02*
X1654945D01*
G01X1654531Y581742D02*
X1648786D01*
G01X1649513Y602313D02*
X1649486Y602309D01*
X1649460Y602298D01*
X1649436Y602280D01*
X1649415Y602255D01*
X1649397Y602226D01*
X1649385Y602192D01*
X1649377Y602155D01*
X1649374Y602116D01*
G01X1649513Y599163D02*
X1649486Y599160D01*
X1649460Y599148D01*
X1649436Y599130D01*
X1649415Y599106D01*
X1649397Y599076D01*
X1649385Y599042D01*
X1649377Y599005D01*
X1649374Y598966D01*
G01X1649513Y596014D02*
X1649486Y596010D01*
X1649460Y595999D01*
X1649436Y595981D01*
X1649415Y595956D01*
X1649397Y595926D01*
X1649385Y595892D01*
X1649377Y595856D01*
X1649374Y595817D01*
G01X1649513Y592864D02*
X1649486Y592860D01*
X1649460Y592849D01*
X1649436Y592831D01*
X1649415Y592806D01*
X1649397Y592777D01*
X1649385Y592743D01*
X1649377Y592706D01*
X1649374Y592667D01*
G01X1649513Y589714D02*
X1649486Y589711D01*
X1649460Y589700D01*
X1649436Y589682D01*
X1649415Y589657D01*
X1649397Y589627D01*
X1649385Y589593D01*
X1649377Y589557D01*
X1649374Y589518D01*
G01X1649513Y586565D02*
X1649486Y586561D01*
X1649460Y586550D01*
X1649436Y586532D01*
X1649415Y586507D01*
X1649397Y586478D01*
X1649385Y586444D01*
X1649377Y586407D01*
X1649374Y586368D01*
G01X1649513Y583415D02*
X1649486Y583412D01*
X1649460Y583400D01*
X1649436Y583382D01*
X1649415Y583358D01*
X1649397Y583328D01*
X1649385Y583294D01*
X1649377Y583257D01*
X1649374Y583218D01*
G01X1649513Y580266D02*
X1649486Y580262D01*
X1649460Y580251D01*
X1649436Y580233D01*
X1649415Y580208D01*
X1649397Y580178D01*
X1649385Y580144D01*
X1649377Y580108D01*
X1649374Y580069D01*
G01X1649513Y577116D02*
X1649486Y577112D01*
X1649460Y577101D01*
X1649436Y577083D01*
X1649415Y577058D01*
X1649397Y577029D01*
X1649385Y576995D01*
X1649377Y576958D01*
X1649374Y576919D01*
G01X1649513Y573966D02*
X1649486Y573963D01*
X1649460Y573952D01*
X1649436Y573934D01*
X1649415Y573909D01*
X1649397Y573879D01*
X1649385Y573845D01*
X1649377Y573809D01*
X1649374Y573770D01*
G01X1649513Y570817D02*
X1649486Y570813D01*
X1649460Y570802D01*
X1649436Y570784D01*
X1649415Y570759D01*
X1649397Y570729D01*
X1649385Y570696D01*
X1649377Y570659D01*
X1649374Y570620D01*
G01X1649513Y567667D02*
X1649486Y567663D01*
X1649460Y567652D01*
X1649436Y567634D01*
X1649415Y567610D01*
X1649397Y567580D01*
X1649385Y567546D01*
X1649377Y567509D01*
X1649374Y567470D01*
G01X1649513Y564518D02*
X1649486Y564514D01*
X1649460Y564503D01*
X1649436Y564485D01*
X1649415Y564460D01*
X1649397Y564430D01*
X1649385Y564396D01*
X1649377Y564360D01*
X1649374Y564321D01*
G01X1649513Y561368D02*
X1649486Y561364D01*
X1649460Y561353D01*
X1649436Y561335D01*
X1649415Y561310D01*
X1649397Y561281D01*
X1649385Y561247D01*
X1649377Y561210D01*
X1649374Y561171D01*
G01X1654561Y573179D02*
X1654689Y573207D01*
X1654777Y573280D01*
X1654809Y573376D01*
G01X1654561Y570029D02*
X1654689Y570057D01*
X1654777Y570130D01*
X1654809Y570226D01*
G01X1654561Y566880D02*
X1654689Y566908D01*
X1654777Y566980D01*
X1654809Y567077D01*
G01X1654561Y563730D02*
X1654689Y563758D01*
X1654777Y563831D01*
X1654809Y563927D01*
G01X1649964Y601525D02*
X1649925Y601552D01*
X1649897Y601624D01*
X1649887Y601722D01*
G01X1649964Y598376D02*
X1649925Y598402D01*
X1649897Y598474D01*
X1649887Y598573D01*
G01X1649964Y595226D02*
X1649925Y595253D01*
X1649897Y595325D01*
X1649887Y595423D01*
G01X1649964Y592077D02*
X1649925Y592103D01*
X1649897Y592175D01*
X1649887Y592274D01*
G01X1649964Y588927D02*
X1649925Y588953D01*
X1649897Y589026D01*
X1649887Y589124D01*
G01X1649964Y585777D02*
X1649925Y585804D01*
X1649897Y585876D01*
X1649887Y585974D01*
G01X1649964Y582628D02*
X1649925Y582654D01*
X1649897Y582726D01*
X1649887Y582825D01*
G01X1649964Y579478D02*
X1649925Y579505D01*
X1649897Y579577D01*
X1649887Y579675D01*
G01X1649964Y576329D02*
X1649925Y576355D01*
X1649897Y576427D01*
X1649887Y576525D01*
G01X1649964Y573179D02*
X1649925Y573205D01*
X1649897Y573278D01*
X1649887Y573376D01*
G01X1649964Y570029D02*
X1649925Y570056D01*
X1649897Y570128D01*
X1649887Y570226D01*
G01X1649964Y566880D02*
X1649925Y566906D01*
X1649897Y566978D01*
X1649887Y567077D01*
G01X1649964Y563730D02*
X1649925Y563757D01*
X1649897Y563829D01*
X1649887Y563927D01*
G01X1654561Y589714D02*
X1654688Y589687D01*
X1654777Y589614D01*
X1654809Y589518D01*
G01X1654561Y561368D02*
X1654688Y561341D01*
X1654777Y561268D01*
X1654809Y561171D01*
G01X1654561Y580266D02*
X1648477D01*
G01X1648197Y580069D02*
X1654809D01*
G01Y579675D02*
X1648197D01*
G01X1654561Y579478D02*
X1648477D01*
G01X1654531Y578317D02*
X1648786D01*
G01X1648359Y577726D02*
X1654945D01*
G01X1648359Y577333D02*
X1654945D01*
G01X1654561Y577116D02*
X1648477D01*
G01X1648197Y576919D02*
X1654809D01*
G01X1654531Y576742D02*
X1648786D01*
G01X1654809Y576525D02*
X1648197D01*
G01X1654561Y576329D02*
X1648477D01*
G01X1654561Y573966D02*
X1648477D01*
G01X1648197Y573770D02*
X1654809D01*
G01Y573376D02*
X1648197D01*
G01X1654531Y573317D02*
X1648786D01*
G01X1654561Y573179D02*
X1648477D01*
G01X1648359Y572726D02*
X1654945D01*
G01X1648359Y572333D02*
X1654945D01*
G01X1654531Y571742D02*
X1648786D01*
G01X1654561Y570817D02*
X1648477D01*
G01X1648197Y570620D02*
X1654809D01*
G01Y570226D02*
X1648197D01*
G01X1654561Y570029D02*
X1648477D01*
G01X1654531Y568317D02*
X1648786D01*
G01X1648359Y567726D02*
X1654945D01*
G01X1654561Y567667D02*
X1648477D01*
G01X1648197Y567470D02*
X1654809D01*
G01X1648359Y567333D02*
X1654945D01*
G01X1654809Y567077D02*
X1648197D01*
G01X1654561Y566880D02*
X1648477D01*
G01X1654531Y566742D02*
X1648786D01*
G01X1654561Y564518D02*
X1648477D01*
G01X1648197Y564321D02*
X1654809D01*
G01Y563927D02*
X1648197D01*
G01X1654561Y563730D02*
X1648477D01*
G01X1654531Y563317D02*
X1648786D01*
G01X1648359Y562726D02*
X1654945D01*
G01X1648359Y562333D02*
X1654945D01*
G01X1654531Y561742D02*
X1648786D01*
G01X1654561Y561368D02*
X1648477D01*
G01X1648197Y561171D02*
X1654809D01*
G01Y560777D02*
X1648197D01*
G01X1654561Y560581D02*
X1648477D01*
G01X1654531Y558317D02*
X1648786D01*
G01X1654561Y558218D02*
X1648477D01*
G01X1649964Y560581D02*
X1649925Y560607D01*
X1649897Y560679D01*
X1649887Y560777D01*
G01X1662079Y611270D02*
X1665488Y613238D01*
G01X1660822Y618886D02*
X1660768Y618509D01*
G01X1660821Y618884D02*
X1660858Y619208D01*
X1660852Y619449D01*
X1660795Y619585D01*
G01X1665488Y613238D02*
Y614970D01*
G01X1660764Y611270D02*
Y618435D01*
G01X1660795Y619585D02*
X1660853Y619445D01*
X1660858Y619205D01*
G01X1665488Y614970D02*
X1660764Y619616D01*
G01X1660768Y618509D02*
X1665488Y613867D01*
G01X1643736Y826959D02*
Y806880D01*
G01X1639799Y813573D02*
Y812588D01*
G01Y816132D02*
Y815148D01*
G01Y818691D02*
Y817707D01*
G01Y821250D02*
Y820266D01*
G01X1649964Y884990D02*
X1649925Y884964D01*
X1649897Y884892D01*
X1649887Y884793D01*
G01X1649964Y894439D02*
X1649925Y894412D01*
X1649897Y894340D01*
X1649887Y894242D01*
G01X1649964Y897588D02*
X1649925Y897562D01*
X1649897Y897490D01*
X1649887Y897392D01*
G01X1649964Y900738D02*
X1649925Y900712D01*
X1649897Y900640D01*
X1649887Y900541D01*
G01X1649964Y910187D02*
X1649925Y910160D01*
X1649897Y910088D01*
X1649887Y909990D01*
G01X1649964Y913337D02*
X1649925Y913310D01*
X1649897Y913238D01*
X1649887Y913140D01*
G01X1658795Y876270D02*
X1656827Y874301D01*
G01X1648786Y883829D02*
X1648359Y883238D01*
G01X1648786Y888829D02*
X1648359Y888238D01*
G01X1648786Y893829D02*
X1648359Y893238D01*
G01X1648786Y898829D02*
X1648359Y898238D01*
G01X1648786Y903829D02*
X1648359Y903238D01*
G01X1648786Y908829D02*
X1648359Y908238D01*
G01X1648718Y913829D02*
X1648294Y913238D01*
G01X1654531Y882254D02*
X1654670Y882450D01*
X1654808Y882647D01*
X1654945Y882844D01*
G01X1654531Y887254D02*
X1654670Y887450D01*
X1654808Y887647D01*
X1654945Y887844D01*
G01X1654531Y892254D02*
X1654670Y892450D01*
X1654808Y892647D01*
X1654945Y892844D01*
G01X1654531Y897254D02*
X1654670Y897450D01*
X1654808Y897647D01*
X1654945Y897844D01*
G01X1654531Y902254D02*
X1654670Y902450D01*
X1654808Y902647D01*
X1654945Y902844D01*
G01X1654531Y907254D02*
X1654670Y907450D01*
X1654808Y907647D01*
X1654945Y907844D01*
G01X1654631Y912254D02*
X1654767Y912450D01*
X1654902Y912647D01*
X1655036Y912844D01*
G01X1649203Y883238D02*
X1649476Y883829D01*
G01X1649203Y888238D02*
X1649476Y888829D01*
G01X1649203Y893238D02*
X1649476Y893829D01*
G01X1649203Y898238D02*
X1649476Y898829D01*
G01X1649203Y903238D02*
X1649476Y903829D01*
G01X1649203Y908238D02*
X1649476Y908829D01*
G01X1649203Y913238D02*
X1649476Y913829D01*
G01X1649513Y919636D02*
X1649486Y919632D01*
X1649460Y919621D01*
X1649436Y919603D01*
X1649415Y919578D01*
X1649397Y919548D01*
X1649385Y919515D01*
X1649377Y919478D01*
X1649374Y919439D01*
G01X1654571Y920130D02*
X1654698Y920157D01*
X1654787Y920230D01*
X1654819Y920327D01*
G01X1654571Y916980D02*
X1654698Y917008D01*
X1654787Y917080D01*
X1654819Y917177D01*
G01X1654561Y918848D02*
X1654689Y918876D01*
X1654777Y918949D01*
X1654809Y919045D01*
G01X1654561Y915699D02*
X1654689Y915726D01*
X1654777Y915799D01*
X1654809Y915896D01*
G01X1654561Y912549D02*
X1654689Y912577D01*
X1654777Y912650D01*
X1654809Y912746D01*
G01X1654561Y909400D02*
X1654689Y909427D01*
X1654777Y909500D01*
X1654809Y909596D01*
G01X1654561Y906250D02*
X1654689Y906278D01*
X1654777Y906351D01*
X1654809Y906447D01*
G01X1654561Y903100D02*
X1654689Y903128D01*
X1654777Y903201D01*
X1654809Y903297D01*
G01X1654561Y899951D02*
X1654689Y899978D01*
X1654777Y900051D01*
X1654809Y900148D01*
G01X1654561Y896801D02*
X1654689Y896829D01*
X1654777Y896902D01*
X1654809Y896998D01*
G01X1654561Y893651D02*
X1654689Y893679D01*
X1654777Y893752D01*
X1654809Y893848D01*
G01X1650328Y883238D02*
X1650405Y883829D01*
G01X1650328Y888238D02*
X1650405Y888829D01*
G01X1650328Y893238D02*
X1650405Y893829D01*
G01X1650328Y898238D02*
X1650405Y898829D01*
G01X1650328Y903238D02*
X1650405Y903829D01*
G01X1650328Y908238D02*
X1650405Y908829D01*
G01X1650328Y913238D02*
X1650405Y913829D01*
G01X1649887Y887943D02*
X1649897Y888041D01*
X1649925Y888113D01*
X1649964Y888140D01*
G01X1649887Y891092D02*
X1649897Y891191D01*
X1649925Y891263D01*
X1649964Y891289D01*
G01X1649887Y903691D02*
X1649897Y903789D01*
X1649925Y903861D01*
X1649964Y903888D01*
G01X1649887Y906840D02*
X1649897Y906939D01*
X1649925Y907011D01*
X1649964Y907037D01*
G01X1649887Y916289D02*
X1649897Y916388D01*
X1649925Y916460D01*
X1649964Y916486D01*
G01X1649887Y919439D02*
X1649897Y919537D01*
X1649925Y919609D01*
X1649964Y919636D01*
G01X1649443Y918162D02*
X1649445Y918200D01*
X1649454Y918237D01*
X1649467Y918270D01*
X1649486Y918301D01*
X1649508Y918325D01*
X1649534Y918343D01*
X1649561Y918354D01*
X1649590Y918358D01*
G01X1650328Y912844D02*
X1650405Y912254D01*
G01X1650328Y907844D02*
X1650405Y907254D01*
G01X1650328Y902844D02*
X1650405Y902254D01*
G01X1650328Y897844D02*
X1650405Y897254D01*
G01X1650328Y892844D02*
X1650405Y892254D01*
G01X1650328Y887844D02*
X1650405Y887254D01*
G01X1650328Y882844D02*
X1650405Y882254D01*
G01X1648501Y920327D02*
X1654819D01*
G01X1648763Y920130D02*
X1654571D01*
G01X1654561Y919636D02*
X1648477D01*
G01X1648197Y919439D02*
X1654809D01*
G01Y919045D02*
X1648197D01*
G01X1654561Y918848D02*
X1648477D01*
G01X1648763Y918358D02*
X1654571D01*
G01X1654819Y918162D02*
X1648501D01*
G01Y917177D02*
X1654819D01*
G01X1648763Y916980D02*
X1654571D01*
G01X1654561Y916486D02*
X1648477D01*
G01X1648197Y916289D02*
X1654809D01*
G01Y915896D02*
X1648197D01*
G01X1654561Y915699D02*
X1648477D01*
G01X1658795Y914616D02*
X1652326D01*
G01X1654631Y913829D02*
X1648718D01*
G01X1654561Y913337D02*
X1648477D01*
G01X1648294Y913238D02*
X1655036D01*
G01X1648197Y913140D02*
X1654809D01*
G01X1648294Y912844D02*
X1655036D01*
G01X1654809Y912746D02*
X1648197D01*
G01X1654561Y912549D02*
X1648477D01*
G01X1654631Y912254D02*
X1648718D01*
G01X1654561Y910187D02*
X1648477D01*
G01X1648197Y909990D02*
X1654809D01*
G01Y909596D02*
X1648197D01*
G01X1654561Y909400D02*
X1648477D01*
G01X1654531Y908829D02*
X1648786D01*
G01X1648359Y908238D02*
X1654945D01*
G01X1648359Y907844D02*
X1654945D01*
G01X1654531Y907254D02*
X1648786D01*
G01X1654561Y907037D02*
X1648477D01*
G01X1648197Y906840D02*
X1654809D01*
G01Y906447D02*
X1648197D01*
G01X1654561Y906250D02*
X1648477D01*
G01X1654561Y903888D02*
X1648477D01*
G01X1654531Y903829D02*
X1648786D01*
G01X1648197Y903691D02*
X1654809D01*
G01Y903297D02*
X1648197D01*
G01X1648359Y903238D02*
X1654945D01*
G01X1654561Y903100D02*
X1648477D01*
G01X1648359Y902844D02*
X1654945D01*
G01X1654531Y902254D02*
X1648786D01*
G01X1654561Y900738D02*
X1648477D01*
G01X1648197Y900541D02*
X1654809D01*
G01Y900148D02*
X1648197D01*
G01X1654561Y899951D02*
X1648477D01*
G01X1654531Y898829D02*
X1648786D01*
G01X1648359Y898238D02*
X1654945D01*
G01X1648359Y897844D02*
X1654945D01*
G01X1654561Y897588D02*
X1648477D01*
G01X1648197Y897392D02*
X1654809D01*
G01X1654531Y897254D02*
X1648786D01*
G01X1654809Y896998D02*
X1648197D01*
G01X1654561Y896801D02*
X1648477D01*
G01X1654561Y894439D02*
X1648477D01*
G01X1648197Y894242D02*
X1654809D01*
G01Y893848D02*
X1648197D01*
G01X1654531Y893829D02*
X1648786D01*
G01X1654561Y893651D02*
X1648477D01*
G01X1648359Y893238D02*
X1654945D01*
G01X1648359Y892844D02*
X1654945D01*
G01X1654531Y892254D02*
X1648786D01*
G01X1654561Y891289D02*
X1648477D01*
G01X1648197Y891092D02*
X1654809D01*
G01Y890699D02*
X1648197D01*
G01X1654561Y890502D02*
X1648477D01*
G01X1649513Y916486D02*
X1649486Y916482D01*
X1649460Y916471D01*
X1649436Y916453D01*
X1649415Y916428D01*
X1649397Y916399D01*
X1649385Y916365D01*
X1649377Y916328D01*
X1649374Y916289D01*
G01X1649513Y913337D02*
X1649486Y913333D01*
X1649460Y913322D01*
X1649436Y913304D01*
X1649415Y913279D01*
X1649397Y913249D01*
X1649385Y913215D01*
X1649377Y913179D01*
X1649374Y913140D01*
G01X1649513Y910187D02*
X1649486Y910183D01*
X1649460Y910172D01*
X1649436Y910154D01*
X1649415Y910129D01*
X1649397Y910100D01*
X1649385Y910066D01*
X1649377Y910029D01*
X1649374Y909990D01*
G01X1649513Y907037D02*
X1649486Y907034D01*
X1649460Y907022D01*
X1649436Y907004D01*
X1649415Y906980D01*
X1649397Y906950D01*
X1649385Y906916D01*
X1649377Y906879D01*
X1649374Y906840D01*
G01X1649513Y903888D02*
X1649486Y903884D01*
X1649460Y903873D01*
X1649436Y903855D01*
X1649415Y903830D01*
X1649397Y903800D01*
X1649385Y903767D01*
X1649377Y903730D01*
X1649374Y903691D01*
G01X1649513Y900738D02*
X1649486Y900734D01*
X1649460Y900723D01*
X1649436Y900705D01*
X1649415Y900680D01*
X1649397Y900651D01*
X1649385Y900617D01*
X1649377Y900580D01*
X1649374Y900541D01*
G01X1649513Y897588D02*
X1649486Y897585D01*
X1649460Y897574D01*
X1649436Y897556D01*
X1649415Y897531D01*
X1649397Y897501D01*
X1649385Y897467D01*
X1649377Y897431D01*
X1649374Y897392D01*
G01X1649513Y894439D02*
X1649486Y894435D01*
X1649460Y894424D01*
X1649436Y894406D01*
X1649415Y894381D01*
X1649397Y894352D01*
X1649385Y894318D01*
X1649377Y894281D01*
X1649374Y894242D01*
G01X1649513Y891289D02*
X1649486Y891286D01*
X1649460Y891274D01*
X1649436Y891256D01*
X1649415Y891232D01*
X1649397Y891202D01*
X1649385Y891168D01*
X1649377Y891131D01*
X1649374Y891092D01*
G01X1649513Y888140D02*
X1649486Y888136D01*
X1649460Y888125D01*
X1649436Y888107D01*
X1649415Y888082D01*
X1649397Y888052D01*
X1649385Y888018D01*
X1649377Y887982D01*
X1649374Y887943D01*
G01X1649513Y884990D02*
X1649486Y884986D01*
X1649460Y884975D01*
X1649436Y884957D01*
X1649415Y884932D01*
X1649397Y884903D01*
X1649385Y884869D01*
X1649377Y884832D01*
X1649374Y884793D01*
G01X1654561Y890502D02*
X1654689Y890530D01*
X1654777Y890603D01*
X1654809Y890699D01*
G01X1654561Y887352D02*
X1654689Y887380D01*
X1654777Y887453D01*
X1654809Y887549D01*
G01X1654561Y884203D02*
X1654689Y884230D01*
X1654777Y884303D01*
X1654809Y884400D01*
G01X1650595Y918162D02*
Y918200D01*
X1650597Y918237D01*
X1650600Y918270D01*
X1650604Y918301D01*
X1650609Y918325D01*
X1650615Y918343D01*
X1650621Y918354D01*
X1650627Y918358D01*
G01X1658795Y874301D02*
Y1016781D01*
G01X1657784Y914820D02*
Y909439D01*
G01X1657673Y1012254D02*
Y878829D01*
G01X1657614Y914616D02*
Y936466D01*
G01Y909439D02*
Y878435D01*
G01X1656827Y879222D02*
Y1011860D01*
G01X1655036Y913238D02*
Y912844D01*
G01X1654945Y883238D02*
Y882844D01*
G01Y888238D02*
Y887844D01*
G01Y893238D02*
Y892844D01*
G01Y898238D02*
Y897844D01*
G01Y903238D02*
Y902844D01*
G01Y908238D02*
Y907844D01*
G01X1654819Y918162D02*
Y917177D01*
G01Y921311D02*
Y920327D01*
G01X1654809Y919045D02*
Y919439D01*
G01Y912746D02*
Y913140D01*
G01Y915896D02*
Y916289D01*
G01Y909596D02*
Y909990D01*
G01Y906447D02*
Y906840D01*
G01Y903297D02*
Y903691D01*
G01Y900148D02*
Y900541D01*
G01Y896998D02*
Y897392D01*
G01Y893848D02*
Y894242D01*
G01Y890699D02*
Y891092D01*
G01Y884400D02*
Y884793D01*
G01Y887549D02*
Y887943D01*
G01X1652326Y915797D02*
Y914616D01*
G01X1650595Y920327D02*
Y921311D01*
G01Y917177D02*
Y918162D01*
G01X1650328Y883238D02*
Y882844D01*
G01Y888238D02*
Y887844D01*
G01Y893238D02*
Y892844D01*
G01Y898238D02*
Y897844D01*
G01Y903238D02*
Y902844D01*
G01Y908238D02*
Y907844D01*
G01Y913238D02*
Y912844D01*
G01X1649887Y919045D02*
Y919439D01*
G01Y912746D02*
Y913140D01*
G01Y915896D02*
Y916289D01*
G01Y909596D02*
Y909990D01*
G01Y906447D02*
Y906840D01*
G01Y903297D02*
Y903691D01*
G01Y900148D02*
Y900541D01*
G01Y896998D02*
Y897392D01*
G01Y893848D02*
Y894242D01*
G01Y890699D02*
Y891092D01*
G01Y884400D02*
Y884793D01*
G01Y887549D02*
Y887943D01*
G01X1649443Y920327D02*
Y921311D01*
G01Y917177D02*
Y918162D01*
G01X1649374Y884793D02*
Y884400D01*
G01Y887943D02*
Y887549D01*
G01Y891092D02*
Y890699D01*
G01Y897392D02*
Y896998D01*
G01Y894242D02*
Y893848D01*
G01Y900541D02*
Y900148D01*
G01Y906840D02*
Y906447D01*
G01Y903691D02*
Y903297D01*
G01Y909990D02*
Y909596D01*
G01Y913140D02*
Y912746D01*
G01Y916289D02*
Y915896D01*
G01Y919439D02*
Y919045D01*
G01X1649203Y912844D02*
Y913238D01*
G01Y907844D02*
Y908238D01*
G01Y902844D02*
Y903238D01*
G01Y897844D02*
Y898238D01*
G01Y892844D02*
Y893238D01*
G01Y887844D02*
Y888238D01*
G01Y882844D02*
Y883238D01*
G01X1648501Y920327D02*
Y921311D01*
G01Y917177D02*
Y918162D01*
G01X1648359Y907844D02*
Y908238D01*
G01Y902844D02*
Y903238D01*
G01Y897844D02*
Y898238D01*
G01Y892844D02*
Y893238D01*
G01Y887844D02*
Y888238D01*
G01Y882844D02*
Y883238D01*
G01X1648294Y912844D02*
Y913238D01*
G01X1648197Y884793D02*
Y884400D01*
G01Y887943D02*
Y887549D01*
G01Y891092D02*
Y890699D01*
G01Y897392D02*
Y896998D01*
G01Y894242D02*
Y893848D01*
G01Y900541D02*
Y900148D01*
G01Y906840D02*
Y906447D01*
G01Y903691D02*
Y903297D01*
G01Y909990D02*
Y909596D01*
G01Y913140D02*
Y912746D01*
G01Y916289D02*
Y915896D01*
G01Y919439D02*
Y919045D01*
G01X1649374D02*
X1649377Y919007D01*
X1649385Y918970D01*
X1649397Y918936D01*
X1649415Y918906D01*
X1649436Y918882D01*
X1649459Y918863D01*
X1649485Y918852D01*
X1649513Y918848D01*
G01X1649374Y915896D02*
X1649377Y915857D01*
X1649385Y915821D01*
X1649397Y915787D01*
X1649415Y915756D01*
X1649436Y915732D01*
X1649459Y915714D01*
X1649485Y915703D01*
X1649513Y915699D01*
G01X1649374Y912746D02*
X1649377Y912708D01*
X1649385Y912671D01*
X1649397Y912637D01*
X1649415Y912607D01*
X1649436Y912582D01*
X1649459Y912564D01*
X1649485Y912553D01*
X1649513Y912549D01*
G01X1649374Y909596D02*
X1649377Y909558D01*
X1649385Y909521D01*
X1649397Y909487D01*
X1649415Y909457D01*
X1649436Y909433D01*
X1649459Y909415D01*
X1649485Y909403D01*
X1649513Y909400D01*
G01X1649374Y906447D02*
X1649377Y906409D01*
X1649385Y906372D01*
X1649397Y906338D01*
X1649415Y906308D01*
X1649436Y906283D01*
X1649459Y906265D01*
X1649485Y906254D01*
X1649513Y906250D01*
G01X1649374Y903297D02*
X1649377Y903259D01*
X1649385Y903222D01*
X1649397Y903188D01*
X1649415Y903158D01*
X1649436Y903134D01*
X1649459Y903115D01*
X1649485Y903104D01*
X1649513Y903100D01*
G01X1649374Y900148D02*
X1649377Y900109D01*
X1649385Y900073D01*
X1649397Y900039D01*
X1649415Y900008D01*
X1649436Y899984D01*
X1649459Y899966D01*
X1649485Y899955D01*
X1649513Y899951D01*
G01X1649374Y896998D02*
X1649377Y896960D01*
X1649385Y896923D01*
X1649397Y896889D01*
X1649415Y896859D01*
X1649436Y896834D01*
X1649459Y896816D01*
X1649485Y896805D01*
X1649513Y896801D01*
G01X1649374Y893848D02*
X1649377Y893810D01*
X1649385Y893773D01*
X1649397Y893739D01*
X1649415Y893709D01*
X1649436Y893685D01*
X1649459Y893667D01*
X1649485Y893655D01*
X1649513Y893651D01*
G01X1649374Y890699D02*
X1649377Y890660D01*
X1649385Y890624D01*
X1649397Y890590D01*
X1649415Y890560D01*
X1649436Y890535D01*
X1649459Y890517D01*
X1649485Y890506D01*
X1649513Y890502D01*
G01X1649374Y887549D02*
X1649377Y887511D01*
X1649385Y887474D01*
X1649397Y887440D01*
X1649415Y887410D01*
X1649436Y887386D01*
X1649459Y887367D01*
X1649485Y887356D01*
X1649513Y887352D01*
G01X1649374Y884400D02*
X1649377Y884361D01*
X1649385Y884325D01*
X1649397Y884291D01*
X1649415Y884260D01*
X1649436Y884236D01*
X1649459Y884218D01*
X1649485Y884207D01*
X1649513Y884203D01*
G01X1654809Y919439D02*
X1654777Y919536D01*
X1654689Y919608D01*
X1654561Y919636D01*
G01X1654809Y916289D02*
X1654777Y916386D01*
X1654689Y916458D01*
X1654561Y916486D01*
G01X1654809Y913140D02*
X1654777Y913237D01*
X1654689Y913309D01*
X1654561Y913337D01*
G01X1654809Y909990D02*
X1654777Y910087D01*
X1654689Y910159D01*
X1654561Y910187D01*
G01X1654809Y906840D02*
X1654777Y906937D01*
X1654689Y907010D01*
X1654561Y907037D01*
G01X1654809Y903691D02*
X1654777Y903788D01*
X1654689Y903860D01*
X1654561Y903888D01*
G01X1654809Y900541D02*
X1654777Y900638D01*
X1654689Y900710D01*
X1654561Y900738D01*
G01X1654809Y897392D02*
X1654777Y897489D01*
X1654689Y897561D01*
X1654561Y897588D01*
G01X1654809Y894242D02*
X1654777Y894339D01*
X1654689Y894411D01*
X1654561Y894439D01*
G01X1654809Y891092D02*
X1654777Y891189D01*
X1654689Y891262D01*
X1654561Y891289D01*
G01X1654809Y887943D02*
X1654777Y888040D01*
X1654689Y888112D01*
X1654561Y888140D01*
G01X1654809Y884793D02*
X1654777Y884890D01*
X1654689Y884962D01*
X1654561Y884990D01*
G01X1654819Y918162D02*
X1654785Y918261D01*
X1654697Y918331D01*
X1654571Y918358D01*
G01X1649476Y912254D02*
X1649203Y912844D01*
G01X1649476Y907254D02*
X1649203Y907844D01*
G01X1649476Y902254D02*
X1649203Y902844D01*
G01X1649476Y897254D02*
X1649203Y897844D01*
G01X1649476Y892254D02*
X1649203Y892844D01*
G01X1649476Y887254D02*
X1649203Y887844D01*
G01X1649476Y882254D02*
X1649203Y882844D01*
G01X1649590Y920130D02*
X1649562Y920134D01*
X1649534Y920145D01*
X1649509Y920163D01*
X1649486Y920188D01*
X1649468Y920217D01*
X1649454Y920251D01*
X1649446Y920288D01*
X1649443Y920327D01*
G01X1649590Y916980D02*
X1649562Y916984D01*
X1649534Y916995D01*
X1649509Y917013D01*
X1649486Y917038D01*
X1649468Y917068D01*
X1649454Y917102D01*
X1649446Y917138D01*
X1649443Y917177D01*
G01X1654531Y888829D02*
X1648786D01*
G01X1648359Y888238D02*
X1654945D01*
G01X1654561Y888140D02*
X1648477D01*
G01X1648197Y887943D02*
X1654809D01*
G01X1648359Y887844D02*
X1654945D01*
G01X1654809Y887549D02*
X1648197D01*
G01X1654561Y887352D02*
X1648477D01*
G01X1654531Y887254D02*
X1648786D01*
G01X1654561Y884990D02*
X1648477D01*
G01X1648197Y884793D02*
X1654809D01*
G01Y884400D02*
X1648197D01*
G01X1654561Y884203D02*
X1648477D01*
G01X1654531Y883829D02*
X1648786D01*
G01X1648359Y883238D02*
X1654945D01*
G01X1648359Y882844D02*
X1654945D01*
G01X1654531Y882254D02*
X1648786D01*
G01X1662079Y874301D02*
X1658795D01*
G01X1655036Y913238D02*
X1654902Y913436D01*
X1654767Y913633D01*
X1654631Y913829D01*
G01X1654945Y908238D02*
X1654808Y908436D01*
X1654670Y908633D01*
X1654531Y908829D01*
G01X1654945Y903238D02*
X1654808Y903436D01*
X1654670Y903633D01*
X1654531Y903829D01*
G01X1654945Y898238D02*
X1654808Y898436D01*
X1654670Y898633D01*
X1654531Y898829D01*
G01X1654945Y893238D02*
X1654808Y893436D01*
X1654670Y893633D01*
X1654531Y893829D01*
G01X1654945Y888238D02*
X1654808Y888436D01*
X1654670Y888633D01*
X1654531Y888829D01*
G01X1654945Y883238D02*
X1654808Y883436D01*
X1654670Y883633D01*
X1654531Y883829D01*
G01X1648718Y912254D02*
X1648294Y912844D01*
G01X1648786Y907254D02*
X1648359Y907844D01*
G01X1648786Y902254D02*
X1648359Y902844D01*
G01X1648786Y897254D02*
X1648359Y897844D01*
G01X1648786Y892254D02*
X1648359Y892844D01*
G01X1648786Y887254D02*
X1648359Y887844D01*
G01X1648786Y882254D02*
X1648359Y882844D01*
G01X1656827Y915777D02*
X1658795Y913809D01*
G01Y877254D02*
X1656827Y879222D01*
G01X1649964Y918848D02*
X1649925Y918875D01*
X1649897Y918947D01*
X1649887Y919045D01*
G01X1649964Y915699D02*
X1649925Y915725D01*
X1649897Y915797D01*
X1649887Y915896D01*
G01X1649964Y912549D02*
X1649925Y912576D01*
X1649897Y912648D01*
X1649887Y912746D01*
G01X1649964Y909400D02*
X1649925Y909426D01*
X1649897Y909498D01*
X1649887Y909596D01*
G01X1649964Y906250D02*
X1649925Y906276D01*
X1649897Y906348D01*
X1649887Y906447D01*
G01X1649964Y903100D02*
X1649925Y903127D01*
X1649897Y903199D01*
X1649887Y903297D01*
G01X1649964Y899951D02*
X1649925Y899977D01*
X1649897Y900049D01*
X1649887Y900148D01*
G01X1649964Y896801D02*
X1649925Y896827D01*
X1649897Y896900D01*
X1649887Y896998D01*
G01X1649964Y893651D02*
X1649925Y893678D01*
X1649897Y893750D01*
X1649887Y893848D01*
G01X1649964Y890502D02*
X1649925Y890528D01*
X1649897Y890600D01*
X1649887Y890699D01*
G01X1649964Y887352D02*
X1649925Y887379D01*
X1649897Y887451D01*
X1649887Y887549D01*
G01X1649964Y884203D02*
X1649925Y884229D01*
X1649897Y884301D01*
X1649887Y884400D01*
G01X1650627Y920130D02*
X1650621Y920134D01*
X1650615Y920145D01*
X1650609Y920163D01*
X1650604Y920188D01*
X1650600Y920217D01*
X1650597Y920251D01*
X1650595Y920288D01*
Y920327D01*
G01X1650627Y916980D02*
X1650621Y916984D01*
X1650615Y916995D01*
X1650609Y917013D01*
X1650604Y917038D01*
X1650600Y917068D01*
X1650597Y917102D01*
X1650595Y917138D01*
Y917177D01*
G01X1665488Y870600D02*
X1660764Y865955D01*
G01X1665488Y871704D02*
X1660768Y867062D01*
G01X1660795Y865986D02*
X1660852Y866120D01*
X1660858Y866356D01*
X1660822Y866685D01*
G01X1660795Y865986D02*
X1660853Y866126D01*
X1660858Y866366D01*
G01X1660823Y866677D02*
X1660768Y867062D01*
G01X1665488Y872333D02*
Y870600D01*
G01X1660764Y867136D02*
Y874301D01*
G01X1662079D02*
X1665488Y872333D01*
G01X1654561Y921998D02*
X1654689Y922026D01*
X1654777Y922099D01*
X1654809Y922195D01*
G01X1649443Y921311D02*
X1649445Y921349D01*
X1649454Y921386D01*
X1649467Y921420D01*
X1649486Y921450D01*
X1649508Y921475D01*
X1649534Y921493D01*
X1649561Y921504D01*
X1649590Y921508D01*
G01X1654809Y922195D02*
X1648197D01*
G01X1654561Y921998D02*
X1648477D01*
G01X1648763Y921508D02*
X1654571D01*
G01X1654819Y921311D02*
X1648501D01*
G01X1650595D02*
Y921349D01*
X1650597Y921386D01*
X1650600Y921420D01*
X1650604Y921450D01*
X1650609Y921475D01*
X1650615Y921493D01*
X1650621Y921504D01*
X1650627Y921508D01*
G01X1654809Y922195D02*
Y922588D01*
G01X1649887Y922195D02*
Y922588D01*
G01X1649374D02*
Y922195D01*
G01X1648197Y922588D02*
Y922195D01*
G01X1649374D02*
X1649377Y922157D01*
X1649385Y922120D01*
X1649397Y922086D01*
X1649415Y922056D01*
X1649436Y922031D01*
X1649459Y922013D01*
X1649485Y922002D01*
X1649513Y921998D01*
G01X1654819Y921311D02*
X1654785Y921410D01*
X1654697Y921481D01*
X1654571Y921508D01*
G01X1649964Y921998D02*
X1649925Y922024D01*
X1649897Y922096D01*
X1649887Y922195D01*
G01X1649964Y929085D02*
X1649925Y929058D01*
X1649897Y928986D01*
X1649887Y928888D01*
G01X1658795Y937274D02*
X1656827Y935305D01*
G01X1648786Y943829D02*
X1648359Y943238D01*
G01X1648786Y948829D02*
X1648359Y948238D01*
G01X1650754Y953829D02*
X1650328Y953238D01*
G01X1648786Y958829D02*
X1648359Y958238D01*
G01X1648786Y963829D02*
X1648359Y963238D01*
G01X1648786Y968829D02*
X1648359Y968238D01*
G01X1648786Y973829D02*
X1648359Y973238D01*
G01X1648786Y978829D02*
X1648359Y978238D01*
G01X1648786Y983829D02*
X1648359Y983238D01*
G01X1648786Y988829D02*
X1648359Y988238D01*
G01X1650754Y993829D02*
X1650328Y993238D01*
G01X1648718Y938829D02*
X1648294Y938238D01*
G01X1654531Y942254D02*
X1654670Y942450D01*
X1654808Y942647D01*
X1654945Y942844D01*
G01X1654531Y947254D02*
X1654670Y947450D01*
X1654808Y947647D01*
X1654945Y947844D01*
G01X1656500Y952254D02*
X1656639Y952450D01*
X1656777Y952647D01*
X1656914Y952844D01*
G01X1654531Y957254D02*
X1654670Y957450D01*
X1654808Y957647D01*
X1654945Y957844D01*
G01X1654531Y962254D02*
X1654670Y962450D01*
X1654808Y962647D01*
X1654945Y962844D01*
G01X1654531Y967254D02*
X1654670Y967450D01*
X1654808Y967647D01*
X1654945Y967844D01*
G01X1654531Y972254D02*
X1654670Y972450D01*
X1654808Y972647D01*
X1654945Y972844D01*
G01X1654531Y977254D02*
X1654670Y977450D01*
X1654808Y977647D01*
X1654945Y977844D01*
G01X1654531Y982254D02*
X1654670Y982450D01*
X1654808Y982647D01*
X1654945Y982844D01*
G01X1654531Y987254D02*
X1654670Y987450D01*
X1654808Y987647D01*
X1654945Y987844D01*
G01X1656500Y992254D02*
X1656639Y992450D01*
X1656777Y992647D01*
X1656914Y992844D01*
G01X1654631Y937254D02*
X1654767Y937450D01*
X1654902Y937647D01*
X1655036Y937844D01*
G01X1654561Y991289D02*
X1654689Y991317D01*
X1654777Y991390D01*
X1654809Y991486D01*
G01X1654561Y988140D02*
X1654689Y988167D01*
X1654777Y988240D01*
X1654809Y988337D01*
G01X1654561Y984990D02*
X1654689Y985018D01*
X1654777Y985091D01*
X1654809Y985187D01*
G01X1654561Y981840D02*
X1654689Y981868D01*
X1654777Y981941D01*
X1654809Y982037D01*
G01X1654561Y978691D02*
X1654689Y978719D01*
X1654777Y978791D01*
X1654809Y978888D01*
G01X1654561Y975541D02*
X1654689Y975569D01*
X1654777Y975642D01*
X1654809Y975738D01*
G01X1654561Y972392D02*
X1654689Y972419D01*
X1654777Y972492D01*
X1654809Y972588D01*
G01X1649203Y938238D02*
X1649476Y938829D01*
G01X1649203Y943238D02*
X1649476Y943829D01*
G01X1649203Y948238D02*
X1649476Y948829D01*
G01X1651172Y953238D02*
X1651444Y953829D01*
G01X1649203Y958238D02*
X1649476Y958829D01*
G01X1649203Y963238D02*
X1649476Y963829D01*
G01X1649203Y968238D02*
X1649476Y968829D01*
G01X1649203Y973238D02*
X1649476Y973829D01*
G01X1649203Y978238D02*
X1649476Y978829D01*
G01X1649203Y983238D02*
X1649476Y983829D01*
G01X1649203Y988238D02*
X1649476Y988829D01*
G01X1651172Y993238D02*
X1651444Y993829D01*
G01X1654809Y966289D02*
X1654775Y966190D01*
X1654687Y966119D01*
X1654561Y966092D01*
G01X1650328Y993238D02*
X1656914D01*
G01X1650328Y992844D02*
X1656914D01*
G01X1656500Y992254D02*
X1650754D01*
G01X1654561Y992077D02*
X1648477D01*
G01X1648197Y991880D02*
X1654809D01*
G01Y991486D02*
X1648197D01*
G01X1654561Y991289D02*
X1648477D01*
G01X1654561Y988927D02*
X1648477D01*
G01X1654531Y988829D02*
X1648786D01*
G01X1648197Y988730D02*
X1654809D01*
G01Y988337D02*
X1648197D01*
G01X1648359Y988238D02*
X1654945D01*
G01X1654561Y988140D02*
X1648477D01*
G01X1648359Y987844D02*
X1654945D01*
G01X1654531Y987254D02*
X1648786D01*
G01X1654561Y985777D02*
X1648477D01*
G01X1648197Y985581D02*
X1654809D01*
G01Y985187D02*
X1648197D01*
G01X1654561Y984990D02*
X1648477D01*
G01X1654531Y983829D02*
X1648786D01*
G01X1648359Y983238D02*
X1654945D01*
G01X1648359Y982844D02*
X1654945D01*
G01X1654561Y982628D02*
X1648477D01*
G01X1648197Y982431D02*
X1654809D01*
G01X1654531Y982254D02*
X1648786D01*
G01X1654809Y982037D02*
X1648197D01*
G01X1654561Y981840D02*
X1648477D01*
G01X1654561Y979478D02*
X1648477D01*
G01X1648197Y979281D02*
X1654809D01*
G01Y978888D02*
X1648197D01*
G01X1654531Y978829D02*
X1648786D01*
G01X1654561Y978691D02*
X1648477D01*
G01X1648359Y978238D02*
X1654945D01*
G01X1648359Y977844D02*
X1654945D01*
G01X1654531Y977254D02*
X1648786D01*
G01X1654561Y976329D02*
X1648477D01*
G01X1648197Y976132D02*
X1654809D01*
G01Y975738D02*
X1648197D01*
G01X1654561Y975541D02*
X1648477D01*
G01X1654531Y973829D02*
X1648786D01*
G01X1648359Y973238D02*
X1654945D01*
G01X1654561Y973179D02*
X1648477D01*
G01X1648197Y972982D02*
X1654809D01*
G01X1648359Y972844D02*
X1654945D01*
G01X1654809Y972588D02*
X1648197D01*
G01X1654561Y972392D02*
X1648477D01*
G01X1654531Y972254D02*
X1648786D01*
G01X1654561Y970029D02*
X1648477D01*
G01X1648197Y969833D02*
X1654809D01*
G01Y969439D02*
X1648197D01*
G01X1654561Y969242D02*
X1648477D01*
G01X1654531Y968829D02*
X1648786D01*
G01X1648359Y968238D02*
X1654945D01*
G01X1648359Y967844D02*
X1654945D01*
G01X1654531Y967254D02*
X1648786D01*
G01X1654561Y966880D02*
X1648477D01*
G01X1648197Y966683D02*
X1654809D01*
G01X1649513Y992077D02*
X1649486Y992073D01*
X1649460Y992062D01*
X1649436Y992044D01*
X1649415Y992019D01*
X1649397Y991989D01*
X1649385Y991955D01*
X1649377Y991919D01*
X1649374Y991880D01*
G01X1649513Y988927D02*
X1649486Y988923D01*
X1649460Y988912D01*
X1649436Y988894D01*
X1649415Y988869D01*
X1649397Y988840D01*
X1649385Y988806D01*
X1649377Y988769D01*
X1649374Y988730D01*
G01X1649513Y985777D02*
X1649486Y985774D01*
X1649460Y985763D01*
X1649436Y985745D01*
X1649415Y985720D01*
X1649397Y985690D01*
X1649385Y985656D01*
X1649377Y985620D01*
X1649374Y985581D01*
G01X1649513Y982628D02*
X1649486Y982624D01*
X1649460Y982613D01*
X1649436Y982595D01*
X1649415Y982570D01*
X1649397Y982541D01*
X1649385Y982507D01*
X1649377Y982470D01*
X1649374Y982431D01*
G01X1649513Y979478D02*
X1649486Y979475D01*
X1649460Y979463D01*
X1649436Y979445D01*
X1649415Y979421D01*
X1649397Y979391D01*
X1649385Y979357D01*
X1649377Y979320D01*
X1649374Y979281D01*
G01X1649513Y976329D02*
X1649486Y976325D01*
X1649460Y976314D01*
X1649436Y976296D01*
X1649415Y976271D01*
X1649397Y976241D01*
X1649385Y976207D01*
X1649377Y976171D01*
X1649374Y976132D01*
G01X1649513Y973179D02*
X1649486Y973175D01*
X1649460Y973164D01*
X1649436Y973146D01*
X1649415Y973121D01*
X1649397Y973092D01*
X1649385Y973058D01*
X1649377Y973021D01*
X1649374Y972982D01*
G01X1649513Y970029D02*
X1649486Y970026D01*
X1649460Y970015D01*
X1649436Y969997D01*
X1649415Y969972D01*
X1649397Y969942D01*
X1649385Y969908D01*
X1649377Y969871D01*
X1649374Y969833D01*
G01X1649513Y966880D02*
X1649486Y966876D01*
X1649460Y966865D01*
X1649436Y966847D01*
X1649415Y966822D01*
X1649397Y966792D01*
X1649385Y966759D01*
X1649377Y966722D01*
X1649374Y966683D01*
G01X1649513Y963730D02*
X1649486Y963726D01*
X1649460Y963715D01*
X1649436Y963697D01*
X1649415Y963673D01*
X1649397Y963643D01*
X1649385Y963609D01*
X1649377Y963572D01*
X1649374Y963533D01*
G01X1649513Y960581D02*
X1649486Y960577D01*
X1649460Y960566D01*
X1649436Y960548D01*
X1649415Y960523D01*
X1649397Y960493D01*
X1649385Y960459D01*
X1649377Y960423D01*
X1649374Y960384D01*
G01X1649513Y957431D02*
X1649486Y957427D01*
X1649460Y957416D01*
X1649436Y957398D01*
X1649415Y957373D01*
X1649397Y957344D01*
X1649385Y957310D01*
X1649377Y957273D01*
X1649374Y957234D01*
G01X1649513Y954281D02*
X1649486Y954278D01*
X1649460Y954267D01*
X1649436Y954249D01*
X1649415Y954224D01*
X1649397Y954194D01*
X1649385Y954160D01*
X1649377Y954123D01*
X1649374Y954085D01*
G01X1649513Y951132D02*
X1649486Y951128D01*
X1649460Y951117D01*
X1649436Y951099D01*
X1649415Y951074D01*
X1649397Y951044D01*
X1649385Y951011D01*
X1649377Y950974D01*
X1649374Y950935D01*
G01X1649513Y947982D02*
X1649486Y947978D01*
X1649460Y947967D01*
X1649436Y947949D01*
X1649415Y947925D01*
X1649397Y947895D01*
X1649385Y947861D01*
X1649377Y947824D01*
X1649374Y947785D01*
G01X1649513Y944833D02*
X1649486Y944829D01*
X1649460Y944818D01*
X1649436Y944800D01*
X1649415Y944775D01*
X1649397Y944745D01*
X1649385Y944711D01*
X1649377Y944675D01*
X1649374Y944636D01*
G01X1649513Y941683D02*
X1649486Y941679D01*
X1649460Y941668D01*
X1649436Y941650D01*
X1649415Y941625D01*
X1649397Y941596D01*
X1649385Y941562D01*
X1649377Y941525D01*
X1649374Y941486D01*
G01X1649513Y938533D02*
X1649486Y938530D01*
X1649460Y938519D01*
X1649436Y938500D01*
X1649415Y938476D01*
X1649397Y938446D01*
X1649385Y938412D01*
X1649377Y938375D01*
X1649374Y938337D01*
G01X1649513Y935384D02*
X1649486Y935380D01*
X1649460Y935369D01*
X1649436Y935351D01*
X1649415Y935326D01*
X1649397Y935296D01*
X1649385Y935263D01*
X1649377Y935226D01*
X1649374Y935187D01*
G01X1649513Y932234D02*
X1649486Y932230D01*
X1649460Y932219D01*
X1649436Y932201D01*
X1649415Y932177D01*
X1649397Y932147D01*
X1649385Y932113D01*
X1649377Y932076D01*
X1649374Y932037D01*
G01X1649513Y929085D02*
X1649486Y929081D01*
X1649460Y929070D01*
X1649436Y929052D01*
X1649415Y929027D01*
X1649397Y928997D01*
X1649385Y928963D01*
X1649377Y928927D01*
X1649374Y928888D01*
G01X1649513Y925935D02*
X1649486Y925931D01*
X1649460Y925920D01*
X1649436Y925902D01*
X1649415Y925877D01*
X1649397Y925848D01*
X1649385Y925814D01*
X1649377Y925777D01*
X1649374Y925738D01*
G01X1649513Y922785D02*
X1649486Y922782D01*
X1649460Y922770D01*
X1649436Y922752D01*
X1649415Y922728D01*
X1649397Y922698D01*
X1649385Y922664D01*
X1649377Y922627D01*
X1649374Y922588D01*
G01X1654571Y932728D02*
X1654698Y932756D01*
X1654787Y932829D01*
X1654819Y932925D01*
G01X1654571Y929579D02*
X1654698Y929606D01*
X1654787Y929679D01*
X1654819Y929776D01*
G01X1654571Y926429D02*
X1654698Y926457D01*
X1654787Y926529D01*
X1654819Y926626D01*
G01X1654571Y923280D02*
X1654698Y923307D01*
X1654787Y923380D01*
X1654819Y923476D01*
G01X1654561Y969242D02*
X1654689Y969270D01*
X1654777Y969343D01*
X1654809Y969439D01*
G01X1654561Y962943D02*
X1654689Y962971D01*
X1654777Y963043D01*
X1654809Y963140D01*
G01X1654561Y959793D02*
X1654689Y959821D01*
X1654777Y959894D01*
X1654809Y959990D01*
G01X1654561Y956644D02*
X1654689Y956671D01*
X1654777Y956744D01*
X1654809Y956840D01*
G01X1654561Y953494D02*
X1654689Y953522D01*
X1654777Y953595D01*
X1654809Y953691D01*
G01X1654561Y950344D02*
X1654689Y950372D01*
X1654777Y950445D01*
X1654809Y950541D01*
G01X1654561Y947195D02*
X1654689Y947223D01*
X1654777Y947295D01*
X1654809Y947392D01*
G01X1654561Y944045D02*
X1654689Y944073D01*
X1654777Y944146D01*
X1654809Y944242D01*
G01X1654561Y940896D02*
X1654689Y940923D01*
X1654777Y940996D01*
X1654809Y941092D01*
G01X1654561Y937746D02*
X1654689Y937774D01*
X1654777Y937847D01*
X1654809Y937943D01*
G01X1654561Y934596D02*
X1654689Y934624D01*
X1654777Y934697D01*
X1654809Y934793D01*
G01X1654561Y931447D02*
X1654689Y931475D01*
X1654777Y931547D01*
X1654809Y931644D01*
G01X1654561Y928297D02*
X1654689Y928325D01*
X1654777Y928398D01*
X1654809Y928494D01*
G01X1654561Y925148D02*
X1654689Y925175D01*
X1654777Y925248D01*
X1654809Y925344D01*
G01X1650328Y938238D02*
X1650405Y938829D01*
G01X1652296Y953238D02*
X1652374Y953829D01*
G01X1650328Y943238D02*
X1650405Y943829D01*
G01X1650328Y948238D02*
X1650405Y948829D01*
G01X1650328Y958238D02*
X1650405Y958829D01*
G01X1650328Y963238D02*
X1650405Y963829D01*
G01X1650328Y968238D02*
X1650405Y968829D01*
G01X1650328Y973238D02*
X1650405Y973829D01*
G01X1650328Y978238D02*
X1650405Y978829D01*
G01X1652296Y993238D02*
X1652374Y993829D01*
G01X1650328Y983238D02*
X1650405Y983829D01*
G01X1650328Y988238D02*
X1650405Y988829D01*
G01X1649887Y922588D02*
X1649897Y922687D01*
X1649925Y922759D01*
X1649964Y922785D01*
G01X1649887Y925738D02*
X1649897Y925836D01*
X1649925Y925909D01*
X1649964Y925935D01*
G01X1649887Y932037D02*
X1649897Y932136D01*
X1649925Y932208D01*
X1649964Y932234D01*
G01X1649887Y935187D02*
X1649897Y935285D01*
X1649925Y935357D01*
X1649964Y935384D01*
G01X1649887Y938337D02*
X1649897Y938435D01*
X1649925Y938507D01*
X1649964Y938533D01*
G01X1649887Y941486D02*
X1649897Y941584D01*
X1649925Y941657D01*
X1649964Y941683D01*
G01X1649887Y944636D02*
X1649897Y944734D01*
X1649925Y944806D01*
X1649964Y944833D01*
G01X1649887Y947785D02*
X1649897Y947884D01*
X1649925Y947956D01*
X1649964Y947982D01*
G01X1649887Y950935D02*
X1649897Y951033D01*
X1649925Y951105D01*
X1649964Y951132D01*
G01X1649887Y954085D02*
X1649897Y954183D01*
X1649925Y954255D01*
X1649964Y954281D01*
G01X1649887Y957234D02*
X1649897Y957333D01*
X1649925Y957405D01*
X1649964Y957431D01*
G01X1649887Y960384D02*
X1649897Y960482D01*
X1649925Y960554D01*
X1649964Y960581D01*
G01X1649887Y963533D02*
X1649897Y963632D01*
X1649925Y963704D01*
X1649964Y963730D01*
G01X1649887Y966683D02*
X1649897Y966781D01*
X1649925Y966853D01*
X1649964Y966880D01*
G01X1649887Y969833D02*
X1649897Y969931D01*
X1649925Y970003D01*
X1649964Y970029D01*
G01X1649887Y972982D02*
X1649897Y973081D01*
X1649925Y973153D01*
X1649964Y973179D01*
G01X1649887Y976132D02*
X1649897Y976230D01*
X1649925Y976302D01*
X1649964Y976329D01*
G01X1649887Y979281D02*
X1649897Y979380D01*
X1649925Y979452D01*
X1649964Y979478D01*
G01X1649887Y982431D02*
X1649897Y982529D01*
X1649925Y982601D01*
X1649964Y982628D01*
G01X1649887Y985581D02*
X1649897Y985679D01*
X1649925Y985751D01*
X1649964Y985777D01*
G01X1649887Y988730D02*
X1649897Y988829D01*
X1649925Y988901D01*
X1649964Y988927D01*
G01X1649887Y991880D02*
X1649897Y991978D01*
X1649925Y992050D01*
X1649964Y992077D01*
G01X1649443Y924461D02*
X1649445Y924499D01*
X1649454Y924536D01*
X1649467Y924570D01*
X1649486Y924600D01*
X1649508Y924624D01*
X1649534Y924642D01*
X1649561Y924654D01*
X1649590Y924658D01*
G01X1649443Y927610D02*
X1649445Y927649D01*
X1649454Y927685D01*
X1649467Y927719D01*
X1649486Y927750D01*
X1649508Y927774D01*
X1649534Y927792D01*
X1649561Y927803D01*
X1649590Y927807D01*
G01X1649443Y930760D02*
X1649445Y930798D01*
X1649454Y930835D01*
X1649467Y930869D01*
X1649486Y930899D01*
X1649508Y930924D01*
X1649534Y930942D01*
X1649561Y930953D01*
X1649590Y930957D01*
G01X1649443Y933910D02*
X1649445Y933948D01*
X1649454Y933985D01*
X1649467Y934018D01*
X1649486Y934049D01*
X1649508Y934073D01*
X1649534Y934091D01*
X1649561Y934103D01*
X1649590Y934106D01*
G01X1652296Y992844D02*
X1652374Y992254D01*
G01X1650328Y987844D02*
X1650405Y987254D01*
G01X1650328Y982844D02*
X1650405Y982254D01*
G01X1650328Y977844D02*
X1650405Y977254D01*
G01X1650328Y972844D02*
X1650405Y972254D01*
G01X1650328Y967844D02*
X1650405Y967254D01*
G01X1652296Y952844D02*
X1652374Y952254D01*
G01X1650328Y962844D02*
X1650405Y962254D01*
G01X1650328Y957844D02*
X1650405Y957254D01*
G01X1650328Y947844D02*
X1650405Y947254D01*
G01X1650328Y942844D02*
X1650405Y942254D01*
G01X1650328Y937844D02*
X1650405Y937254D01*
G01X1654561Y966880D02*
X1654688Y966852D01*
X1654777Y966780D01*
X1654809Y966683D01*
G01X1649590Y932728D02*
X1649562Y932732D01*
X1649534Y932743D01*
X1649509Y932761D01*
X1649486Y932786D01*
X1649468Y932816D01*
X1649454Y932850D01*
X1649446Y932886D01*
X1649443Y932925D01*
G01X1649590Y929579D02*
X1649562Y929583D01*
X1649534Y929594D01*
X1649509Y929612D01*
X1649486Y929636D01*
X1649468Y929666D01*
X1649454Y929700D01*
X1649446Y929737D01*
X1649443Y929776D01*
G01X1654809Y966289D02*
X1648197D01*
G01X1654561Y966092D02*
X1648477D01*
G01X1654531Y963829D02*
X1648786D01*
G01X1654561Y963730D02*
X1648477D01*
G01X1648197Y963533D02*
X1654809D01*
G01X1648359Y963238D02*
X1654945D01*
G01X1654809Y963140D02*
X1648197D01*
G01X1654561Y962943D02*
X1648477D01*
G01X1648359Y962844D02*
X1654945D01*
G01X1654531Y962254D02*
X1648786D01*
G01X1654561Y960581D02*
X1648477D01*
G01X1648197Y960384D02*
X1654809D01*
G01Y959990D02*
X1648197D01*
G01X1654561Y959793D02*
X1648477D01*
G01X1654531Y958829D02*
X1648786D01*
G01X1648359Y958238D02*
X1654945D01*
G01X1648359Y957844D02*
X1654945D01*
G01X1654561Y957431D02*
X1648477D01*
G01X1654531Y957254D02*
X1648786D01*
G01X1648197Y957234D02*
X1654809D01*
G01Y956840D02*
X1648197D01*
G01X1654561Y956644D02*
X1648477D01*
G01X1654561Y954281D02*
X1648477D01*
G01X1648197Y954085D02*
X1654809D01*
G01X1656500Y953829D02*
X1650754D01*
G01X1654809Y953691D02*
X1648197D01*
G01X1654561Y953494D02*
X1648477D01*
G01X1650328Y953238D02*
X1656914D01*
G01X1650328Y952844D02*
X1656914D01*
G01X1656500Y952254D02*
X1650754D01*
G01X1654561Y951132D02*
X1648477D01*
G01X1648197Y950935D02*
X1654809D01*
G01Y950541D02*
X1648197D01*
G01X1654561Y950344D02*
X1648477D01*
G01X1654531Y948829D02*
X1648786D01*
G01X1648359Y948238D02*
X1654945D01*
G01X1654561Y947982D02*
X1648477D01*
G01X1648359Y947844D02*
X1654945D01*
G01X1648197Y947785D02*
X1654809D01*
G01Y947392D02*
X1648197D01*
G01X1654531Y947254D02*
X1648786D01*
G01X1654561Y947195D02*
X1648477D01*
G01X1654561Y944833D02*
X1648477D01*
G01X1648197Y944636D02*
X1654809D01*
G01Y944242D02*
X1648197D01*
G01X1654561Y944045D02*
X1648477D01*
G01X1654531Y943829D02*
X1648786D01*
G01X1648359Y943238D02*
X1654945D01*
G01X1648359Y942844D02*
X1654945D01*
G01X1654531Y942254D02*
X1648786D01*
G01X1654561Y941683D02*
X1648477D01*
G01X1648197Y941486D02*
X1654809D01*
G01Y941092D02*
X1648197D01*
G01X1654561Y940896D02*
X1648477D01*
G01X1654631Y938829D02*
X1648718D01*
G01X1654561Y938533D02*
X1648477D01*
G01X1648197Y938337D02*
X1654809D01*
G01X1648294Y938238D02*
X1655036D01*
G01X1654809Y937943D02*
X1648197D01*
G01X1648294Y937844D02*
X1655036D01*
G01X1654561Y937746D02*
X1648477D01*
G01X1654631Y937254D02*
X1648718D01*
G01X1652326Y936466D02*
X1658795D01*
G01X1654561Y935384D02*
X1648477D01*
G01X1648197Y935187D02*
X1654809D01*
G01Y934793D02*
X1648197D01*
G01X1654561Y934596D02*
X1648477D01*
G01X1648763Y934106D02*
X1654571D01*
G01X1654819Y933910D02*
X1648501D01*
G01Y932925D02*
X1654819D01*
G01X1648763Y932728D02*
X1654571D01*
G01X1654561Y932234D02*
X1648477D01*
G01X1648197Y932037D02*
X1654809D01*
G01Y931644D02*
X1648197D01*
G01X1654561Y931447D02*
X1648477D01*
G01X1648763Y930957D02*
X1654571D01*
G01X1654819Y930760D02*
X1648501D01*
G01Y929776D02*
X1654819D01*
G01X1648763Y929579D02*
X1654571D01*
G01X1654561Y929085D02*
X1648477D01*
G01X1648197Y928888D02*
X1654809D01*
G01Y928494D02*
X1648197D01*
G01X1654561Y928297D02*
X1648477D01*
G01X1648763Y927807D02*
X1654571D01*
G01X1654819Y927610D02*
X1648501D01*
G01Y926626D02*
X1654819D01*
G01X1648763Y926429D02*
X1654571D01*
G01X1654561Y925935D02*
X1648477D01*
G01X1648197Y925738D02*
X1654809D01*
G01Y925344D02*
X1648197D01*
G01X1654561Y925148D02*
X1648477D01*
G01X1648763Y924658D02*
X1654571D01*
G01X1654819Y924461D02*
X1648501D01*
G01Y923476D02*
X1654819D01*
G01X1648763Y923280D02*
X1654571D01*
G01X1654561Y922785D02*
X1648477D01*
G01X1648197Y922588D02*
X1654809D01*
G01X1650595Y924461D02*
Y924499D01*
X1650597Y924536D01*
X1650600Y924570D01*
X1650604Y924600D01*
X1650609Y924624D01*
X1650615Y924642D01*
X1650621Y924654D01*
X1650627Y924658D01*
G01X1650595Y927610D02*
Y927649D01*
X1650597Y927685D01*
X1650600Y927719D01*
X1650604Y927750D01*
X1650609Y927774D01*
X1650615Y927792D01*
X1650621Y927803D01*
X1650627Y927807D01*
G01X1650595Y930760D02*
Y930798D01*
X1650597Y930835D01*
X1650600Y930869D01*
X1650604Y930899D01*
X1650609Y930924D01*
X1650615Y930942D01*
X1650621Y930953D01*
X1650627Y930957D01*
G01X1650595Y933910D02*
Y933948D01*
X1650597Y933985D01*
X1650600Y934018D01*
X1650604Y934049D01*
X1650609Y934073D01*
X1650615Y934091D01*
X1650621Y934103D01*
X1650627Y934106D01*
G01X1657784Y941742D02*
Y936262D01*
G01X1657614Y1012648D02*
Y941742D01*
G01X1656914Y953238D02*
Y952844D01*
G01Y993238D02*
Y992844D01*
G01X1655036Y938238D02*
Y937844D01*
G01X1654945Y943238D02*
Y942844D01*
G01Y948238D02*
Y947844D01*
G01Y958238D02*
Y957844D01*
G01Y963238D02*
Y962844D01*
G01Y968238D02*
Y967844D01*
G01Y973238D02*
Y972844D01*
G01Y978238D02*
Y977844D01*
G01Y983238D02*
Y982844D01*
G01Y988238D02*
Y987844D01*
G01X1654819Y924461D02*
Y923476D01*
G01Y927610D02*
Y926626D01*
G01Y930760D02*
Y929776D01*
G01Y933910D02*
Y932925D01*
G01X1654809Y991486D02*
Y991880D01*
G01Y988337D02*
Y988730D01*
G01Y985187D02*
Y985581D01*
G01Y982037D02*
Y982431D01*
G01Y978888D02*
Y979281D01*
G01Y975738D02*
Y976132D01*
G01Y972588D02*
Y972982D01*
G01Y969439D02*
Y969833D01*
G01Y966289D02*
Y966683D01*
G01Y963140D02*
Y963533D01*
G01Y959990D02*
Y960384D01*
G01Y956840D02*
Y957234D01*
G01Y953691D02*
Y954085D01*
G01Y950541D02*
Y950935D01*
G01Y944242D02*
Y944636D01*
G01Y947392D02*
Y947785D01*
G01Y941092D02*
Y941486D01*
G01Y934793D02*
Y935187D01*
G01Y937943D02*
Y938337D01*
G01Y931644D02*
Y932037D01*
G01Y928494D02*
Y928888D01*
G01Y925344D02*
Y925738D01*
G01X1652326Y936466D02*
Y935285D01*
G01X1652296Y953238D02*
Y952844D01*
G01Y993238D02*
Y992844D01*
G01X1651172D02*
Y993238D01*
G01Y952844D02*
Y953238D01*
G01X1650595Y929776D02*
Y930760D01*
G01Y932925D02*
Y933910D01*
G01Y926626D02*
Y927610D01*
G01Y923476D02*
Y924461D01*
G01X1650328Y992844D02*
Y993238D01*
G01Y952844D02*
Y953238D01*
G01Y938238D02*
Y937844D01*
G01Y943238D02*
Y942844D01*
G01Y948238D02*
Y947844D01*
G01Y958238D02*
Y957844D01*
G01Y963238D02*
Y962844D01*
G01Y968238D02*
Y967844D01*
G01Y973238D02*
Y972844D01*
G01Y978238D02*
Y977844D01*
G01Y983238D02*
Y982844D01*
G01Y988238D02*
Y987844D01*
G01X1649887Y991486D02*
Y991880D01*
G01Y988337D02*
Y988730D01*
G01Y985187D02*
Y985581D01*
G01Y982037D02*
Y982431D01*
G01Y978888D02*
Y979281D01*
G01Y975738D02*
Y976132D01*
G01Y972588D02*
Y972982D01*
G01Y969439D02*
Y969833D01*
G01Y966289D02*
Y966683D01*
G01Y963140D02*
Y963533D01*
G01Y959990D02*
Y960384D01*
G01Y956840D02*
Y957234D01*
G01Y953691D02*
Y954085D01*
G01Y950541D02*
Y950935D01*
G01Y944242D02*
Y944636D01*
G01Y947392D02*
Y947785D01*
G01Y941092D02*
Y941486D01*
G01Y934793D02*
Y935187D01*
G01Y937943D02*
Y938337D01*
G01Y931644D02*
Y932037D01*
G01Y928494D02*
Y928888D01*
G01Y925344D02*
Y925738D01*
G01X1649443Y929776D02*
Y930760D01*
G01Y932925D02*
Y933910D01*
G01Y926626D02*
Y927610D01*
G01Y923476D02*
Y924461D01*
G01X1649374Y928888D02*
Y928494D01*
G01Y925738D02*
Y925344D01*
G01Y932037D02*
Y931644D01*
G01Y935187D02*
Y934793D01*
G01Y938337D02*
Y937943D01*
G01Y941486D02*
Y941092D01*
G01Y944636D02*
Y944242D01*
G01Y947785D02*
Y947392D01*
G01Y950935D02*
Y950541D01*
G01Y957234D02*
Y956840D01*
G01Y954085D02*
Y953691D01*
G01Y960384D02*
Y959990D01*
G01Y966683D02*
Y966289D01*
G01Y963533D02*
Y963140D01*
G01Y969833D02*
Y969439D01*
G01Y976132D02*
Y975738D01*
G01Y972982D02*
Y972588D01*
G01Y979281D02*
Y978888D01*
G01Y985581D02*
Y985187D01*
G01Y982431D02*
Y982037D01*
G01Y988730D02*
Y988337D01*
G01Y991880D02*
Y991486D01*
G01X1649203Y987844D02*
Y988238D01*
G01Y982844D02*
Y983238D01*
G01Y977844D02*
Y978238D01*
G01Y972844D02*
Y973238D01*
G01Y967844D02*
Y968238D01*
G01Y962844D02*
Y963238D01*
G01Y957844D02*
Y958238D01*
G01Y947844D02*
Y948238D01*
G01Y942844D02*
Y943238D01*
G01Y937844D02*
Y938238D01*
G01X1648501Y929776D02*
Y930760D01*
G01Y932925D02*
Y933910D01*
G01Y926626D02*
Y927610D01*
G01Y923476D02*
Y924461D01*
G01X1648359Y987844D02*
Y988238D01*
G01Y982844D02*
Y983238D01*
G01Y977844D02*
Y978238D01*
G01Y972844D02*
Y973238D01*
G01Y967844D02*
Y968238D01*
G01Y962844D02*
Y963238D01*
G01Y957844D02*
Y958238D01*
G01Y947844D02*
Y948238D01*
G01Y942844D02*
Y943238D01*
G01X1648294Y937844D02*
Y938238D01*
G01X1648197Y928888D02*
Y928494D01*
G01Y925738D02*
Y925344D01*
G01Y932037D02*
Y931644D01*
G01Y935187D02*
Y934793D01*
G01Y938337D02*
Y937943D01*
G01Y941486D02*
Y941092D01*
G01Y944636D02*
Y944242D01*
G01Y947785D02*
Y947392D01*
G01Y950935D02*
Y950541D01*
G01Y957234D02*
Y956840D01*
G01Y954085D02*
Y953691D01*
G01Y960384D02*
Y959990D01*
G01Y966683D02*
Y966289D01*
G01Y963533D02*
Y963140D01*
G01Y969833D02*
Y969439D01*
G01Y976132D02*
Y975738D01*
G01Y972982D02*
Y972588D01*
G01Y979281D02*
Y978888D01*
G01Y985581D02*
Y985187D01*
G01Y982431D02*
Y982037D01*
G01Y988730D02*
Y988337D01*
G01Y991880D02*
Y991486D01*
G01X1649374D02*
X1649377Y991448D01*
X1649385Y991411D01*
X1649397Y991377D01*
X1649415Y991347D01*
X1649436Y991323D01*
X1649459Y991304D01*
X1649485Y991293D01*
X1649513Y991289D01*
G01X1649374Y988337D02*
X1649377Y988298D01*
X1649385Y988262D01*
X1649397Y988228D01*
X1649415Y988197D01*
X1649436Y988173D01*
X1649459Y988155D01*
X1649485Y988144D01*
X1649513Y988140D01*
G01X1649374Y985187D02*
X1649377Y985149D01*
X1649385Y985112D01*
X1649397Y985078D01*
X1649415Y985048D01*
X1649436Y985023D01*
X1649459Y985005D01*
X1649485Y984994D01*
X1649513Y984990D01*
G01X1649374Y982037D02*
X1649377Y981999D01*
X1649385Y981962D01*
X1649397Y981928D01*
X1649415Y981898D01*
X1649436Y981874D01*
X1649459Y981856D01*
X1649485Y981844D01*
X1649513Y981840D01*
G01X1649374Y978888D02*
X1649377Y978849D01*
X1649385Y978813D01*
X1649397Y978779D01*
X1649415Y978749D01*
X1649436Y978724D01*
X1649459Y978706D01*
X1649485Y978695D01*
X1649513Y978691D01*
G01X1649374Y975738D02*
X1649377Y975700D01*
X1649385Y975663D01*
X1649397Y975629D01*
X1649415Y975599D01*
X1649436Y975575D01*
X1649459Y975556D01*
X1649485Y975545D01*
X1649513Y975541D01*
G01X1649374Y972588D02*
X1649377Y972550D01*
X1649385Y972513D01*
X1649397Y972480D01*
X1649415Y972449D01*
X1649436Y972425D01*
X1649459Y972407D01*
X1649485Y972396D01*
X1649513Y972392D01*
G01X1649374Y969439D02*
X1649377Y969401D01*
X1649385Y969364D01*
X1649397Y969330D01*
X1649415Y969300D01*
X1649436Y969275D01*
X1649459Y969257D01*
X1649485Y969246D01*
X1649513Y969242D01*
G01X1649374Y966289D02*
X1649377Y966251D01*
X1649385Y966214D01*
X1649397Y966180D01*
X1649415Y966150D01*
X1649436Y966126D01*
X1649459Y966108D01*
X1649485Y966096D01*
X1649513Y966092D01*
G01X1649374Y963140D02*
X1649377Y963101D01*
X1649385Y963065D01*
X1649397Y963031D01*
X1649415Y963000D01*
X1649436Y962976D01*
X1649459Y962958D01*
X1649485Y962947D01*
X1649513Y962943D01*
G01X1649374Y959990D02*
X1649377Y959952D01*
X1649385Y959915D01*
X1649397Y959881D01*
X1649415Y959851D01*
X1649436Y959826D01*
X1649459Y959808D01*
X1649485Y959797D01*
X1649513Y959793D01*
G01X1649374Y956840D02*
X1649377Y956802D01*
X1649385Y956765D01*
X1649397Y956732D01*
X1649415Y956701D01*
X1649436Y956677D01*
X1649459Y956659D01*
X1649485Y956647D01*
X1649513Y956644D01*
G01X1649374Y953691D02*
X1649377Y953653D01*
X1649385Y953616D01*
X1649397Y953582D01*
X1649415Y953552D01*
X1649436Y953527D01*
X1649459Y953509D01*
X1649485Y953498D01*
X1649513Y953494D01*
G01X1649374Y950541D02*
X1649377Y950503D01*
X1649385Y950466D01*
X1649397Y950432D01*
X1649415Y950402D01*
X1649436Y950378D01*
X1649459Y950360D01*
X1649485Y950348D01*
X1649513Y950344D01*
G01X1649374Y947392D02*
X1649377Y947353D01*
X1649385Y947317D01*
X1649397Y947283D01*
X1649415Y947252D01*
X1649436Y947228D01*
X1649459Y947210D01*
X1649485Y947199D01*
X1649513Y947195D01*
G01X1649374Y944242D02*
X1649377Y944204D01*
X1649385Y944167D01*
X1649397Y944133D01*
X1649415Y944103D01*
X1649436Y944078D01*
X1649459Y944060D01*
X1649485Y944049D01*
X1649513Y944045D01*
G01X1649374Y941092D02*
X1649377Y941054D01*
X1649385Y941017D01*
X1649397Y940983D01*
X1649415Y940953D01*
X1649436Y940929D01*
X1649459Y940911D01*
X1649485Y940899D01*
X1649513Y940896D01*
G01X1649374Y937943D02*
X1649377Y937905D01*
X1649385Y937868D01*
X1649397Y937834D01*
X1649415Y937804D01*
X1649436Y937779D01*
X1649459Y937761D01*
X1649485Y937750D01*
X1649513Y937746D01*
G01X1649374Y934793D02*
X1649377Y934755D01*
X1649385Y934718D01*
X1649397Y934684D01*
X1649415Y934654D01*
X1649436Y934630D01*
X1649459Y934611D01*
X1649485Y934600D01*
X1649513Y934596D01*
G01X1649374Y931644D02*
X1649377Y931605D01*
X1649385Y931569D01*
X1649397Y931535D01*
X1649415Y931504D01*
X1649436Y931480D01*
X1649459Y931462D01*
X1649485Y931451D01*
X1649513Y931447D01*
G01X1649374Y928494D02*
X1649377Y928456D01*
X1649385Y928419D01*
X1649397Y928385D01*
X1649415Y928355D01*
X1649436Y928330D01*
X1649459Y928312D01*
X1649485Y928301D01*
X1649513Y928297D01*
G01X1649374Y925344D02*
X1649377Y925306D01*
X1649385Y925269D01*
X1649397Y925235D01*
X1649415Y925205D01*
X1649436Y925181D01*
X1649459Y925163D01*
X1649485Y925151D01*
X1649513Y925148D01*
G01X1654809Y991880D02*
X1654777Y991977D01*
X1654689Y992049D01*
X1654561Y992077D01*
G01X1654809Y988730D02*
X1654777Y988827D01*
X1654689Y988899D01*
X1654561Y988927D01*
G01X1654809Y985581D02*
X1654777Y985678D01*
X1654689Y985750D01*
X1654561Y985777D01*
G01X1654809Y982431D02*
X1654777Y982528D01*
X1654689Y982600D01*
X1654561Y982628D01*
G01X1654809Y979281D02*
X1654777Y979378D01*
X1654689Y979451D01*
X1654561Y979478D01*
G01X1654809Y976132D02*
X1654777Y976229D01*
X1654689Y976301D01*
X1654561Y976329D01*
G01X1654809Y972982D02*
X1654777Y973079D01*
X1654689Y973151D01*
X1654561Y973179D01*
G01X1654809Y969833D02*
X1654777Y969930D01*
X1654689Y970002D01*
X1654561Y970029D01*
G01X1654809Y963533D02*
X1654777Y963630D01*
X1654689Y963703D01*
X1654561Y963730D01*
G01X1654809Y960384D02*
X1654777Y960481D01*
X1654689Y960553D01*
X1654561Y960581D01*
G01X1654809Y957234D02*
X1654777Y957331D01*
X1654689Y957403D01*
X1654561Y957431D01*
G01X1654809Y954085D02*
X1654777Y954182D01*
X1654689Y954254D01*
X1654561Y954281D01*
G01X1654809Y950935D02*
X1654777Y951032D01*
X1654689Y951104D01*
X1654561Y951132D01*
G01X1654809Y947785D02*
X1654777Y947882D01*
X1654689Y947955D01*
X1654561Y947982D01*
G01X1654809Y944636D02*
X1654777Y944733D01*
X1654689Y944805D01*
X1654561Y944833D01*
G01X1654809Y941486D02*
X1654777Y941583D01*
X1654689Y941655D01*
X1654561Y941683D01*
G01X1654809Y938337D02*
X1654777Y938434D01*
X1654689Y938506D01*
X1654561Y938533D01*
G01X1654809Y935187D02*
X1654777Y935284D01*
X1654689Y935356D01*
X1654561Y935384D01*
G01X1654809Y932037D02*
X1654777Y932134D01*
X1654689Y932207D01*
X1654561Y932234D01*
G01X1654809Y928888D02*
X1654777Y928985D01*
X1654689Y929057D01*
X1654561Y929085D01*
G01X1654809Y925738D02*
X1654777Y925835D01*
X1654689Y925907D01*
X1654561Y925935D01*
G01X1654809Y922588D02*
X1654777Y922685D01*
X1654689Y922758D01*
X1654561Y922785D01*
G01X1654819Y933910D02*
X1654785Y934009D01*
X1654697Y934079D01*
X1654571Y934106D01*
G01X1654819Y930760D02*
X1654785Y930859D01*
X1654697Y930930D01*
X1654571Y930957D01*
G01X1654819Y927610D02*
X1654785Y927709D01*
X1654697Y927780D01*
X1654571Y927807D01*
G01X1654819Y924461D02*
X1654785Y924560D01*
X1654697Y924631D01*
X1654571Y924658D01*
G01X1651444Y992254D02*
X1651172Y992844D01*
G01X1649476Y987254D02*
X1649203Y987844D01*
G01X1649476Y982254D02*
X1649203Y982844D01*
G01X1649476Y977254D02*
X1649203Y977844D01*
G01X1649476Y972254D02*
X1649203Y972844D01*
G01X1649476Y967254D02*
X1649203Y967844D01*
G01X1649476Y962254D02*
X1649203Y962844D01*
G01X1649476Y957254D02*
X1649203Y957844D01*
G01X1651444Y952254D02*
X1651172Y952844D01*
G01X1649476Y947254D02*
X1649203Y947844D01*
G01X1649476Y942254D02*
X1649203Y942844D01*
G01X1649476Y937254D02*
X1649203Y937844D01*
G01X1655036Y938238D02*
X1654902Y938436D01*
X1654767Y938633D01*
X1654631Y938829D01*
G01X1656914Y993238D02*
X1656777Y993436D01*
X1656639Y993633D01*
X1656500Y993829D01*
G01X1654945Y988238D02*
X1654808Y988436D01*
X1654670Y988633D01*
X1654531Y988829D01*
G01X1654945Y983238D02*
X1654808Y983436D01*
X1654670Y983633D01*
X1654531Y983829D01*
G01X1654945Y978238D02*
X1654808Y978436D01*
X1654670Y978633D01*
X1654531Y978829D01*
G01X1654945Y973238D02*
X1654808Y973436D01*
X1654670Y973633D01*
X1654531Y973829D01*
G01X1654945Y968238D02*
X1654808Y968436D01*
X1654670Y968633D01*
X1654531Y968829D01*
G01X1654945Y963238D02*
X1654808Y963436D01*
X1654670Y963633D01*
X1654531Y963829D01*
G01X1654945Y958238D02*
X1654808Y958436D01*
X1654670Y958633D01*
X1654531Y958829D01*
G01X1656914Y953238D02*
X1656777Y953436D01*
X1656639Y953633D01*
X1656500Y953829D01*
G01X1654945Y948238D02*
X1654808Y948436D01*
X1654670Y948633D01*
X1654531Y948829D01*
G01X1654945Y943238D02*
X1654808Y943436D01*
X1654670Y943633D01*
X1654531Y943829D01*
G01X1648718Y937254D02*
X1648294Y937844D01*
G01X1650754Y992254D02*
X1650328Y992844D01*
G01X1648786Y987254D02*
X1648359Y987844D01*
G01X1648786Y982254D02*
X1648359Y982844D01*
G01X1648786Y977254D02*
X1648359Y977844D01*
G01X1648786Y972254D02*
X1648359Y972844D01*
G01X1648786Y967254D02*
X1648359Y967844D01*
G01X1648786Y962254D02*
X1648359Y962844D01*
G01X1648786Y957254D02*
X1648359Y957844D01*
G01X1650754Y952254D02*
X1650328Y952844D01*
G01X1648786Y947254D02*
X1648359Y947844D01*
G01X1648786Y942254D02*
X1648359Y942844D01*
G01X1649964Y991289D02*
X1649925Y991316D01*
X1649897Y991388D01*
X1649887Y991486D01*
G01X1649964Y988140D02*
X1649925Y988166D01*
X1649897Y988238D01*
X1649887Y988337D01*
G01X1649964Y984990D02*
X1649925Y985016D01*
X1649897Y985089D01*
X1649887Y985187D01*
G01X1649964Y981840D02*
X1649925Y981867D01*
X1649897Y981939D01*
X1649887Y982037D01*
G01X1649964Y978691D02*
X1649925Y978717D01*
X1649897Y978789D01*
X1649887Y978888D01*
G01X1649964Y975541D02*
X1649925Y975568D01*
X1649897Y975640D01*
X1649887Y975738D01*
G01X1649964Y972392D02*
X1649925Y972418D01*
X1649897Y972490D01*
X1649887Y972588D01*
G01X1649964Y969242D02*
X1649925Y969268D01*
X1649897Y969341D01*
X1649887Y969439D01*
G01X1649964Y966092D02*
X1649925Y966119D01*
X1649897Y966191D01*
X1649887Y966289D01*
G01X1649964Y962943D02*
X1649925Y962969D01*
X1649897Y963041D01*
X1649887Y963140D01*
G01X1649964Y959793D02*
X1649925Y959820D01*
X1649897Y959892D01*
X1649887Y959990D01*
G01X1649964Y956644D02*
X1649925Y956670D01*
X1649897Y956742D01*
X1649887Y956840D01*
G01X1649964Y953494D02*
X1649925Y953520D01*
X1649897Y953593D01*
X1649887Y953691D01*
G01X1649964Y950344D02*
X1649925Y950371D01*
X1649897Y950443D01*
X1649887Y950541D01*
G01X1649964Y947195D02*
X1649925Y947221D01*
X1649897Y947293D01*
X1649887Y947392D01*
G01X1649964Y944045D02*
X1649925Y944072D01*
X1649897Y944144D01*
X1649887Y944242D01*
G01X1649964Y940896D02*
X1649925Y940922D01*
X1649897Y940994D01*
X1649887Y941092D01*
G01X1649964Y937746D02*
X1649925Y937772D01*
X1649897Y937844D01*
X1649887Y937943D01*
G01X1650627Y932728D02*
X1650621Y932732D01*
X1650615Y932743D01*
X1650609Y932761D01*
X1650604Y932786D01*
X1650600Y932816D01*
X1650597Y932850D01*
X1650595Y932886D01*
Y932925D01*
G01X1650627Y929579D02*
X1650621Y929583D01*
X1650615Y929594D01*
X1650609Y929612D01*
X1650604Y929636D01*
X1650600Y929666D01*
X1650597Y929700D01*
X1650595Y929737D01*
Y929776D01*
G01X1649590Y926429D02*
X1649562Y926433D01*
X1649534Y926444D01*
X1649509Y926462D01*
X1649486Y926487D01*
X1649468Y926517D01*
X1649454Y926550D01*
X1649446Y926587D01*
X1649443Y926626D01*
G01X1649590Y923280D02*
X1649562Y923283D01*
X1649534Y923294D01*
X1649509Y923313D01*
X1649486Y923337D01*
X1649468Y923367D01*
X1649454Y923401D01*
X1649446Y923438D01*
X1649443Y923476D01*
G01X1649964Y934596D02*
X1649925Y934623D01*
X1649897Y934695D01*
X1649887Y934793D01*
G01X1649964Y931447D02*
X1649925Y931473D01*
X1649897Y931545D01*
X1649887Y931644D01*
G01X1649964Y928297D02*
X1649925Y928324D01*
X1649897Y928396D01*
X1649887Y928494D01*
G01X1649964Y925148D02*
X1649925Y925174D01*
X1649897Y925246D01*
X1649887Y925344D01*
G01X1650627Y926429D02*
X1650621Y926433D01*
X1650615Y926444D01*
X1650609Y926462D01*
X1650604Y926487D01*
X1650600Y926517D01*
X1650597Y926550D01*
X1650595Y926587D01*
Y926626D01*
G01X1650627Y923280D02*
X1650621Y923283D01*
X1650615Y923294D01*
X1650609Y923313D01*
X1650604Y923337D01*
X1650600Y923367D01*
X1650597Y923401D01*
X1650595Y923438D01*
Y923476D01*
G01X1654809Y994636D02*
X1654775Y994537D01*
X1654687Y994466D01*
X1654561Y994439D01*
G01Y995226D02*
X1648477D01*
G01X1648197Y995029D02*
X1654809D01*
G01Y994636D02*
X1648197D01*
G01X1654561Y994439D02*
X1648477D01*
G01X1656500Y993829D02*
X1650754D01*
G01X1649513Y995226D02*
X1649486Y995223D01*
X1649460Y995211D01*
X1649436Y995193D01*
X1649415Y995169D01*
X1649397Y995139D01*
X1649385Y995105D01*
X1649377Y995068D01*
X1649374Y995029D01*
G01X1649887D02*
X1649897Y995128D01*
X1649925Y995200D01*
X1649964Y995226D01*
G01X1654561D02*
X1654688Y995199D01*
X1654777Y995126D01*
X1654809Y995029D01*
G01Y994636D02*
Y995029D01*
G01X1649887Y994636D02*
Y995029D01*
G01X1649374D02*
Y994636D01*
G01X1648197Y995029D02*
Y994636D01*
G01X1649374D02*
X1649377Y994597D01*
X1649385Y994561D01*
X1649397Y994527D01*
X1649415Y994497D01*
X1649436Y994472D01*
X1649459Y994454D01*
X1649485Y994443D01*
X1649513Y994439D01*
G01X1649964D02*
X1649925Y994465D01*
X1649897Y994537D01*
X1649887Y994636D01*
G01X1656827Y1011860D02*
X1658795Y1013829D01*
G01X1648786Y998829D02*
X1648359Y998238D01*
G01X1648786Y1003829D02*
X1648359Y1003238D01*
G01X1648786Y1008829D02*
X1648359Y1008238D01*
G01X1654531Y997254D02*
X1654670Y997450D01*
X1654808Y997647D01*
X1654945Y997844D01*
G01X1654531Y1002254D02*
X1654670Y1002450D01*
X1654808Y1002647D01*
X1654945Y1002844D01*
G01X1654531Y1007254D02*
X1654670Y1007450D01*
X1654808Y1007647D01*
X1654945Y1007844D01*
G01X1649513Y1007825D02*
X1649486Y1007821D01*
X1649460Y1007810D01*
X1649436Y1007792D01*
X1649415Y1007767D01*
X1649397Y1007737D01*
X1649385Y1007704D01*
X1649377Y1007667D01*
X1649374Y1007628D01*
G01X1649513Y1004675D02*
X1649486Y1004671D01*
X1649460Y1004660D01*
X1649436Y1004642D01*
X1649415Y1004617D01*
X1649397Y1004588D01*
X1649385Y1004554D01*
X1649377Y1004517D01*
X1649374Y1004478D01*
G01X1649513Y1001525D02*
X1649486Y1001522D01*
X1649460Y1001511D01*
X1649436Y1001493D01*
X1649415Y1001468D01*
X1649397Y1001438D01*
X1649385Y1001404D01*
X1649377Y1001368D01*
X1649374Y1001329D01*
G01X1649513Y998376D02*
X1649486Y998372D01*
X1649460Y998361D01*
X1649436Y998343D01*
X1649415Y998318D01*
X1649397Y998289D01*
X1649385Y998255D01*
X1649377Y998218D01*
X1649374Y998179D01*
G01X1654561Y1007037D02*
X1654689Y1007065D01*
X1654777Y1007138D01*
X1654809Y1007234D01*
G01X1654561Y1003888D02*
X1654689Y1003915D01*
X1654777Y1003988D01*
X1654809Y1004085D01*
G01X1654561Y1000738D02*
X1654689Y1000766D01*
X1654777Y1000839D01*
X1654809Y1000935D01*
G01X1654561Y997588D02*
X1654689Y997616D01*
X1654777Y997689D01*
X1654809Y997785D01*
G01X1649203Y998238D02*
X1649476Y998829D01*
G01X1649203Y1003238D02*
X1649476Y1003829D01*
G01X1649203Y1008238D02*
X1649476Y1008829D01*
G01X1662079Y1016781D02*
X1658795D01*
G01X1654531Y1008829D02*
X1648786D01*
G01X1648359Y1008238D02*
X1654945D01*
G01X1648359Y1007844D02*
X1654945D01*
G01X1654561Y1007825D02*
X1648477D01*
G01X1648197Y1007628D02*
X1654809D01*
G01X1654531Y1007254D02*
X1648786D01*
G01X1654809Y1007234D02*
X1648197D01*
G01X1654561Y1007037D02*
X1648477D01*
G01X1654561Y1004675D02*
X1648477D01*
G01X1648197Y1004478D02*
X1654809D01*
G01Y1004085D02*
X1648197D01*
G01X1654561Y1003888D02*
X1648477D01*
G01X1654531Y1003829D02*
X1648786D01*
G01X1648359Y1003238D02*
X1654945D01*
G01X1648359Y1002844D02*
X1654945D01*
G01X1654531Y1002254D02*
X1648786D01*
G01X1654561Y1001525D02*
X1648477D01*
G01X1648197Y1001329D02*
X1654809D01*
G01Y1000935D02*
X1648197D01*
G01X1654561Y1000738D02*
X1648477D01*
G01X1654531Y998829D02*
X1648786D01*
G01X1654561Y998376D02*
X1648477D01*
G01X1648359Y998238D02*
X1654945D01*
G01X1648197Y998179D02*
X1654809D01*
G01X1648359Y997844D02*
X1654945D01*
G01X1654809Y997785D02*
X1648197D01*
G01X1654561Y997588D02*
X1648477D01*
G01X1654531Y997254D02*
X1648786D01*
G01X1650328Y998238D02*
X1650405Y998829D01*
G01Y1003829D02*
X1650328Y1003238D01*
G01Y1008238D02*
X1650405Y1008829D01*
G01X1649887Y998179D02*
X1649897Y998277D01*
X1649925Y998349D01*
X1649964Y998376D01*
G01X1649887Y1001329D02*
X1649897Y1001427D01*
X1649925Y1001499D01*
X1649964Y1001525D01*
G01X1649887Y1004478D02*
X1649897Y1004577D01*
X1649925Y1004649D01*
X1649964Y1004675D01*
G01X1649887Y1007628D02*
X1649897Y1007726D01*
X1649925Y1007798D01*
X1649964Y1007825D01*
G01X1650328Y1007844D02*
X1650405Y1007254D01*
G01Y1002254D02*
X1650328Y1002844D01*
G01Y997844D02*
X1650405Y997254D01*
G01X1654945Y998238D02*
Y997844D01*
G01Y1003238D02*
Y1002844D01*
G01Y1008238D02*
Y1007844D01*
G01X1654809Y1007234D02*
Y1007628D01*
G01Y1004085D02*
Y1004478D01*
G01Y1000935D02*
Y1001329D01*
G01Y997785D02*
Y998179D01*
G01X1650328Y1002844D02*
Y1003238D01*
G01Y998238D02*
Y997844D01*
G01Y1008238D02*
Y1007844D01*
G01X1649887Y1007234D02*
Y1007628D01*
G01Y1004085D02*
Y1004478D01*
G01Y1000935D02*
Y1001329D01*
G01Y997785D02*
Y998179D01*
G01X1649374D02*
Y997785D01*
G01Y1004478D02*
Y1004085D01*
G01Y1001329D02*
Y1000935D01*
G01Y1007628D02*
Y1007234D01*
G01X1649203Y1007844D02*
Y1008238D01*
G01Y1002844D02*
Y1003238D01*
G01Y997844D02*
Y998238D01*
G01X1648359Y1007844D02*
Y1008238D01*
G01Y1002844D02*
Y1003238D01*
G01Y997844D02*
Y998238D01*
G01X1648197Y998179D02*
Y997785D01*
G01Y1004478D02*
Y1004085D01*
G01Y1001329D02*
Y1000935D01*
G01Y1007628D02*
Y1007234D01*
G01X1649374D02*
X1649377Y1007196D01*
X1649385Y1007159D01*
X1649397Y1007125D01*
X1649415Y1007095D01*
X1649436Y1007071D01*
X1649459Y1007052D01*
X1649485Y1007041D01*
X1649513Y1007037D01*
G01X1649374Y1004085D02*
X1649377Y1004046D01*
X1649385Y1004010D01*
X1649397Y1003976D01*
X1649415Y1003945D01*
X1649436Y1003921D01*
X1649459Y1003903D01*
X1649485Y1003892D01*
X1649513Y1003888D01*
G01X1649374Y1000935D02*
X1649377Y1000897D01*
X1649385Y1000860D01*
X1649397Y1000826D01*
X1649415Y1000796D01*
X1649436Y1000771D01*
X1649459Y1000753D01*
X1649485Y1000742D01*
X1649513Y1000738D01*
G01X1649374Y997785D02*
X1649377Y997747D01*
X1649385Y997710D01*
X1649397Y997676D01*
X1649415Y997646D01*
X1649436Y997622D01*
X1649459Y997604D01*
X1649485Y997592D01*
X1649513Y997588D01*
G01X1654809Y1007628D02*
X1654777Y1007725D01*
X1654689Y1007797D01*
X1654561Y1007825D01*
G01X1654809Y1004478D02*
X1654777Y1004575D01*
X1654689Y1004647D01*
X1654561Y1004675D01*
G01X1654809Y1001329D02*
X1654777Y1001426D01*
X1654689Y1001498D01*
X1654561Y1001525D01*
G01X1654809Y998179D02*
X1654777Y998276D01*
X1654689Y998348D01*
X1654561Y998376D01*
G01X1649476Y1007254D02*
X1649203Y1007844D01*
G01X1649476Y1002254D02*
X1649203Y1002844D01*
G01X1649476Y997254D02*
X1649203Y997844D01*
G01X1654945Y1008238D02*
X1654808Y1008436D01*
X1654670Y1008633D01*
X1654531Y1008829D01*
G01X1654945Y1003238D02*
X1654808Y1003436D01*
X1654670Y1003633D01*
X1654531Y1003829D01*
G01X1654945Y998238D02*
X1654808Y998436D01*
X1654670Y998633D01*
X1654531Y998829D01*
G01X1648786Y1007254D02*
X1648359Y1007844D01*
G01X1648786Y1002254D02*
X1648359Y1002844D01*
G01X1648786Y997254D02*
X1648359Y997844D01*
G01X1656827Y1016781D02*
X1658795Y1014813D01*
G01X1649964Y1007037D02*
X1649925Y1007064D01*
X1649897Y1007136D01*
X1649887Y1007234D01*
G01X1649964Y1003888D02*
X1649925Y1003914D01*
X1649897Y1003986D01*
X1649887Y1004085D01*
G01X1649964Y1000738D02*
X1649925Y1000765D01*
X1649897Y1000837D01*
X1649887Y1000935D01*
G01X1649964Y997588D02*
X1649925Y997615D01*
X1649897Y997687D01*
X1649887Y997785D01*
G01X1662079Y1016781D02*
X1665488Y1018750D01*
G01X1660822Y1024398D02*
X1660768Y1024020D01*
G01X1660821Y1024396D02*
X1660858Y1024720D01*
X1660852Y1024961D01*
X1660795Y1025097D01*
G01X1665488Y1018750D02*
Y1020482D01*
G01X1660764Y1016781D02*
Y1023947D01*
G01X1660795Y1025097D02*
X1660853Y1024957D01*
X1660858Y1024717D01*
G01X1665488Y1020482D02*
X1660764Y1025128D01*
G01X1660768Y1024020D02*
X1665488Y1019379D01*
G01X1662079Y1279813D02*
X1658795D01*
G01Y1282766D02*
X1656827Y1284734D01*
G01X1658795Y1281781D02*
X1656827Y1279813D01*
G01X1658795D02*
Y1422293D01*
G01X1657673Y1417766D02*
Y1284340D01*
G01X1657614Y1314951D02*
Y1283947D01*
G01X1662079Y1279813D02*
X1665488Y1277844D01*
G01Y1276112D02*
X1660764Y1271466D01*
G01X1665488Y1277215D02*
X1660768Y1272574D01*
G01X1660795Y1271498D02*
X1660852Y1271632D01*
X1660858Y1271868D01*
X1660822Y1272197D01*
G01X1660795Y1271498D02*
X1660853Y1271638D01*
X1660858Y1271877D01*
G01X1660823Y1272188D02*
X1660768Y1272574D01*
G01X1665488Y1277844D02*
Y1276112D01*
G01X1660764Y1272648D02*
Y1279813D01*
G01X1656827Y1284734D02*
Y1417372D01*
G01X1654561Y1356644D02*
X1648477D01*
G01X1648197Y1356447D02*
X1654809D01*
G01Y1356053D02*
X1648197D01*
G01X1654561Y1355856D02*
X1648477D01*
G01X1654531Y1354340D02*
X1648786D01*
G01X1648359Y1353750D02*
X1654945D01*
G01X1654561Y1353494D02*
X1648477D01*
G01X1648359Y1353356D02*
X1654945D01*
G01X1648197Y1353297D02*
X1654809D01*
G01Y1352903D02*
X1648197D01*
G01X1654531Y1352766D02*
X1648786D01*
G01X1654561Y1352707D02*
X1648477D01*
G01X1649513Y1356644D02*
X1649486Y1356640D01*
X1649460Y1356629D01*
X1649436Y1356611D01*
X1649415Y1356586D01*
X1649397Y1356556D01*
X1649385Y1356522D01*
X1649377Y1356486D01*
X1649374Y1356447D01*
G01X1649513Y1353494D02*
X1649486Y1353490D01*
X1649460Y1353479D01*
X1649436Y1353461D01*
X1649415Y1353436D01*
X1649397Y1353407D01*
X1649385Y1353373D01*
X1649377Y1353336D01*
X1649374Y1353297D01*
G01X1649513Y1350344D02*
X1649486Y1350341D01*
X1649460Y1350330D01*
X1649436Y1350311D01*
X1649415Y1350287D01*
X1649397Y1350257D01*
X1649385Y1350223D01*
X1649377Y1350186D01*
X1649374Y1350148D01*
G01X1649513Y1347195D02*
X1649486Y1347191D01*
X1649460Y1347180D01*
X1649436Y1347162D01*
X1649415Y1347137D01*
X1649397Y1347107D01*
X1649385Y1347074D01*
X1649377Y1347037D01*
X1649374Y1346998D01*
G01X1649513Y1344045D02*
X1649486Y1344041D01*
X1649460Y1344030D01*
X1649436Y1344012D01*
X1649415Y1343988D01*
X1649397Y1343958D01*
X1649385Y1343924D01*
X1649377Y1343887D01*
X1649374Y1343848D01*
G01X1649513Y1340896D02*
X1649486Y1340892D01*
X1649460Y1340881D01*
X1649436Y1340863D01*
X1649415Y1340838D01*
X1649397Y1340808D01*
X1649385Y1340774D01*
X1649377Y1340738D01*
X1649374Y1340699D01*
G01X1649513Y1337746D02*
X1649486Y1337742D01*
X1649460Y1337731D01*
X1649436Y1337713D01*
X1649415Y1337688D01*
X1649397Y1337659D01*
X1649385Y1337625D01*
X1649377Y1337588D01*
X1649374Y1337549D01*
G01X1649513Y1334596D02*
X1649486Y1334593D01*
X1649460Y1334582D01*
X1649436Y1334563D01*
X1649415Y1334539D01*
X1649397Y1334509D01*
X1649385Y1334475D01*
X1649377Y1334438D01*
X1649374Y1334400D01*
G01X1649513Y1331447D02*
X1649486Y1331443D01*
X1649460Y1331432D01*
X1649436Y1331414D01*
X1649415Y1331389D01*
X1649397Y1331359D01*
X1649385Y1331326D01*
X1649377Y1331289D01*
X1649374Y1331250D01*
G01X1649513Y1328297D02*
X1649486Y1328293D01*
X1649460Y1328282D01*
X1649436Y1328264D01*
X1649415Y1328239D01*
X1649397Y1328210D01*
X1649385Y1328176D01*
X1649377Y1328139D01*
X1649374Y1328100D01*
G01X1649513Y1325148D02*
X1649486Y1325144D01*
X1649460Y1325133D01*
X1649436Y1325115D01*
X1649415Y1325090D01*
X1649397Y1325060D01*
X1649385Y1325026D01*
X1649377Y1324990D01*
X1649374Y1324951D01*
G01X1649513Y1321998D02*
X1649486Y1321994D01*
X1649460Y1321983D01*
X1649436Y1321965D01*
X1649415Y1321940D01*
X1649397Y1321911D01*
X1649385Y1321877D01*
X1649377Y1321840D01*
X1649374Y1321801D01*
G01X1649513Y1318848D02*
X1649486Y1318845D01*
X1649460Y1318833D01*
X1649436Y1318815D01*
X1649415Y1318791D01*
X1649397Y1318761D01*
X1649385Y1318727D01*
X1649377Y1318690D01*
X1649374Y1318651D01*
G01X1649513Y1315699D02*
X1649486Y1315695D01*
X1649460Y1315684D01*
X1649436Y1315666D01*
X1649415Y1315641D01*
X1649397Y1315611D01*
X1649385Y1315578D01*
X1649377Y1315541D01*
X1649374Y1315502D01*
G01X1649513Y1312549D02*
X1649486Y1312545D01*
X1649460Y1312534D01*
X1649436Y1312516D01*
X1649415Y1312491D01*
X1649397Y1312462D01*
X1649385Y1312428D01*
X1649377Y1312391D01*
X1649374Y1312352D01*
G01X1649513Y1309400D02*
X1649486Y1309396D01*
X1649460Y1309385D01*
X1649436Y1309367D01*
X1649415Y1309342D01*
X1649397Y1309312D01*
X1649385Y1309278D01*
X1649377Y1309242D01*
X1649374Y1309203D01*
G01X1654571Y1338240D02*
X1654698Y1338268D01*
X1654787Y1338340D01*
X1654819Y1338437D01*
G01X1654571Y1335091D02*
X1654698Y1335118D01*
X1654787Y1335191D01*
X1654819Y1335287D01*
G01X1654571Y1331941D02*
X1654698Y1331968D01*
X1654787Y1332041D01*
X1654819Y1332138D01*
G01X1654571Y1328791D02*
X1654698Y1328819D01*
X1654787Y1328891D01*
X1654819Y1328988D01*
G01X1654571Y1325642D02*
X1654698Y1325669D01*
X1654787Y1325742D01*
X1654819Y1325839D01*
G01X1654571Y1322492D02*
X1654698Y1322520D01*
X1654787Y1322592D01*
X1654819Y1322689D01*
G01X1654561Y1355856D02*
X1654689Y1355884D01*
X1654777Y1355957D01*
X1654809Y1356053D01*
G01X1654561Y1352707D02*
X1654689Y1352734D01*
X1654777Y1352807D01*
X1654809Y1352903D01*
G01X1654561Y1349557D02*
X1654689Y1349585D01*
X1654777Y1349658D01*
X1654809Y1349754D01*
G01X1654561Y1346407D02*
X1654689Y1346435D01*
X1654777Y1346508D01*
X1654809Y1346604D01*
G01X1654561Y1343258D02*
X1654689Y1343286D01*
X1654777Y1343358D01*
X1654809Y1343455D01*
G01X1654561Y1340108D02*
X1654689Y1340136D01*
X1654777Y1340209D01*
X1654809Y1340305D01*
G01X1654561Y1336959D02*
X1654689Y1336986D01*
X1654777Y1337059D01*
X1654809Y1337155D01*
G01X1654561Y1333809D02*
X1654689Y1333837D01*
X1654777Y1333910D01*
X1654809Y1334006D01*
G01X1654561Y1330659D02*
X1654689Y1330687D01*
X1654777Y1330760D01*
X1654809Y1330856D01*
G01X1654561Y1327510D02*
X1654689Y1327537D01*
X1654777Y1327610D01*
X1654809Y1327707D01*
G01X1654561Y1324360D02*
X1654689Y1324388D01*
X1654777Y1324461D01*
X1654809Y1324557D01*
G01X1654561Y1321211D02*
X1654689Y1321238D01*
X1654777Y1321311D01*
X1654809Y1321407D01*
G01X1654561Y1318061D02*
X1654689Y1318089D01*
X1654777Y1318162D01*
X1654809Y1318258D01*
G01X1654561Y1314911D02*
X1654689Y1314939D01*
X1654777Y1315012D01*
X1654809Y1315108D01*
G01X1654561Y1311762D02*
X1654689Y1311789D01*
X1654777Y1311862D01*
X1654809Y1311959D01*
G01X1654561Y1308612D02*
X1654689Y1308640D01*
X1654777Y1308713D01*
X1654809Y1308809D01*
G01X1654561Y1305463D02*
X1654689Y1305490D01*
X1654777Y1305563D01*
X1654809Y1305659D01*
G01X1654561Y1302313D02*
X1654689Y1302341D01*
X1654777Y1302414D01*
X1654809Y1302510D01*
G01X1654561Y1299163D02*
X1654689Y1299191D01*
X1654777Y1299264D01*
X1654809Y1299360D01*
G01X1654561Y1296014D02*
X1654689Y1296041D01*
X1654777Y1296114D01*
X1654809Y1296211D01*
G01X1654561Y1292864D02*
X1654689Y1292892D01*
X1654777Y1292965D01*
X1654809Y1293061D01*
G01X1654561Y1289714D02*
X1654689Y1289742D01*
X1654777Y1289815D01*
X1654809Y1289911D01*
G01X1649590Y1338240D02*
X1649562Y1338244D01*
X1649534Y1338255D01*
X1649509Y1338273D01*
X1649486Y1338298D01*
X1649468Y1338328D01*
X1649454Y1338361D01*
X1649446Y1338398D01*
X1649443Y1338437D01*
G01X1649590Y1335091D02*
X1649562Y1335094D01*
X1649534Y1335105D01*
X1649509Y1335124D01*
X1649486Y1335148D01*
X1649468Y1335178D01*
X1649454Y1335212D01*
X1649446Y1335249D01*
X1649443Y1335287D01*
G01X1649590Y1331941D02*
X1649562Y1331945D01*
X1649534Y1331956D01*
X1649509Y1331974D01*
X1649486Y1331999D01*
X1649468Y1332028D01*
X1649454Y1332062D01*
X1649446Y1332099D01*
X1649443Y1332138D01*
G01X1649590Y1328791D02*
X1649562Y1328795D01*
X1649534Y1328806D01*
X1649509Y1328824D01*
X1649486Y1328849D01*
X1649468Y1328879D01*
X1649454Y1328913D01*
X1649446Y1328949D01*
X1649443Y1328988D01*
G01X1649590Y1325642D02*
X1649562Y1325646D01*
X1649534Y1325657D01*
X1649509Y1325675D01*
X1649486Y1325699D01*
X1649468Y1325729D01*
X1649454Y1325763D01*
X1649446Y1325800D01*
X1649443Y1325839D01*
G01X1649590Y1322492D02*
X1649562Y1322496D01*
X1649534Y1322507D01*
X1649509Y1322525D01*
X1649486Y1322550D01*
X1649468Y1322580D01*
X1649454Y1322613D01*
X1649446Y1322650D01*
X1649443Y1322689D01*
G01X1654561Y1350344D02*
X1648477D01*
G01X1648197Y1350148D02*
X1654809D01*
G01Y1349754D02*
X1648197D01*
G01X1654561Y1349557D02*
X1648477D01*
G01X1654531Y1349340D02*
X1648786D01*
G01X1648359Y1348750D02*
X1654945D01*
G01X1648359Y1348356D02*
X1654945D01*
G01X1654531Y1347766D02*
X1648786D01*
G01X1654561Y1347195D02*
X1648477D01*
G01X1648197Y1346998D02*
X1654809D01*
G01Y1346604D02*
X1648197D01*
G01X1654561Y1346407D02*
X1648477D01*
G01X1654631Y1344340D02*
X1648718D01*
G01X1654561Y1344045D02*
X1648477D01*
G01X1648197Y1343848D02*
X1654809D01*
G01X1648294Y1343750D02*
X1655036D01*
G01X1654809Y1343455D02*
X1648197D01*
G01X1648294Y1343356D02*
X1655036D01*
G01X1654561Y1343258D02*
X1648477D01*
G01X1654631Y1342766D02*
X1648718D01*
G01X1652326Y1341978D02*
X1658795D01*
G01X1654561Y1340896D02*
X1648477D01*
G01X1648197Y1340699D02*
X1654809D01*
G01Y1340305D02*
X1648197D01*
G01X1654561Y1340108D02*
X1648477D01*
G01X1648763Y1339618D02*
X1654571D01*
G01X1654819Y1339421D02*
X1648501D01*
G01Y1338437D02*
X1654819D01*
G01X1648763Y1338240D02*
X1654571D01*
G01X1654561Y1337746D02*
X1648477D01*
G01X1648197Y1337549D02*
X1654809D01*
G01Y1337155D02*
X1648197D01*
G01X1654561Y1336959D02*
X1648477D01*
G01X1648763Y1336469D02*
X1654571D01*
G01X1654819Y1336272D02*
X1648501D01*
G01Y1335287D02*
X1654819D01*
G01X1648763Y1335091D02*
X1654571D01*
G01X1654561Y1334596D02*
X1648477D01*
G01X1648197Y1334400D02*
X1654809D01*
G01Y1334006D02*
X1648197D01*
G01X1654561Y1333809D02*
X1648477D01*
G01X1648763Y1333319D02*
X1654571D01*
G01X1654819Y1333122D02*
X1648501D01*
G01Y1332138D02*
X1654819D01*
G01X1648763Y1331941D02*
X1654571D01*
G01X1654561Y1331447D02*
X1648477D01*
G01X1648197Y1331250D02*
X1654809D01*
G01Y1330856D02*
X1648197D01*
G01X1654561Y1330659D02*
X1648477D01*
G01X1648763Y1330169D02*
X1654571D01*
G01X1654819Y1329973D02*
X1648501D01*
G01Y1328988D02*
X1654819D01*
G01X1648763Y1328791D02*
X1654571D01*
G01X1654561Y1328297D02*
X1648477D01*
G01X1648197Y1328100D02*
X1654809D01*
G01Y1327707D02*
X1648197D01*
G01X1654561Y1327510D02*
X1648477D01*
G01X1648763Y1327020D02*
X1654571D01*
G01X1654819Y1326823D02*
X1648501D01*
G01Y1325839D02*
X1654819D01*
G01X1648763Y1325642D02*
X1654571D01*
G01X1654561Y1325148D02*
X1648477D01*
G01X1648197Y1324951D02*
X1654809D01*
G01Y1324557D02*
X1648197D01*
G01X1654561Y1324360D02*
X1648477D01*
G01X1648763Y1323870D02*
X1654571D01*
G01X1654819Y1323673D02*
X1648501D01*
G01Y1322689D02*
X1654819D01*
G01X1648763Y1322492D02*
X1654571D01*
G01X1654561Y1321998D02*
X1648477D01*
G01X1648197Y1321801D02*
X1654809D01*
G01Y1321407D02*
X1648197D01*
G01X1654561Y1321211D02*
X1648477D01*
G01X1658795Y1320128D02*
X1652326D01*
G01X1654631Y1319340D02*
X1648718D01*
G01X1654561Y1318848D02*
X1648477D01*
G01X1648294Y1318750D02*
X1655036D01*
G01X1648197Y1318651D02*
X1654809D01*
G01X1648294Y1318356D02*
X1655036D01*
G01X1654809Y1318258D02*
X1648197D01*
G01X1654561Y1318061D02*
X1648477D01*
G01X1654631Y1317766D02*
X1648718D01*
G01X1654561Y1315699D02*
X1648477D01*
G01X1648197Y1315502D02*
X1654809D01*
G01Y1315108D02*
X1648197D01*
G01X1654561Y1314911D02*
X1648477D01*
G01X1654531Y1314340D02*
X1648786D01*
G01X1648359Y1313750D02*
X1654945D01*
G01X1648359Y1313356D02*
X1654945D01*
G01X1654531Y1312766D02*
X1648786D01*
G01X1654561Y1312549D02*
X1648477D01*
G01X1648197Y1312352D02*
X1654809D01*
G01Y1311959D02*
X1648197D01*
G01X1654561Y1311762D02*
X1648477D01*
G01X1654561Y1309400D02*
X1648477D01*
G01X1654531Y1309340D02*
X1648786D01*
G01X1648197Y1309203D02*
X1654809D01*
G01Y1308809D02*
X1648197D01*
G01X1648359Y1308750D02*
X1654945D01*
G01X1654561Y1308612D02*
X1648477D01*
G01X1648359Y1308356D02*
X1654945D01*
G01X1654531Y1307766D02*
X1648786D01*
G01X1654561Y1306250D02*
X1648477D01*
G01X1648197Y1306053D02*
X1654809D01*
G01Y1305659D02*
X1648197D01*
G01X1654561Y1305463D02*
X1648477D01*
G01X1654531Y1304340D02*
X1648786D01*
G01X1648359Y1303750D02*
X1654945D01*
G01X1648359Y1303356D02*
X1654945D01*
G01X1654561Y1303100D02*
X1648477D01*
G01X1648197Y1302903D02*
X1654809D01*
G01X1654531Y1302766D02*
X1648786D01*
G01X1654809Y1302510D02*
X1648197D01*
G01X1654561Y1302313D02*
X1648477D01*
G01X1654561Y1299951D02*
X1648477D01*
G01X1648197Y1299754D02*
X1654809D01*
G01Y1299360D02*
X1648197D01*
G01X1654531Y1299340D02*
X1648786D01*
G01X1654561Y1299163D02*
X1648477D01*
G01X1648359Y1298750D02*
X1654945D01*
G01X1648359Y1298356D02*
X1654945D01*
G01X1654531Y1297766D02*
X1648786D01*
G01X1654561Y1296801D02*
X1648477D01*
G01X1648197Y1296604D02*
X1654809D01*
G01Y1296211D02*
X1648197D01*
G01X1654561Y1296014D02*
X1648477D01*
G01X1654531Y1294340D02*
X1648786D01*
G01X1648359Y1293750D02*
X1654945D01*
G01X1654561Y1293651D02*
X1648477D01*
G01X1648197Y1293455D02*
X1654809D01*
G01X1648359Y1293356D02*
X1654945D01*
G01X1654809Y1293061D02*
X1648197D01*
G01X1654561Y1292864D02*
X1648477D01*
G01X1654531Y1292766D02*
X1648786D01*
G01X1654561Y1290502D02*
X1648477D01*
G01X1648197Y1290305D02*
X1654809D01*
G01Y1289911D02*
X1648197D01*
G01X1654561Y1289714D02*
X1648477D01*
G01X1654531Y1289340D02*
X1648786D01*
G01X1648359Y1288750D02*
X1654945D01*
G01X1648359Y1288356D02*
X1654945D01*
G01X1654531Y1287766D02*
X1648786D01*
G01X1649513Y1306250D02*
X1649486Y1306246D01*
X1649460Y1306235D01*
X1649436Y1306217D01*
X1649415Y1306192D01*
X1649397Y1306163D01*
X1649385Y1306129D01*
X1649377Y1306092D01*
X1649374Y1306053D01*
G01X1649513Y1303100D02*
X1649486Y1303097D01*
X1649460Y1303085D01*
X1649436Y1303067D01*
X1649415Y1303043D01*
X1649397Y1303013D01*
X1649385Y1302979D01*
X1649377Y1302942D01*
X1649374Y1302903D01*
G01X1649513Y1299951D02*
X1649486Y1299947D01*
X1649460Y1299936D01*
X1649436Y1299918D01*
X1649415Y1299893D01*
X1649397Y1299863D01*
X1649385Y1299829D01*
X1649377Y1299793D01*
X1649374Y1299754D01*
G01X1649513Y1296801D02*
X1649486Y1296797D01*
X1649460Y1296786D01*
X1649436Y1296768D01*
X1649415Y1296743D01*
X1649397Y1296714D01*
X1649385Y1296680D01*
X1649377Y1296643D01*
X1649374Y1296604D01*
G01X1649513Y1293651D02*
X1649486Y1293648D01*
X1649460Y1293637D01*
X1649436Y1293619D01*
X1649415Y1293594D01*
X1649397Y1293564D01*
X1649385Y1293530D01*
X1649377Y1293494D01*
X1649374Y1293455D01*
G01X1649513Y1290502D02*
X1649486Y1290498D01*
X1649460Y1290487D01*
X1649436Y1290469D01*
X1649415Y1290444D01*
X1649397Y1290415D01*
X1649385Y1290381D01*
X1649377Y1290344D01*
X1649374Y1290305D01*
G01X1649964Y1355856D02*
X1649925Y1355883D01*
X1649897Y1355955D01*
X1649887Y1356053D01*
G01X1649964Y1352707D02*
X1649925Y1352733D01*
X1649897Y1352805D01*
X1649887Y1352903D01*
G01X1649964Y1349557D02*
X1649925Y1349583D01*
X1649897Y1349655D01*
X1649887Y1349754D01*
G01X1649964Y1346407D02*
X1649925Y1346434D01*
X1649897Y1346506D01*
X1649887Y1346604D01*
G01X1649964Y1343258D02*
X1649925Y1343284D01*
X1649897Y1343356D01*
X1649887Y1343455D01*
G01X1649964Y1340108D02*
X1649925Y1340135D01*
X1649897Y1340207D01*
X1649887Y1340305D01*
G01X1649964Y1336959D02*
X1649925Y1336985D01*
X1649897Y1337057D01*
X1649887Y1337155D01*
G01X1649964Y1333809D02*
X1649925Y1333835D01*
X1649897Y1333907D01*
X1649887Y1334006D01*
G01X1649964Y1330659D02*
X1649925Y1330686D01*
X1649897Y1330758D01*
X1649887Y1330856D01*
G01X1649964Y1327510D02*
X1649925Y1327536D01*
X1649897Y1327608D01*
X1649887Y1327707D01*
G01X1649964Y1324360D02*
X1649925Y1324387D01*
X1649897Y1324459D01*
X1649887Y1324557D01*
G01X1649964Y1321211D02*
X1649925Y1321237D01*
X1649897Y1321309D01*
X1649887Y1321407D01*
G01X1649964Y1318061D02*
X1649925Y1318087D01*
X1649897Y1318159D01*
X1649887Y1318258D01*
G01X1649964Y1314911D02*
X1649925Y1314938D01*
X1649897Y1315010D01*
X1649887Y1315108D01*
G01X1649964Y1311762D02*
X1649925Y1311788D01*
X1649897Y1311860D01*
X1649887Y1311959D01*
G01X1649964Y1308612D02*
X1649925Y1308639D01*
X1649897Y1308711D01*
X1649887Y1308809D01*
G01X1650627Y1338240D02*
X1650621Y1338244D01*
X1650615Y1338255D01*
X1650609Y1338273D01*
X1650604Y1338298D01*
X1650600Y1338328D01*
X1650597Y1338361D01*
X1650595Y1338398D01*
Y1338437D01*
G01X1650627Y1335091D02*
X1650621Y1335094D01*
X1650615Y1335105D01*
X1650609Y1335124D01*
X1650604Y1335148D01*
X1650600Y1335178D01*
X1650597Y1335212D01*
X1650595Y1335249D01*
Y1335287D01*
G01X1650627Y1331941D02*
X1650621Y1331945D01*
X1650615Y1331956D01*
X1650609Y1331974D01*
X1650604Y1331999D01*
X1650600Y1332028D01*
X1650597Y1332062D01*
X1650595Y1332099D01*
Y1332138D01*
G01X1650627Y1328791D02*
X1650621Y1328795D01*
X1650615Y1328806D01*
X1650609Y1328824D01*
X1650604Y1328849D01*
X1650600Y1328879D01*
X1650597Y1328913D01*
X1650595Y1328949D01*
Y1328988D01*
G01X1650627Y1325642D02*
X1650621Y1325646D01*
X1650615Y1325657D01*
X1650609Y1325675D01*
X1650604Y1325699D01*
X1650600Y1325729D01*
X1650597Y1325763D01*
X1650595Y1325800D01*
Y1325839D01*
G01X1650627Y1322492D02*
X1650621Y1322496D01*
X1650615Y1322507D01*
X1650609Y1322525D01*
X1650604Y1322550D01*
X1650600Y1322580D01*
X1650597Y1322613D01*
X1650595Y1322650D01*
Y1322689D01*
G01X1655036Y1343750D02*
X1654902Y1343947D01*
X1654767Y1344144D01*
X1654631Y1344340D01*
G01X1654945Y1353750D02*
X1654808Y1353948D01*
X1654670Y1354144D01*
X1654531Y1354340D01*
G01X1654945Y1348750D02*
X1654808Y1348948D01*
X1654670Y1349144D01*
X1654531Y1349340D01*
G01X1648718Y1342766D02*
X1648294Y1343356D01*
G01X1648786Y1352766D02*
X1648359Y1353356D01*
G01X1648786Y1347766D02*
X1648359Y1348356D01*
G01X1656827Y1321289D02*
X1658795Y1319321D01*
G01X1649964Y1305463D02*
X1649925Y1305489D01*
X1649897Y1305561D01*
X1649887Y1305659D01*
G01X1649964Y1302313D02*
X1649925Y1302339D01*
X1649897Y1302411D01*
X1649887Y1302510D01*
G01X1649964Y1299163D02*
X1649925Y1299190D01*
X1649897Y1299262D01*
X1649887Y1299360D01*
G01X1649964Y1296014D02*
X1649925Y1296040D01*
X1649897Y1296112D01*
X1649887Y1296211D01*
G01X1649964Y1292864D02*
X1649925Y1292891D01*
X1649897Y1292963D01*
X1649887Y1293061D01*
G01X1649964Y1289714D02*
X1649925Y1289741D01*
X1649897Y1289813D01*
X1649887Y1289911D01*
G01X1649964Y1290502D02*
X1649925Y1290475D01*
X1649897Y1290403D01*
X1649887Y1290305D01*
G01X1649964Y1299951D02*
X1649925Y1299924D01*
X1649897Y1299852D01*
X1649887Y1299754D01*
G01X1649964Y1303100D02*
X1649925Y1303074D01*
X1649897Y1303002D01*
X1649887Y1302903D01*
G01X1649964Y1306250D02*
X1649925Y1306223D01*
X1649897Y1306151D01*
X1649887Y1306053D01*
G01X1654809Y1356447D02*
X1654777Y1356544D01*
X1654689Y1356616D01*
X1654561Y1356644D01*
G01X1654809Y1353297D02*
X1654777Y1353394D01*
X1654689Y1353466D01*
X1654561Y1353494D01*
G01X1654809Y1350148D02*
X1654777Y1350245D01*
X1654689Y1350317D01*
X1654561Y1350344D01*
G01X1654809Y1346998D02*
X1654777Y1347095D01*
X1654689Y1347167D01*
X1654561Y1347195D01*
G01X1654809Y1343848D02*
X1654777Y1343945D01*
X1654689Y1344018D01*
X1654561Y1344045D01*
G01X1654809Y1340699D02*
X1654777Y1340796D01*
X1654689Y1340868D01*
X1654561Y1340896D01*
G01X1654809Y1337549D02*
X1654777Y1337646D01*
X1654689Y1337718D01*
X1654561Y1337746D01*
G01X1654809Y1334400D02*
X1654777Y1334497D01*
X1654689Y1334569D01*
X1654561Y1334596D01*
G01X1654809Y1331250D02*
X1654777Y1331347D01*
X1654689Y1331419D01*
X1654561Y1331447D01*
G01X1654809Y1328100D02*
X1654777Y1328197D01*
X1654689Y1328269D01*
X1654561Y1328297D01*
G01X1654809Y1324951D02*
X1654777Y1325048D01*
X1654689Y1325120D01*
X1654561Y1325148D01*
G01X1654809Y1321801D02*
X1654777Y1321898D01*
X1654689Y1321970D01*
X1654561Y1321998D01*
G01X1654809Y1318651D02*
X1654777Y1318748D01*
X1654689Y1318821D01*
X1654561Y1318848D01*
G01X1654809Y1315502D02*
X1654777Y1315599D01*
X1654689Y1315671D01*
X1654561Y1315699D01*
G01X1654809Y1312352D02*
X1654777Y1312449D01*
X1654689Y1312521D01*
X1654561Y1312549D01*
G01X1654809Y1309203D02*
X1654777Y1309300D01*
X1654689Y1309372D01*
X1654561Y1309400D01*
G01X1654809Y1306053D02*
X1654777Y1306150D01*
X1654689Y1306222D01*
X1654561Y1306250D01*
G01X1654809Y1302903D02*
X1654777Y1303000D01*
X1654689Y1303073D01*
X1654561Y1303100D01*
G01X1654809Y1299754D02*
X1654777Y1299851D01*
X1654689Y1299923D01*
X1654561Y1299951D01*
G01X1654809Y1296604D02*
X1654777Y1296701D01*
X1654689Y1296773D01*
X1654561Y1296801D01*
G01X1654809Y1293455D02*
X1654777Y1293552D01*
X1654689Y1293624D01*
X1654561Y1293651D01*
G01X1654809Y1290305D02*
X1654777Y1290402D01*
X1654689Y1290474D01*
X1654561Y1290502D01*
G01X1654819Y1339421D02*
X1654785Y1339520D01*
X1654697Y1339591D01*
X1654571Y1339618D01*
G01X1654819Y1336272D02*
X1654785Y1336371D01*
X1654697Y1336442D01*
X1654571Y1336469D01*
G01X1654819Y1333122D02*
X1654785Y1333221D01*
X1654697Y1333292D01*
X1654571Y1333319D01*
G01X1654819Y1329973D02*
X1654785Y1330072D01*
X1654697Y1330142D01*
X1654571Y1330169D01*
G01X1654819Y1326823D02*
X1654785Y1326922D01*
X1654697Y1326993D01*
X1654571Y1327020D01*
G01X1654819Y1323673D02*
X1654785Y1323772D01*
X1654697Y1323843D01*
X1654571Y1323870D01*
G01X1649476Y1352766D02*
X1649203Y1353356D01*
G01X1649476Y1347766D02*
X1649203Y1348356D01*
G01X1649476Y1342766D02*
X1649203Y1343356D01*
G01X1649476Y1317766D02*
X1649203Y1318356D01*
G01X1649476Y1312766D02*
X1649203Y1313356D01*
G01X1649476Y1307766D02*
X1649203Y1308356D01*
G01X1649476Y1302766D02*
X1649203Y1303356D01*
G01X1649476Y1297766D02*
X1649203Y1298356D01*
G01X1649476Y1292766D02*
X1649203Y1293356D01*
G01X1649476Y1287766D02*
X1649203Y1288356D01*
G01X1655036Y1318750D02*
X1654902Y1318947D01*
X1654767Y1319144D01*
X1654631Y1319340D01*
G01X1654945Y1313750D02*
X1654808Y1313948D01*
X1654670Y1314144D01*
X1654531Y1314340D01*
G01X1654945Y1308750D02*
X1654808Y1308948D01*
X1654670Y1309144D01*
X1654531Y1309340D01*
G01X1654945Y1303750D02*
X1654808Y1303948D01*
X1654670Y1304144D01*
X1654531Y1304340D01*
G01X1654945Y1298750D02*
X1654808Y1298948D01*
X1654670Y1299144D01*
X1654531Y1299340D01*
G01X1654945Y1293750D02*
X1654808Y1293948D01*
X1654670Y1294144D01*
X1654531Y1294340D01*
G01X1654945Y1288750D02*
X1654808Y1288948D01*
X1654670Y1289144D01*
X1654531Y1289340D01*
G01X1648718Y1317766D02*
X1648294Y1318356D01*
G01X1648786Y1312766D02*
X1648359Y1313356D01*
G01X1648786Y1307766D02*
X1648359Y1308356D01*
G01X1648786Y1302766D02*
X1648359Y1303356D01*
G01X1648786Y1297766D02*
X1648359Y1298356D01*
G01X1648786Y1292766D02*
X1648359Y1293356D01*
G01X1648786Y1287766D02*
X1648359Y1288356D01*
G01X1649964Y1315699D02*
X1649925Y1315672D01*
X1649897Y1315600D01*
X1649887Y1315502D01*
G01X1649964Y1318848D02*
X1649925Y1318822D01*
X1649897Y1318750D01*
X1649887Y1318651D01*
G01X1649964Y1334596D02*
X1649925Y1334570D01*
X1649897Y1334498D01*
X1649887Y1334400D01*
G01X1658795Y1342785D02*
X1656827Y1340817D01*
G01X1648786Y1289340D02*
X1648359Y1288750D01*
G01X1648786Y1294340D02*
X1648359Y1293750D01*
G01X1648786Y1299340D02*
X1648359Y1298750D01*
G01X1648786Y1304340D02*
X1648359Y1303750D01*
G01X1648786Y1309340D02*
X1648359Y1308750D01*
G01X1648786Y1314340D02*
X1648359Y1313750D01*
G01X1648718Y1319340D02*
X1648294Y1318750D01*
G01X1654531Y1287766D02*
X1654670Y1287962D01*
X1654808Y1288159D01*
X1654945Y1288356D01*
G01X1654531Y1292766D02*
X1654670Y1292962D01*
X1654808Y1293159D01*
X1654945Y1293356D01*
G01X1654531Y1297766D02*
X1654670Y1297962D01*
X1654808Y1298159D01*
X1654945Y1298356D01*
G01X1654531Y1302766D02*
X1654670Y1302962D01*
X1654808Y1303159D01*
X1654945Y1303356D01*
G01X1654531Y1307766D02*
X1654670Y1307962D01*
X1654808Y1308159D01*
X1654945Y1308356D01*
G01X1654531Y1312766D02*
X1654670Y1312962D01*
X1654808Y1313159D01*
X1654945Y1313356D01*
G01X1654631Y1317766D02*
X1654767Y1317962D01*
X1654902Y1318159D01*
X1655036Y1318356D01*
G01X1650328Y1353356D02*
X1650405Y1352766D01*
G01X1650328Y1348356D02*
X1650405Y1347766D01*
G01X1650328Y1343356D02*
X1650405Y1342766D01*
G01X1650328Y1318356D02*
X1650405Y1317766D01*
G01X1650328Y1313356D02*
X1650405Y1312766D01*
G01X1650328Y1308356D02*
X1650405Y1307766D01*
G01X1650328Y1303356D02*
X1650405Y1302766D01*
G01X1650328Y1298356D02*
X1650405Y1297766D01*
G01X1650328Y1293356D02*
X1650405Y1292766D01*
G01X1650328Y1288356D02*
X1650405Y1287766D01*
G01X1648786Y1349340D02*
X1648359Y1348750D01*
G01X1648786Y1354340D02*
X1648359Y1353750D01*
G01X1648718Y1344340D02*
X1648294Y1343750D01*
G01X1654531Y1347766D02*
X1654670Y1347962D01*
X1654808Y1348159D01*
X1654945Y1348356D01*
G01X1654531Y1352766D02*
X1654670Y1352962D01*
X1654808Y1353159D01*
X1654945Y1353356D01*
G01X1654631Y1342766D02*
X1654767Y1342962D01*
X1654902Y1343159D01*
X1655036Y1343356D01*
G01X1649203Y1288750D02*
X1649476Y1289340D01*
G01X1649203Y1293750D02*
X1649476Y1294340D01*
G01X1649203Y1298750D02*
X1649476Y1299340D01*
G01X1649203Y1303750D02*
X1649476Y1304340D01*
G01X1649203Y1308750D02*
X1649476Y1309340D01*
G01X1649203Y1313750D02*
X1649476Y1314340D01*
G01X1649203Y1318750D02*
X1649476Y1319340D01*
G01X1649203Y1343750D02*
X1649476Y1344340D01*
G01X1649203Y1348750D02*
X1649476Y1349340D01*
G01X1649203Y1353750D02*
X1649476Y1354340D01*
G01X1650328Y1288750D02*
X1650405Y1289340D01*
G01X1650328Y1293750D02*
X1650405Y1294340D01*
G01X1650328Y1298750D02*
X1650405Y1299340D01*
G01X1650328Y1303750D02*
X1650405Y1304340D01*
G01X1650328Y1308750D02*
X1650405Y1309340D01*
G01X1650328Y1313750D02*
X1650405Y1314340D01*
G01X1650328Y1318750D02*
X1650405Y1319340D01*
G01X1650328Y1343750D02*
X1650405Y1344340D01*
G01X1650328Y1348750D02*
X1650405Y1349340D01*
G01X1650328Y1353750D02*
X1650405Y1354340D01*
G01X1649887Y1293455D02*
X1649897Y1293553D01*
X1649925Y1293625D01*
X1649964Y1293651D01*
G01X1649887Y1296604D02*
X1649897Y1296703D01*
X1649925Y1296775D01*
X1649964Y1296801D01*
G01X1649887Y1309203D02*
X1649897Y1309301D01*
X1649925Y1309373D01*
X1649964Y1309400D01*
G01X1649887Y1312352D02*
X1649897Y1312451D01*
X1649925Y1312523D01*
X1649964Y1312549D01*
G01X1649887Y1321801D02*
X1649897Y1321899D01*
X1649925Y1321972D01*
X1649964Y1321998D01*
G01X1649887Y1324951D02*
X1649897Y1325049D01*
X1649925Y1325121D01*
X1649964Y1325148D01*
G01X1649887Y1328100D02*
X1649897Y1328199D01*
X1649925Y1328271D01*
X1649964Y1328297D01*
G01X1649887Y1331250D02*
X1649897Y1331348D01*
X1649925Y1331420D01*
X1649964Y1331447D01*
G01X1649887Y1337549D02*
X1649897Y1337647D01*
X1649925Y1337720D01*
X1649964Y1337746D01*
G01X1649887Y1340699D02*
X1649897Y1340797D01*
X1649925Y1340869D01*
X1649964Y1340896D01*
G01X1649887Y1343848D02*
X1649897Y1343947D01*
X1649925Y1344019D01*
X1649964Y1344045D01*
G01X1649887Y1346998D02*
X1649897Y1347096D01*
X1649925Y1347168D01*
X1649964Y1347195D01*
G01X1649887Y1350148D02*
X1649897Y1350246D01*
X1649925Y1350318D01*
X1649964Y1350344D01*
G01X1649887Y1353297D02*
X1649897Y1353395D01*
X1649925Y1353468D01*
X1649964Y1353494D01*
G01X1649887Y1356447D02*
X1649897Y1356545D01*
X1649925Y1356617D01*
X1649964Y1356644D01*
G01X1649443Y1323673D02*
X1649445Y1323712D01*
X1649454Y1323748D01*
X1649467Y1323782D01*
X1649486Y1323813D01*
X1649508Y1323837D01*
X1649534Y1323855D01*
X1649561Y1323866D01*
X1649590Y1323870D01*
G01X1649443Y1326823D02*
X1649445Y1326861D01*
X1649454Y1326898D01*
X1649467Y1326932D01*
X1649486Y1326962D01*
X1649508Y1326987D01*
X1649534Y1327005D01*
X1649561Y1327016D01*
X1649590Y1327020D01*
G01X1649443Y1329973D02*
X1649445Y1330011D01*
X1649454Y1330048D01*
X1649467Y1330081D01*
X1649486Y1330112D01*
X1649508Y1330136D01*
X1649534Y1330154D01*
X1649561Y1330165D01*
X1649590Y1330169D01*
G01X1649443Y1333122D02*
X1649445Y1333160D01*
X1649454Y1333197D01*
X1649467Y1333231D01*
X1649486Y1333261D01*
X1649508Y1333286D01*
X1649534Y1333304D01*
X1649561Y1333315D01*
X1649590Y1333319D01*
G01X1649443Y1336272D02*
X1649445Y1336310D01*
X1649454Y1336347D01*
X1649467Y1336381D01*
X1649486Y1336411D01*
X1649508Y1336435D01*
X1649534Y1336453D01*
X1649561Y1336465D01*
X1649590Y1336469D01*
G01X1649443Y1339421D02*
X1649445Y1339460D01*
X1649454Y1339496D01*
X1649467Y1339530D01*
X1649486Y1339561D01*
X1649508Y1339585D01*
X1649534Y1339603D01*
X1649561Y1339614D01*
X1649590Y1339618D01*
G01X1650595Y1323673D02*
Y1323712D01*
X1650597Y1323748D01*
X1650600Y1323782D01*
X1650604Y1323813D01*
X1650609Y1323837D01*
X1650615Y1323855D01*
X1650621Y1323866D01*
X1650627Y1323870D01*
G01X1650595Y1326823D02*
Y1326861D01*
X1650597Y1326898D01*
X1650600Y1326932D01*
X1650604Y1326962D01*
X1650609Y1326987D01*
X1650615Y1327005D01*
X1650621Y1327016D01*
X1650627Y1327020D01*
G01X1650595Y1329973D02*
Y1330011D01*
X1650597Y1330048D01*
X1650600Y1330081D01*
X1650604Y1330112D01*
X1650609Y1330136D01*
X1650615Y1330154D01*
X1650621Y1330165D01*
X1650627Y1330169D01*
G01X1650595Y1333122D02*
Y1333160D01*
X1650597Y1333197D01*
X1650600Y1333231D01*
X1650604Y1333261D01*
X1650609Y1333286D01*
X1650615Y1333304D01*
X1650621Y1333315D01*
X1650627Y1333319D01*
G01X1650595Y1336272D02*
Y1336310D01*
X1650597Y1336347D01*
X1650600Y1336381D01*
X1650604Y1336411D01*
X1650609Y1336435D01*
X1650615Y1336453D01*
X1650621Y1336465D01*
X1650627Y1336469D01*
G01X1650595Y1339421D02*
Y1339460D01*
X1650597Y1339496D01*
X1650600Y1339530D01*
X1650604Y1339561D01*
X1650609Y1339585D01*
X1650615Y1339603D01*
X1650621Y1339614D01*
X1650627Y1339618D01*
G01X1657784Y1320332D02*
Y1314951D01*
G01Y1347254D02*
Y1341774D01*
G01X1657614Y1320128D02*
Y1341978D01*
G01Y1418159D02*
Y1347254D01*
G01X1655036Y1318750D02*
Y1318356D01*
G01Y1343750D02*
Y1343356D01*
G01X1654945Y1288750D02*
Y1288356D01*
G01Y1293750D02*
Y1293356D01*
G01Y1298750D02*
Y1298356D01*
G01Y1303750D02*
Y1303356D01*
G01Y1308750D02*
Y1308356D01*
G01Y1313750D02*
Y1313356D01*
G01Y1348750D02*
Y1348356D01*
G01Y1353750D02*
Y1353356D01*
G01X1654819Y1323673D02*
Y1322689D01*
G01Y1326823D02*
Y1325839D01*
G01Y1329973D02*
Y1328988D01*
G01Y1333122D02*
Y1332138D01*
G01Y1336272D02*
Y1335287D01*
G01Y1339421D02*
Y1338437D01*
G01X1654809Y1356053D02*
Y1356447D01*
G01Y1352903D02*
Y1353297D01*
G01Y1349754D02*
Y1350148D01*
G01Y1346604D02*
Y1346998D01*
G01Y1343455D02*
Y1343848D01*
G01Y1340305D02*
Y1340699D01*
G01Y1334006D02*
Y1334400D01*
G01Y1337155D02*
Y1337549D01*
G01Y1330856D02*
Y1331250D01*
G01Y1324557D02*
Y1324951D01*
G01Y1327707D02*
Y1328100D01*
G01Y1321407D02*
Y1321801D01*
G01Y1318258D02*
Y1318651D01*
G01Y1315108D02*
Y1315502D01*
G01Y1311959D02*
Y1312352D01*
G01Y1308809D02*
Y1309203D01*
G01Y1305659D02*
Y1306053D01*
G01Y1302510D02*
Y1302903D01*
G01Y1299360D02*
Y1299754D01*
G01Y1296211D02*
Y1296604D01*
G01Y1293061D02*
Y1293455D01*
G01Y1289911D02*
Y1290305D01*
G01X1652326Y1321309D02*
Y1320128D01*
G01Y1341978D02*
Y1340797D01*
G01X1650595Y1338437D02*
Y1339421D01*
G01Y1332138D02*
Y1333122D01*
G01Y1335287D02*
Y1336272D01*
G01Y1328988D02*
Y1329973D01*
G01Y1322689D02*
Y1323673D01*
G01Y1325839D02*
Y1326823D01*
G01X1650328Y1288750D02*
Y1288356D01*
G01Y1293750D02*
Y1293356D01*
G01Y1298750D02*
Y1298356D01*
G01Y1303750D02*
Y1303356D01*
G01Y1308750D02*
Y1308356D01*
G01Y1313750D02*
Y1313356D01*
G01Y1318750D02*
Y1318356D01*
G01Y1343750D02*
Y1343356D01*
G01Y1348750D02*
Y1348356D01*
G01Y1353750D02*
Y1353356D01*
G01X1649887Y1356053D02*
Y1356447D01*
G01Y1352903D02*
Y1353297D01*
G01Y1349754D02*
Y1350148D01*
G01Y1346604D02*
Y1346998D01*
G01Y1343455D02*
Y1343848D01*
G01Y1340305D02*
Y1340699D01*
G01Y1334006D02*
Y1334400D01*
G01Y1337155D02*
Y1337549D01*
G01Y1330856D02*
Y1331250D01*
G01Y1324557D02*
Y1324951D01*
G01Y1327707D02*
Y1328100D01*
G01Y1321407D02*
Y1321801D01*
G01Y1318258D02*
Y1318651D01*
G01Y1315108D02*
Y1315502D01*
G01Y1311959D02*
Y1312352D01*
G01Y1308809D02*
Y1309203D01*
G01Y1305659D02*
Y1306053D01*
G01Y1302510D02*
Y1302903D01*
G01Y1299360D02*
Y1299754D01*
G01Y1296211D02*
Y1296604D01*
G01Y1293061D02*
Y1293455D01*
G01Y1289911D02*
Y1290305D01*
G01X1649443Y1338437D02*
Y1339421D01*
G01Y1332138D02*
Y1333122D01*
G01Y1335287D02*
Y1336272D01*
G01Y1328988D02*
Y1329973D01*
G01Y1322689D02*
Y1323673D01*
G01Y1325839D02*
Y1326823D01*
G01X1649374Y1290305D02*
Y1289911D01*
G01Y1293455D02*
Y1293061D01*
G01Y1299754D02*
Y1299360D01*
G01Y1296604D02*
Y1296211D01*
G01Y1302903D02*
Y1302510D01*
G01Y1309203D02*
Y1308809D01*
G01Y1306053D02*
Y1305659D01*
G01Y1312352D02*
Y1311959D01*
G01Y1318651D02*
Y1318258D01*
G01Y1315502D02*
Y1315108D01*
G01Y1321801D02*
Y1321407D01*
G01Y1324951D02*
Y1324557D01*
G01Y1328100D02*
Y1327707D01*
G01Y1331250D02*
Y1330856D01*
G01Y1334400D02*
Y1334006D01*
G01Y1337549D02*
Y1337155D01*
G01Y1340699D02*
Y1340305D01*
G01Y1343848D02*
Y1343455D01*
G01Y1350148D02*
Y1349754D01*
G01Y1346998D02*
Y1346604D01*
G01Y1353297D02*
Y1352903D01*
G01Y1356447D02*
Y1356053D01*
G01X1649203Y1353356D02*
Y1353750D01*
G01Y1348356D02*
Y1348750D01*
G01Y1343356D02*
Y1343750D01*
G01Y1318356D02*
Y1318750D01*
G01Y1313356D02*
Y1313750D01*
G01Y1308356D02*
Y1308750D01*
G01Y1303356D02*
Y1303750D01*
G01Y1298356D02*
Y1298750D01*
G01Y1293356D02*
Y1293750D01*
G01Y1288356D02*
Y1288750D01*
G01X1648501Y1338437D02*
Y1339421D01*
G01Y1332138D02*
Y1333122D01*
G01Y1335287D02*
Y1336272D01*
G01Y1328988D02*
Y1329973D01*
G01Y1322689D02*
Y1323673D01*
G01Y1325839D02*
Y1326823D01*
G01X1648359Y1353356D02*
Y1353750D01*
G01Y1348356D02*
Y1348750D01*
G01Y1313356D02*
Y1313750D01*
G01Y1308356D02*
Y1308750D01*
G01Y1303356D02*
Y1303750D01*
G01Y1298356D02*
Y1298750D01*
G01Y1293356D02*
Y1293750D01*
G01Y1288356D02*
Y1288750D01*
G01X1648294Y1343356D02*
Y1343750D01*
G01Y1318356D02*
Y1318750D01*
G01X1648197Y1290305D02*
Y1289911D01*
G01Y1293455D02*
Y1293061D01*
G01Y1299754D02*
Y1299360D01*
G01Y1296604D02*
Y1296211D01*
G01Y1302903D02*
Y1302510D01*
G01Y1309203D02*
Y1308809D01*
G01Y1306053D02*
Y1305659D01*
G01Y1312352D02*
Y1311959D01*
G01Y1318651D02*
Y1318258D01*
G01Y1315502D02*
Y1315108D01*
G01Y1321801D02*
Y1321407D01*
G01Y1324951D02*
Y1324557D01*
G01Y1328100D02*
Y1327707D01*
G01Y1331250D02*
Y1330856D01*
G01Y1334400D02*
Y1334006D01*
G01Y1337549D02*
Y1337155D01*
G01Y1340699D02*
Y1340305D01*
G01Y1343848D02*
Y1343455D01*
G01Y1350148D02*
Y1349754D01*
G01Y1346998D02*
Y1346604D01*
G01Y1353297D02*
Y1352903D01*
G01Y1356447D02*
Y1356053D01*
G01X1649374D02*
X1649377Y1356015D01*
X1649385Y1355978D01*
X1649397Y1355944D01*
X1649415Y1355914D01*
X1649436Y1355889D01*
X1649459Y1355871D01*
X1649485Y1355860D01*
X1649513Y1355856D01*
G01X1649374Y1352903D02*
X1649377Y1352865D01*
X1649385Y1352828D01*
X1649397Y1352795D01*
X1649415Y1352764D01*
X1649436Y1352740D01*
X1649459Y1352722D01*
X1649485Y1352710D01*
X1649513Y1352707D01*
G01X1649374Y1349754D02*
X1649377Y1349716D01*
X1649385Y1349679D01*
X1649397Y1349645D01*
X1649415Y1349615D01*
X1649436Y1349590D01*
X1649459Y1349572D01*
X1649485Y1349561D01*
X1649513Y1349557D01*
G01X1649374Y1346604D02*
X1649377Y1346566D01*
X1649385Y1346529D01*
X1649397Y1346495D01*
X1649415Y1346465D01*
X1649436Y1346441D01*
X1649459Y1346423D01*
X1649485Y1346411D01*
X1649513Y1346407D01*
G01X1649374Y1343455D02*
X1649377Y1343416D01*
X1649385Y1343380D01*
X1649397Y1343346D01*
X1649415Y1343315D01*
X1649436Y1343291D01*
X1649459Y1343273D01*
X1649485Y1343262D01*
X1649513Y1343258D01*
G01X1649374Y1340305D02*
X1649377Y1340267D01*
X1649385Y1340230D01*
X1649397Y1340196D01*
X1649415Y1340166D01*
X1649436Y1340141D01*
X1649459Y1340123D01*
X1649485Y1340112D01*
X1649513Y1340108D01*
G01X1649374Y1337155D02*
X1649377Y1337117D01*
X1649385Y1337080D01*
X1649397Y1337046D01*
X1649415Y1337016D01*
X1649436Y1336992D01*
X1649459Y1336974D01*
X1649485Y1336962D01*
X1649513Y1336959D01*
G01X1649374Y1334006D02*
X1649377Y1333968D01*
X1649385Y1333931D01*
X1649397Y1333897D01*
X1649415Y1333867D01*
X1649436Y1333842D01*
X1649459Y1333824D01*
X1649485Y1333813D01*
X1649513Y1333809D01*
G01X1649374Y1330856D02*
X1649377Y1330818D01*
X1649385Y1330781D01*
X1649397Y1330747D01*
X1649415Y1330717D01*
X1649436Y1330693D01*
X1649459Y1330674D01*
X1649485Y1330663D01*
X1649513Y1330659D01*
G01X1649374Y1327707D02*
X1649377Y1327668D01*
X1649385Y1327632D01*
X1649397Y1327598D01*
X1649415Y1327567D01*
X1649436Y1327543D01*
X1649459Y1327525D01*
X1649485Y1327514D01*
X1649513Y1327510D01*
G01X1649374Y1324557D02*
X1649377Y1324519D01*
X1649385Y1324482D01*
X1649397Y1324448D01*
X1649415Y1324418D01*
X1649436Y1324393D01*
X1649459Y1324375D01*
X1649485Y1324364D01*
X1649513Y1324360D01*
G01X1649374Y1321407D02*
X1649377Y1321369D01*
X1649385Y1321332D01*
X1649397Y1321298D01*
X1649415Y1321268D01*
X1649436Y1321244D01*
X1649459Y1321226D01*
X1649485Y1321214D01*
X1649513Y1321211D01*
G01X1649374Y1318258D02*
X1649377Y1318220D01*
X1649385Y1318183D01*
X1649397Y1318149D01*
X1649415Y1318119D01*
X1649436Y1318094D01*
X1649459Y1318076D01*
X1649485Y1318065D01*
X1649513Y1318061D01*
G01X1649374Y1315108D02*
X1649377Y1315070D01*
X1649385Y1315033D01*
X1649397Y1314999D01*
X1649415Y1314969D01*
X1649436Y1314945D01*
X1649459Y1314926D01*
X1649485Y1314915D01*
X1649513Y1314911D01*
G01X1649374Y1311959D02*
X1649377Y1311920D01*
X1649385Y1311884D01*
X1649397Y1311850D01*
X1649415Y1311819D01*
X1649436Y1311795D01*
X1649459Y1311777D01*
X1649485Y1311766D01*
X1649513Y1311762D01*
G01X1649374Y1308809D02*
X1649377Y1308771D01*
X1649385Y1308734D01*
X1649397Y1308700D01*
X1649415Y1308670D01*
X1649436Y1308645D01*
X1649459Y1308627D01*
X1649485Y1308616D01*
X1649513Y1308612D01*
G01X1649374Y1305659D02*
X1649377Y1305621D01*
X1649385Y1305584D01*
X1649397Y1305550D01*
X1649415Y1305520D01*
X1649436Y1305496D01*
X1649459Y1305478D01*
X1649485Y1305466D01*
X1649513Y1305463D01*
G01X1649374Y1302510D02*
X1649377Y1302472D01*
X1649385Y1302435D01*
X1649397Y1302401D01*
X1649415Y1302371D01*
X1649436Y1302346D01*
X1649459Y1302328D01*
X1649485Y1302317D01*
X1649513Y1302313D01*
G01X1649374Y1299360D02*
X1649377Y1299322D01*
X1649385Y1299285D01*
X1649397Y1299251D01*
X1649415Y1299221D01*
X1649436Y1299197D01*
X1649459Y1299178D01*
X1649485Y1299167D01*
X1649513Y1299163D01*
G01X1649374Y1296211D02*
X1649377Y1296172D01*
X1649385Y1296136D01*
X1649397Y1296102D01*
X1649415Y1296071D01*
X1649436Y1296047D01*
X1649459Y1296029D01*
X1649485Y1296018D01*
X1649513Y1296014D01*
G01X1649374Y1293061D02*
X1649377Y1293023D01*
X1649385Y1292986D01*
X1649397Y1292952D01*
X1649415Y1292922D01*
X1649436Y1292897D01*
X1649459Y1292879D01*
X1649485Y1292868D01*
X1649513Y1292864D01*
G01X1649374Y1289911D02*
X1649377Y1289873D01*
X1649385Y1289836D01*
X1649397Y1289802D01*
X1649415Y1289772D01*
X1649436Y1289748D01*
X1649459Y1289730D01*
X1649485Y1289718D01*
X1649513Y1289714D01*
G01X1654561Y1359793D02*
X1648477D01*
G01X1648197Y1359596D02*
X1654809D01*
G01X1656500Y1359340D02*
X1650754D01*
G01X1654809Y1359203D02*
X1648197D01*
G01X1654561Y1359006D02*
X1648477D01*
G01X1650328Y1358750D02*
X1656914D01*
G01X1650328Y1358356D02*
X1656914D01*
G01X1656500Y1357766D02*
X1650754D01*
G01X1649513Y1359793D02*
X1649486Y1359789D01*
X1649460Y1359778D01*
X1649436Y1359760D01*
X1649415Y1359736D01*
X1649397Y1359706D01*
X1649385Y1359672D01*
X1649377Y1359635D01*
X1649374Y1359596D01*
G01X1654561Y1359006D02*
X1654689Y1359034D01*
X1654777Y1359106D01*
X1654809Y1359203D01*
G01X1649964Y1359006D02*
X1649925Y1359032D01*
X1649897Y1359104D01*
X1649887Y1359203D01*
G01X1656914Y1358750D02*
X1656777Y1358948D01*
X1656639Y1359144D01*
X1656500Y1359340D01*
G01X1650754Y1357766D02*
X1650328Y1358356D01*
G01X1654809Y1359596D02*
X1654777Y1359693D01*
X1654689Y1359766D01*
X1654561Y1359793D01*
G01X1651444Y1357766D02*
X1651172Y1358356D01*
G01X1652296D02*
X1652374Y1357766D01*
G01X1650754Y1359340D02*
X1650328Y1358750D01*
G01X1656500Y1357766D02*
X1656639Y1357962D01*
X1656777Y1358159D01*
X1656914Y1358356D01*
G01X1651172Y1358750D02*
X1651444Y1359340D01*
G01X1652296Y1358750D02*
X1652374Y1359340D01*
G01X1649887Y1359596D02*
X1649897Y1359695D01*
X1649925Y1359767D01*
X1649964Y1359793D01*
G01X1656914Y1358750D02*
Y1358356D01*
G01X1654809Y1359203D02*
Y1359596D01*
G01X1652296Y1358750D02*
Y1358356D01*
G01X1651172D02*
Y1358750D01*
G01X1650328Y1358356D02*
Y1358750D01*
G01X1649887Y1359203D02*
Y1359596D01*
G01X1649374D02*
Y1359203D01*
G01X1648197Y1359596D02*
Y1359203D01*
G01X1649374D02*
X1649377Y1359164D01*
X1649385Y1359128D01*
X1649397Y1359094D01*
X1649415Y1359063D01*
X1649436Y1359039D01*
X1649459Y1359021D01*
X1649485Y1359010D01*
X1649513Y1359006D01*
G01Y1413337D02*
X1649486Y1413333D01*
X1649460Y1413322D01*
X1649436Y1413304D01*
X1649415Y1413279D01*
X1649397Y1413249D01*
X1649385Y1413215D01*
X1649377Y1413179D01*
X1649374Y1413140D01*
G01X1649513Y1410187D02*
X1649486Y1410183D01*
X1649460Y1410172D01*
X1649436Y1410154D01*
X1649415Y1410129D01*
X1649397Y1410100D01*
X1649385Y1410066D01*
X1649377Y1410029D01*
X1649374Y1409990D01*
G01X1649513Y1407037D02*
X1649486Y1407034D01*
X1649460Y1407022D01*
X1649436Y1407004D01*
X1649415Y1406980D01*
X1649397Y1406950D01*
X1649385Y1406916D01*
X1649377Y1406879D01*
X1649374Y1406840D01*
G01X1649513Y1403888D02*
X1649486Y1403884D01*
X1649460Y1403873D01*
X1649436Y1403855D01*
X1649415Y1403830D01*
X1649397Y1403800D01*
X1649385Y1403767D01*
X1649377Y1403730D01*
X1649374Y1403691D01*
G01X1649513Y1400738D02*
X1649486Y1400734D01*
X1649460Y1400723D01*
X1649436Y1400705D01*
X1649415Y1400680D01*
X1649397Y1400651D01*
X1649385Y1400617D01*
X1649377Y1400580D01*
X1649374Y1400541D01*
G01X1649513Y1397588D02*
X1649486Y1397585D01*
X1649460Y1397574D01*
X1649436Y1397556D01*
X1649415Y1397531D01*
X1649397Y1397501D01*
X1649385Y1397467D01*
X1649377Y1397431D01*
X1649374Y1397392D01*
G01X1649513Y1394439D02*
X1649486Y1394435D01*
X1649460Y1394424D01*
X1649436Y1394406D01*
X1649415Y1394381D01*
X1649397Y1394352D01*
X1649385Y1394318D01*
X1649377Y1394281D01*
X1649374Y1394242D01*
G01X1649513Y1391289D02*
X1649486Y1391286D01*
X1649460Y1391274D01*
X1649436Y1391256D01*
X1649415Y1391232D01*
X1649397Y1391202D01*
X1649385Y1391168D01*
X1649377Y1391131D01*
X1649374Y1391092D01*
G01X1649513Y1388140D02*
X1649486Y1388136D01*
X1649460Y1388125D01*
X1649436Y1388107D01*
X1649415Y1388082D01*
X1649397Y1388052D01*
X1649385Y1388018D01*
X1649377Y1387982D01*
X1649374Y1387943D01*
G01X1654561Y1412549D02*
X1654689Y1412577D01*
X1654777Y1412650D01*
X1654809Y1412746D01*
G01X1654561Y1409400D02*
X1654689Y1409427D01*
X1654777Y1409500D01*
X1654809Y1409596D01*
G01X1654561Y1406250D02*
X1654689Y1406278D01*
X1654777Y1406351D01*
X1654809Y1406447D01*
G01X1654561Y1403100D02*
X1654689Y1403128D01*
X1654777Y1403201D01*
X1654809Y1403297D01*
G01X1654561Y1396801D02*
X1654689Y1396829D01*
X1654777Y1396902D01*
X1654809Y1396998D01*
G01X1654561Y1393651D02*
X1654689Y1393679D01*
X1654777Y1393752D01*
X1654809Y1393848D01*
G01X1654561Y1390502D02*
X1654689Y1390530D01*
X1654777Y1390603D01*
X1654809Y1390699D01*
G01X1654561Y1387352D02*
X1654689Y1387380D01*
X1654777Y1387453D01*
X1654809Y1387549D01*
G01X1654561Y1384203D02*
X1654689Y1384230D01*
X1654777Y1384303D01*
X1654809Y1384400D01*
G01X1654561Y1381053D02*
X1654689Y1381081D01*
X1654777Y1381154D01*
X1654809Y1381250D01*
G01X1654561Y1377903D02*
X1654689Y1377931D01*
X1654777Y1378004D01*
X1654809Y1378100D01*
G01X1654561Y1374754D02*
X1654689Y1374782D01*
X1654777Y1374854D01*
X1654809Y1374951D01*
G01X1654561Y1368455D02*
X1654689Y1368482D01*
X1654777Y1368555D01*
X1654809Y1368651D01*
G01X1654561Y1365305D02*
X1654689Y1365333D01*
X1654777Y1365406D01*
X1654809Y1365502D01*
G01X1662079Y1422293D02*
X1658795D01*
G01X1654531Y1414340D02*
X1648786D01*
G01X1648359Y1413750D02*
X1654945D01*
G01X1648359Y1413356D02*
X1654945D01*
G01X1654561Y1413337D02*
X1648477D01*
G01X1648197Y1413140D02*
X1654809D01*
G01X1654531Y1412766D02*
X1648786D01*
G01X1654809Y1412746D02*
X1648197D01*
G01X1654561Y1412549D02*
X1648477D01*
G01X1654561Y1410187D02*
X1648477D01*
G01X1648197Y1409990D02*
X1654809D01*
G01Y1409596D02*
X1648197D01*
G01X1654561Y1409400D02*
X1648477D01*
G01X1654531Y1409340D02*
X1648786D01*
G01X1648359Y1408750D02*
X1654945D01*
G01X1648359Y1408356D02*
X1654945D01*
G01X1654531Y1407766D02*
X1648786D01*
G01X1654561Y1407037D02*
X1648477D01*
G01X1648197Y1406840D02*
X1654809D01*
G01Y1406447D02*
X1648197D01*
G01X1654561Y1406250D02*
X1648477D01*
G01X1654531Y1404340D02*
X1648786D01*
G01X1654561Y1403888D02*
X1648477D01*
G01X1648359Y1403750D02*
X1654945D01*
G01X1648197Y1403691D02*
X1654809D01*
G01X1648359Y1403356D02*
X1654945D01*
G01X1654809Y1403297D02*
X1648197D01*
G01X1654561Y1403100D02*
X1648477D01*
G01X1654531Y1402766D02*
X1648786D01*
G01X1654561Y1400738D02*
X1648477D01*
G01X1648197Y1400541D02*
X1654809D01*
G01Y1400148D02*
X1648197D01*
G01X1654561Y1399951D02*
X1648477D01*
G01X1656500Y1399340D02*
X1650754D01*
G01X1650328Y1398750D02*
X1656914D01*
G01X1650328Y1398356D02*
X1656914D01*
G01X1656500Y1397766D02*
X1650754D01*
G01X1654561Y1397588D02*
X1648477D01*
G01X1648197Y1397392D02*
X1654809D01*
G01Y1396998D02*
X1648197D01*
G01X1654561Y1396801D02*
X1648477D01*
G01X1654561Y1394439D02*
X1648477D01*
G01X1654531Y1394340D02*
X1648786D01*
G01X1648197Y1394242D02*
X1654809D01*
G01Y1393848D02*
X1648197D01*
G01X1648359Y1393750D02*
X1654945D01*
G01X1654561Y1393651D02*
X1648477D01*
G01X1648359Y1393356D02*
X1654945D01*
G01X1654531Y1392766D02*
X1648786D01*
G01X1654561Y1391289D02*
X1648477D01*
G01X1648197Y1391092D02*
X1654809D01*
G01Y1390699D02*
X1648197D01*
G01X1654561Y1390502D02*
X1648477D01*
G01X1654531Y1389340D02*
X1648786D01*
G01X1648359Y1388750D02*
X1654945D01*
G01X1648359Y1388356D02*
X1654945D01*
G01X1654561Y1388140D02*
X1648477D01*
G01X1648197Y1387943D02*
X1654809D01*
G01X1654531Y1387766D02*
X1648786D01*
G01X1654809Y1387549D02*
X1648197D01*
G01X1654561Y1387352D02*
X1648477D01*
G01X1654561Y1384990D02*
X1648477D01*
G01X1648197Y1384793D02*
X1654809D01*
G01Y1384400D02*
X1648197D01*
G01X1654531Y1384340D02*
X1648786D01*
G01X1654561Y1384203D02*
X1648477D01*
G01X1648359Y1383750D02*
X1654945D01*
G01X1648359Y1383356D02*
X1654945D01*
G01X1654531Y1382766D02*
X1648786D01*
G01X1654561Y1381840D02*
X1648477D01*
G01X1648197Y1381644D02*
X1654809D01*
G01Y1381250D02*
X1648197D01*
G01X1654561Y1381053D02*
X1648477D01*
G01X1654531Y1379340D02*
X1648786D01*
G01X1648359Y1378750D02*
X1654945D01*
G01X1654561Y1378691D02*
X1648477D01*
G01X1648197Y1378494D02*
X1654809D01*
G01X1648359Y1378356D02*
X1654945D01*
G01X1654809Y1378100D02*
X1648197D01*
G01X1654561Y1377903D02*
X1648477D01*
G01X1654531Y1377766D02*
X1648786D01*
G01X1654561Y1375541D02*
X1648477D01*
G01X1648197Y1375344D02*
X1654809D01*
G01Y1374951D02*
X1648197D01*
G01X1654561Y1374754D02*
X1648477D01*
G01X1654531Y1374340D02*
X1648786D01*
G01X1648359Y1373750D02*
X1654945D01*
G01X1648359Y1373356D02*
X1654945D01*
G01X1654531Y1372766D02*
X1648786D01*
G01X1654561Y1372392D02*
X1648477D01*
G01X1648197Y1372195D02*
X1654809D01*
G01Y1371801D02*
X1648197D01*
G01X1654561Y1371604D02*
X1648477D01*
G01X1654531Y1369340D02*
X1648786D01*
G01X1654561Y1369242D02*
X1648477D01*
G01X1648197Y1369045D02*
X1654809D01*
G01X1648359Y1368750D02*
X1654945D01*
G01X1654809Y1368651D02*
X1648197D01*
G01X1654561Y1368455D02*
X1648477D01*
G01X1648359Y1368356D02*
X1654945D01*
G01X1654531Y1367766D02*
X1648786D01*
G01X1654561Y1366092D02*
X1648477D01*
G01X1648197Y1365896D02*
X1654809D01*
G01Y1365502D02*
X1648197D01*
G01X1654561Y1365305D02*
X1648477D01*
G01X1654531Y1364340D02*
X1648786D01*
G01X1648359Y1363750D02*
X1654945D01*
G01X1648359Y1363356D02*
X1654945D01*
G01X1654561Y1362943D02*
X1648477D01*
G01X1654531Y1362766D02*
X1648786D01*
G01X1648197Y1362746D02*
X1654809D01*
G01Y1362352D02*
X1648197D01*
G01X1654561Y1362155D02*
X1648477D01*
G01X1649513Y1384990D02*
X1649486Y1384986D01*
X1649460Y1384975D01*
X1649436Y1384957D01*
X1649415Y1384932D01*
X1649397Y1384903D01*
X1649385Y1384869D01*
X1649377Y1384832D01*
X1649374Y1384793D01*
G01X1649513Y1381840D02*
X1649486Y1381837D01*
X1649460Y1381826D01*
X1649436Y1381808D01*
X1649415Y1381783D01*
X1649397Y1381753D01*
X1649385Y1381719D01*
X1649377Y1381683D01*
X1649374Y1381644D01*
G01X1649513Y1378691D02*
X1649486Y1378687D01*
X1649460Y1378676D01*
X1649436Y1378658D01*
X1649415Y1378633D01*
X1649397Y1378604D01*
X1649385Y1378570D01*
X1649377Y1378533D01*
X1649374Y1378494D01*
G01X1649513Y1375541D02*
X1649486Y1375537D01*
X1649460Y1375526D01*
X1649436Y1375508D01*
X1649415Y1375484D01*
X1649397Y1375454D01*
X1649385Y1375420D01*
X1649377Y1375383D01*
X1649374Y1375344D01*
G01X1649513Y1372392D02*
X1649486Y1372388D01*
X1649460Y1372377D01*
X1649436Y1372359D01*
X1649415Y1372334D01*
X1649397Y1372304D01*
X1649385Y1372270D01*
X1649377Y1372234D01*
X1649374Y1372195D01*
G01X1649513Y1369242D02*
X1649486Y1369238D01*
X1649460Y1369227D01*
X1649436Y1369209D01*
X1649415Y1369184D01*
X1649397Y1369155D01*
X1649385Y1369121D01*
X1649377Y1369084D01*
X1649374Y1369045D01*
G01X1649513Y1366092D02*
X1649486Y1366089D01*
X1649460Y1366078D01*
X1649436Y1366060D01*
X1649415Y1366035D01*
X1649397Y1366005D01*
X1649385Y1365971D01*
X1649377Y1365934D01*
X1649374Y1365896D01*
G01X1649513Y1362943D02*
X1649486Y1362939D01*
X1649460Y1362928D01*
X1649436Y1362910D01*
X1649415Y1362885D01*
X1649397Y1362855D01*
X1649385Y1362822D01*
X1649377Y1362785D01*
X1649374Y1362746D01*
G01X1654561Y1362155D02*
X1654689Y1362183D01*
X1654777Y1362256D01*
X1654809Y1362352D01*
G01X1654561Y1400738D02*
X1654688Y1400711D01*
X1654777Y1400638D01*
X1654809Y1400541D01*
G01X1654561Y1372392D02*
X1654688Y1372364D01*
X1654777Y1372292D01*
X1654809Y1372195D01*
G01X1649964Y1412549D02*
X1649925Y1412576D01*
X1649897Y1412648D01*
X1649887Y1412746D01*
G01X1649964Y1409400D02*
X1649925Y1409426D01*
X1649897Y1409498D01*
X1649887Y1409596D01*
G01X1649964Y1406250D02*
X1649925Y1406276D01*
X1649897Y1406348D01*
X1649887Y1406447D01*
G01X1649964Y1403100D02*
X1649925Y1403127D01*
X1649897Y1403199D01*
X1649887Y1403297D01*
G01X1656827Y1422293D02*
X1658795Y1420325D01*
G01X1649964Y1399951D02*
X1649925Y1399977D01*
X1649897Y1400049D01*
X1649887Y1400148D01*
G01X1649964Y1396801D02*
X1649925Y1396827D01*
X1649897Y1396900D01*
X1649887Y1396998D01*
G01X1649964Y1393651D02*
X1649925Y1393678D01*
X1649897Y1393750D01*
X1649887Y1393848D01*
G01X1649964Y1390502D02*
X1649925Y1390528D01*
X1649897Y1390600D01*
X1649887Y1390699D01*
G01X1649964Y1387352D02*
X1649925Y1387379D01*
X1649897Y1387451D01*
X1649887Y1387549D01*
G01X1649964Y1384203D02*
X1649925Y1384229D01*
X1649897Y1384301D01*
X1649887Y1384400D01*
G01X1649964Y1381053D02*
X1649925Y1381079D01*
X1649897Y1381152D01*
X1649887Y1381250D01*
G01X1649964Y1377903D02*
X1649925Y1377930D01*
X1649897Y1378002D01*
X1649887Y1378100D01*
G01X1649964Y1374754D02*
X1649925Y1374780D01*
X1649897Y1374852D01*
X1649887Y1374951D01*
G01X1649964Y1371604D02*
X1649925Y1371631D01*
X1649897Y1371703D01*
X1649887Y1371801D01*
G01X1649964Y1368455D02*
X1649925Y1368481D01*
X1649897Y1368553D01*
X1649887Y1368651D01*
G01X1649964Y1365305D02*
X1649925Y1365331D01*
X1649897Y1365404D01*
X1649887Y1365502D01*
G01X1649964Y1362155D02*
X1649925Y1362182D01*
X1649897Y1362254D01*
X1649887Y1362352D01*
G01X1654945Y1413750D02*
X1654808Y1413948D01*
X1654670Y1414144D01*
X1654531Y1414340D01*
G01X1654945Y1408750D02*
X1654808Y1408948D01*
X1654670Y1409144D01*
X1654531Y1409340D01*
G01X1654945Y1403750D02*
X1654808Y1403948D01*
X1654670Y1404144D01*
X1654531Y1404340D01*
G01X1656914Y1398750D02*
X1656777Y1398948D01*
X1656639Y1399144D01*
X1656500Y1399340D01*
G01X1654945Y1393750D02*
X1654808Y1393948D01*
X1654670Y1394144D01*
X1654531Y1394340D01*
G01X1654945Y1388750D02*
X1654808Y1388948D01*
X1654670Y1389144D01*
X1654531Y1389340D01*
G01X1654945Y1383750D02*
X1654808Y1383948D01*
X1654670Y1384144D01*
X1654531Y1384340D01*
G01X1654945Y1378750D02*
X1654808Y1378948D01*
X1654670Y1379144D01*
X1654531Y1379340D01*
G01X1654945Y1373750D02*
X1654808Y1373948D01*
X1654670Y1374144D01*
X1654531Y1374340D01*
G01X1654945Y1368750D02*
X1654808Y1368948D01*
X1654670Y1369144D01*
X1654531Y1369340D01*
G01X1654945Y1363750D02*
X1654808Y1363948D01*
X1654670Y1364144D01*
X1654531Y1364340D01*
G01X1648786Y1412766D02*
X1648359Y1413356D01*
G01X1648786Y1407766D02*
X1648359Y1408356D01*
G01X1648786Y1402766D02*
X1648359Y1403356D01*
G01X1650754Y1397766D02*
X1650328Y1398356D01*
G01X1648786Y1392766D02*
X1648359Y1393356D01*
G01X1648786Y1387766D02*
X1648359Y1388356D01*
G01X1648786Y1382766D02*
X1648359Y1383356D01*
G01X1648786Y1377766D02*
X1648359Y1378356D01*
G01X1648786Y1372766D02*
X1648359Y1373356D01*
G01X1648786Y1367766D02*
X1648359Y1368356D01*
G01X1648786Y1362766D02*
X1648359Y1363356D01*
G01X1650328Y1413356D02*
X1650405Y1412766D01*
G01X1652296Y1398356D02*
X1652374Y1397766D01*
G01X1650405Y1407766D02*
X1650328Y1408356D01*
G01Y1403356D02*
X1650405Y1402766D01*
G01X1654809Y1413140D02*
X1654777Y1413237D01*
X1654689Y1413309D01*
X1654561Y1413337D01*
G01X1654809Y1409990D02*
X1654777Y1410087D01*
X1654689Y1410159D01*
X1654561Y1410187D01*
G01X1654809Y1406840D02*
X1654777Y1406937D01*
X1654689Y1407010D01*
X1654561Y1407037D01*
G01X1654809Y1403691D02*
X1654777Y1403788D01*
X1654689Y1403860D01*
X1654561Y1403888D01*
G01X1654809Y1397392D02*
X1654777Y1397489D01*
X1654689Y1397561D01*
X1654561Y1397588D01*
G01X1654809Y1394242D02*
X1654777Y1394339D01*
X1654689Y1394411D01*
X1654561Y1394439D01*
G01X1654809Y1391092D02*
X1654777Y1391189D01*
X1654689Y1391262D01*
X1654561Y1391289D01*
G01X1654809Y1387943D02*
X1654777Y1388040D01*
X1654689Y1388112D01*
X1654561Y1388140D01*
G01X1654809Y1384793D02*
X1654777Y1384890D01*
X1654689Y1384962D01*
X1654561Y1384990D01*
G01X1654809Y1381644D02*
X1654777Y1381741D01*
X1654689Y1381813D01*
X1654561Y1381840D01*
G01X1654809Y1378494D02*
X1654777Y1378591D01*
X1654689Y1378663D01*
X1654561Y1378691D01*
G01X1654809Y1375344D02*
X1654777Y1375441D01*
X1654689Y1375514D01*
X1654561Y1375541D01*
G01X1654809Y1369045D02*
X1654777Y1369142D01*
X1654689Y1369214D01*
X1654561Y1369242D01*
G01X1654809Y1365896D02*
X1654777Y1365993D01*
X1654689Y1366065D01*
X1654561Y1366092D01*
G01X1654809Y1362746D02*
X1654777Y1362843D01*
X1654689Y1362915D01*
X1654561Y1362943D01*
G01X1649476Y1412766D02*
X1649203Y1413356D01*
G01X1649476Y1407766D02*
X1649203Y1408356D01*
G01X1649476Y1402766D02*
X1649203Y1403356D01*
G01X1651444Y1397766D02*
X1651172Y1398356D01*
G01X1649476Y1392766D02*
X1649203Y1393356D01*
G01X1649476Y1387766D02*
X1649203Y1388356D01*
G01X1649476Y1382766D02*
X1649203Y1383356D01*
G01X1649476Y1377766D02*
X1649203Y1378356D01*
G01X1649476Y1372766D02*
X1649203Y1373356D01*
G01X1649476Y1367766D02*
X1649203Y1368356D01*
G01X1649476Y1362766D02*
X1649203Y1363356D01*
G01X1650328Y1393356D02*
X1650405Y1392766D01*
G01X1650328Y1388356D02*
X1650405Y1387766D01*
G01X1650328Y1383356D02*
X1650405Y1382766D01*
G01X1650328Y1378356D02*
X1650405Y1377766D01*
G01X1650328Y1373356D02*
X1650405Y1372766D01*
G01X1650328Y1368356D02*
X1650405Y1367766D01*
G01X1650328Y1363356D02*
X1650405Y1362766D01*
G01X1656827Y1417372D02*
X1658795Y1419340D01*
G01X1648786Y1364340D02*
X1648359Y1363750D01*
G01X1648786Y1369340D02*
X1648359Y1368750D01*
G01X1648786Y1374340D02*
X1648359Y1373750D01*
G01X1648786Y1379340D02*
X1648359Y1378750D01*
G01X1648786Y1384340D02*
X1648359Y1383750D01*
G01X1648786Y1389340D02*
X1648359Y1388750D01*
G01X1648786Y1394340D02*
X1648359Y1393750D01*
G01X1650754Y1399340D02*
X1650328Y1398750D01*
G01X1648786Y1404340D02*
X1648359Y1403750D01*
G01X1648786Y1409340D02*
X1648359Y1408750D01*
G01X1648786Y1414340D02*
X1648359Y1413750D01*
G01X1654531Y1362766D02*
X1654670Y1362962D01*
X1654808Y1363159D01*
X1654945Y1363356D01*
G01X1654531Y1367766D02*
X1654670Y1367962D01*
X1654808Y1368159D01*
X1654945Y1368356D01*
G01X1654531Y1372766D02*
X1654670Y1372962D01*
X1654808Y1373159D01*
X1654945Y1373356D01*
G01X1654531Y1377766D02*
X1654670Y1377962D01*
X1654808Y1378159D01*
X1654945Y1378356D01*
G01X1654531Y1382766D02*
X1654670Y1382962D01*
X1654808Y1383159D01*
X1654945Y1383356D01*
G01X1654531Y1387766D02*
X1654670Y1387962D01*
X1654808Y1388159D01*
X1654945Y1388356D01*
G01X1654531Y1392766D02*
X1654670Y1392962D01*
X1654808Y1393159D01*
X1654945Y1393356D01*
G01X1656500Y1397766D02*
X1656639Y1397962D01*
X1656777Y1398159D01*
X1656914Y1398356D01*
G01X1654531Y1402766D02*
X1654670Y1402962D01*
X1654808Y1403159D01*
X1654945Y1403356D01*
G01X1654531Y1407766D02*
X1654670Y1407962D01*
X1654808Y1408159D01*
X1654945Y1408356D01*
G01X1654531Y1412766D02*
X1654670Y1412962D01*
X1654808Y1413159D01*
X1654945Y1413356D01*
G01X1649203Y1363750D02*
X1649476Y1364340D01*
G01X1649203Y1368750D02*
X1649476Y1369340D01*
G01X1649203Y1373750D02*
X1649476Y1374340D01*
G01X1649203Y1378750D02*
X1649476Y1379340D01*
G01X1649203Y1383750D02*
X1649476Y1384340D01*
G01X1649203Y1388750D02*
X1649476Y1389340D01*
G01X1649203Y1393750D02*
X1649476Y1394340D01*
G01X1651172Y1398750D02*
X1651444Y1399340D01*
G01X1649203Y1403750D02*
X1649476Y1404340D01*
G01X1649203Y1408750D02*
X1649476Y1409340D01*
G01X1649203Y1413750D02*
X1649476Y1414340D01*
G01X1654809Y1371801D02*
X1654775Y1371702D01*
X1654687Y1371631D01*
X1654561Y1371604D01*
G01X1654809Y1400148D02*
X1654775Y1400049D01*
X1654687Y1399978D01*
X1654561Y1399951D01*
G01X1650328Y1363750D02*
X1650405Y1364340D01*
G01X1650328Y1368750D02*
X1650405Y1369340D01*
G01X1650328Y1373750D02*
X1650405Y1374340D01*
G01X1650328Y1378750D02*
X1650405Y1379340D01*
G01X1650328Y1383750D02*
X1650405Y1384340D01*
G01X1652296Y1398750D02*
X1652374Y1399340D01*
G01X1650328Y1388750D02*
X1650405Y1389340D01*
G01X1650328Y1393750D02*
X1650405Y1394340D01*
G01X1650328Y1403750D02*
X1650405Y1404340D01*
G01Y1409340D02*
X1650328Y1408750D01*
G01Y1413750D02*
X1650405Y1414340D01*
G01X1649887Y1362746D02*
X1649897Y1362844D01*
X1649925Y1362916D01*
X1649964Y1362943D01*
G01X1649887Y1365896D02*
X1649897Y1365994D01*
X1649925Y1366066D01*
X1649964Y1366092D01*
G01X1649887Y1369045D02*
X1649897Y1369144D01*
X1649925Y1369216D01*
X1649964Y1369242D01*
G01X1649887Y1372195D02*
X1649897Y1372293D01*
X1649925Y1372365D01*
X1649964Y1372392D01*
G01X1649887Y1375344D02*
X1649897Y1375443D01*
X1649925Y1375515D01*
X1649964Y1375541D01*
G01X1649887Y1378494D02*
X1649897Y1378592D01*
X1649925Y1378664D01*
X1649964Y1378691D01*
G01X1649887Y1381644D02*
X1649897Y1381742D01*
X1649925Y1381814D01*
X1649964Y1381840D01*
G01X1649887Y1384793D02*
X1649897Y1384892D01*
X1649925Y1384964D01*
X1649964Y1384990D01*
G01X1649887Y1387943D02*
X1649897Y1388041D01*
X1649925Y1388113D01*
X1649964Y1388140D01*
G01X1649887Y1391092D02*
X1649897Y1391191D01*
X1649925Y1391263D01*
X1649964Y1391289D01*
G01X1649887Y1394242D02*
X1649897Y1394340D01*
X1649925Y1394412D01*
X1649964Y1394439D01*
G01X1649887Y1397392D02*
X1649897Y1397490D01*
X1649925Y1397562D01*
X1649964Y1397588D01*
G01X1649887Y1400541D02*
X1649897Y1400640D01*
X1649925Y1400712D01*
X1649964Y1400738D01*
G01X1649887Y1403691D02*
X1649897Y1403789D01*
X1649925Y1403861D01*
X1649964Y1403888D01*
G01X1649887Y1406840D02*
X1649897Y1406939D01*
X1649925Y1407011D01*
X1649964Y1407037D01*
G01X1649887Y1409990D02*
X1649897Y1410088D01*
X1649925Y1410161D01*
X1649964Y1410187D01*
G01X1649887Y1413140D02*
X1649897Y1413238D01*
X1649925Y1413310D01*
X1649964Y1413337D01*
G01X1656914Y1398750D02*
Y1398356D01*
G01X1654945Y1363750D02*
Y1363356D01*
G01Y1368750D02*
Y1368356D01*
G01Y1373750D02*
Y1373356D01*
G01Y1378750D02*
Y1378356D01*
G01Y1383750D02*
Y1383356D01*
G01Y1388750D02*
Y1388356D01*
G01Y1393750D02*
Y1393356D01*
G01Y1403750D02*
Y1403356D01*
G01Y1408750D02*
Y1408356D01*
G01Y1413750D02*
Y1413356D01*
G01X1654809Y1412746D02*
Y1413140D01*
G01Y1409596D02*
Y1409990D01*
G01Y1403297D02*
Y1403691D01*
G01Y1406447D02*
Y1406840D01*
G01Y1400148D02*
Y1400541D01*
G01Y1393848D02*
Y1394242D01*
G01Y1396998D02*
Y1397392D01*
G01Y1390699D02*
Y1391092D01*
G01Y1384400D02*
Y1384793D01*
G01Y1387549D02*
Y1387943D01*
G01Y1381250D02*
Y1381644D01*
G01Y1378100D02*
Y1378494D01*
G01Y1374951D02*
Y1375344D01*
G01Y1371801D02*
Y1372195D01*
G01Y1365502D02*
Y1365896D01*
G01Y1368651D02*
Y1369045D01*
G01Y1362352D02*
Y1362746D01*
G01X1652296Y1398750D02*
Y1398356D01*
G01X1651172D02*
Y1398750D01*
G01X1650328Y1398356D02*
Y1398750D01*
G01Y1408356D02*
Y1408750D01*
G01Y1363750D02*
Y1363356D01*
G01Y1368750D02*
Y1368356D01*
G01Y1373750D02*
Y1373356D01*
G01Y1378750D02*
Y1378356D01*
G01Y1383750D02*
Y1383356D01*
G01Y1388750D02*
Y1388356D01*
G01Y1393750D02*
Y1393356D01*
G01Y1403750D02*
Y1403356D01*
G01Y1413750D02*
Y1413356D01*
G01X1649887Y1412746D02*
Y1413140D01*
G01Y1409596D02*
Y1409990D01*
G01Y1403297D02*
Y1403691D01*
G01Y1406447D02*
Y1406840D01*
G01Y1400148D02*
Y1400541D01*
G01Y1393848D02*
Y1394242D01*
G01Y1396998D02*
Y1397392D01*
G01Y1390699D02*
Y1391092D01*
G01Y1384400D02*
Y1384793D01*
G01Y1387549D02*
Y1387943D01*
G01Y1381250D02*
Y1381644D01*
G01Y1378100D02*
Y1378494D01*
G01Y1374951D02*
Y1375344D01*
G01Y1371801D02*
Y1372195D01*
G01Y1365502D02*
Y1365896D01*
G01Y1368651D02*
Y1369045D01*
G01Y1362352D02*
Y1362746D01*
G01X1649374D02*
Y1362352D01*
G01Y1365896D02*
Y1365502D01*
G01Y1369045D02*
Y1368651D01*
G01Y1372195D02*
Y1371801D01*
G01Y1378494D02*
Y1378100D01*
G01Y1375344D02*
Y1374951D01*
G01Y1381644D02*
Y1381250D01*
G01Y1384793D02*
Y1384400D01*
G01Y1387943D02*
Y1387549D01*
G01Y1391092D02*
Y1390699D01*
G01Y1394242D02*
Y1393848D01*
G01Y1397392D02*
Y1396998D01*
G01Y1400541D02*
Y1400148D01*
G01Y1403691D02*
Y1403297D01*
G01Y1406840D02*
Y1406447D01*
G01Y1409990D02*
Y1409596D01*
G01Y1413140D02*
Y1412746D01*
G01X1649203Y1413356D02*
Y1413750D01*
G01Y1408356D02*
Y1408750D01*
G01Y1403356D02*
Y1403750D01*
G01Y1393356D02*
Y1393750D01*
G01Y1388356D02*
Y1388750D01*
G01Y1383356D02*
Y1383750D01*
G01Y1378356D02*
Y1378750D01*
G01Y1373356D02*
Y1373750D01*
G01Y1368356D02*
Y1368750D01*
G01Y1363356D02*
Y1363750D01*
G01X1648359Y1413356D02*
Y1413750D01*
G01Y1408356D02*
Y1408750D01*
G01Y1403356D02*
Y1403750D01*
G01Y1393356D02*
Y1393750D01*
G01Y1388356D02*
Y1388750D01*
G01Y1383356D02*
Y1383750D01*
G01Y1378356D02*
Y1378750D01*
G01Y1373356D02*
Y1373750D01*
G01Y1368356D02*
Y1368750D01*
G01Y1363356D02*
Y1363750D01*
G01X1648197Y1362746D02*
Y1362352D01*
G01Y1365896D02*
Y1365502D01*
G01Y1369045D02*
Y1368651D01*
G01Y1372195D02*
Y1371801D01*
G01Y1378494D02*
Y1378100D01*
G01Y1375344D02*
Y1374951D01*
G01Y1381644D02*
Y1381250D01*
G01Y1384793D02*
Y1384400D01*
G01Y1387943D02*
Y1387549D01*
G01Y1391092D02*
Y1390699D01*
G01Y1394242D02*
Y1393848D01*
G01Y1397392D02*
Y1396998D01*
G01Y1400541D02*
Y1400148D01*
G01Y1403691D02*
Y1403297D01*
G01Y1406840D02*
Y1406447D01*
G01Y1409990D02*
Y1409596D01*
G01Y1413140D02*
Y1412746D01*
G01X1649374D02*
X1649377Y1412708D01*
X1649385Y1412671D01*
X1649397Y1412637D01*
X1649415Y1412607D01*
X1649436Y1412582D01*
X1649459Y1412564D01*
X1649485Y1412553D01*
X1649513Y1412549D01*
G01X1649374Y1409596D02*
X1649377Y1409558D01*
X1649385Y1409521D01*
X1649397Y1409487D01*
X1649415Y1409457D01*
X1649436Y1409433D01*
X1649459Y1409415D01*
X1649485Y1409403D01*
X1649513Y1409400D01*
G01X1649374Y1406447D02*
X1649377Y1406409D01*
X1649385Y1406372D01*
X1649397Y1406338D01*
X1649415Y1406308D01*
X1649436Y1406283D01*
X1649459Y1406265D01*
X1649485Y1406254D01*
X1649513Y1406250D01*
G01X1649374Y1403297D02*
X1649377Y1403259D01*
X1649385Y1403222D01*
X1649397Y1403188D01*
X1649415Y1403158D01*
X1649436Y1403134D01*
X1649459Y1403115D01*
X1649485Y1403104D01*
X1649513Y1403100D01*
G01X1649374Y1400148D02*
X1649377Y1400109D01*
X1649385Y1400073D01*
X1649397Y1400039D01*
X1649415Y1400008D01*
X1649436Y1399984D01*
X1649459Y1399966D01*
X1649485Y1399955D01*
X1649513Y1399951D01*
G01X1649374Y1396998D02*
X1649377Y1396960D01*
X1649385Y1396923D01*
X1649397Y1396889D01*
X1649415Y1396859D01*
X1649436Y1396834D01*
X1649459Y1396816D01*
X1649485Y1396805D01*
X1649513Y1396801D01*
G01X1649374Y1393848D02*
X1649377Y1393810D01*
X1649385Y1393773D01*
X1649397Y1393739D01*
X1649415Y1393709D01*
X1649436Y1393685D01*
X1649459Y1393667D01*
X1649485Y1393655D01*
X1649513Y1393651D01*
G01X1649374Y1390699D02*
X1649377Y1390660D01*
X1649385Y1390624D01*
X1649397Y1390590D01*
X1649415Y1390560D01*
X1649436Y1390535D01*
X1649459Y1390517D01*
X1649485Y1390506D01*
X1649513Y1390502D01*
G01X1649374Y1387549D02*
X1649377Y1387511D01*
X1649385Y1387474D01*
X1649397Y1387440D01*
X1649415Y1387410D01*
X1649436Y1387386D01*
X1649459Y1387367D01*
X1649485Y1387356D01*
X1649513Y1387352D01*
G01X1649374Y1384400D02*
X1649377Y1384361D01*
X1649385Y1384325D01*
X1649397Y1384291D01*
X1649415Y1384260D01*
X1649436Y1384236D01*
X1649459Y1384218D01*
X1649485Y1384207D01*
X1649513Y1384203D01*
G01X1649374Y1381250D02*
X1649377Y1381212D01*
X1649385Y1381175D01*
X1649397Y1381141D01*
X1649415Y1381111D01*
X1649436Y1381086D01*
X1649459Y1381068D01*
X1649485Y1381057D01*
X1649513Y1381053D01*
G01X1649374Y1378100D02*
X1649377Y1378062D01*
X1649385Y1378025D01*
X1649397Y1377991D01*
X1649415Y1377961D01*
X1649436Y1377937D01*
X1649459Y1377919D01*
X1649485Y1377907D01*
X1649513Y1377903D01*
G01X1649374Y1374951D02*
X1649377Y1374912D01*
X1649385Y1374876D01*
X1649397Y1374842D01*
X1649415Y1374811D01*
X1649436Y1374787D01*
X1649459Y1374769D01*
X1649485Y1374758D01*
X1649513Y1374754D01*
G01X1649374Y1371801D02*
X1649377Y1371763D01*
X1649385Y1371726D01*
X1649397Y1371692D01*
X1649415Y1371662D01*
X1649436Y1371638D01*
X1649459Y1371619D01*
X1649485Y1371608D01*
X1649513Y1371604D01*
G01X1649374Y1368651D02*
X1649377Y1368613D01*
X1649385Y1368576D01*
X1649397Y1368543D01*
X1649415Y1368512D01*
X1649436Y1368488D01*
X1649459Y1368470D01*
X1649485Y1368459D01*
X1649513Y1368455D01*
G01X1649374Y1365502D02*
X1649377Y1365464D01*
X1649385Y1365427D01*
X1649397Y1365393D01*
X1649415Y1365363D01*
X1649436Y1365338D01*
X1649459Y1365320D01*
X1649485Y1365309D01*
X1649513Y1365305D01*
G01X1649374Y1362352D02*
X1649377Y1362314D01*
X1649385Y1362277D01*
X1649397Y1362243D01*
X1649415Y1362213D01*
X1649436Y1362189D01*
X1649459Y1362171D01*
X1649485Y1362159D01*
X1649513Y1362155D01*
G01X1665488Y1425994D02*
X1660764Y1430640D01*
G01X1660768Y1429532D02*
X1665488Y1424891D01*
G01X1662079Y1422293D02*
X1665488Y1424262D01*
G01X1660822Y1429910D02*
X1660768Y1429532D01*
G01X1660821Y1429908D02*
X1660858Y1430232D01*
X1660852Y1430473D01*
X1660795Y1430609D01*
G01X1665488Y1424262D02*
Y1425994D01*
G01X1660764Y1422293D02*
Y1429459D01*
G01X1657081Y1478270D02*
X1654158D01*
X1653671Y1474661D01*
X1654645Y1475383D01*
X1655620D01*
X1656594Y1474661D01*
X1657081Y1473939D01*
X1657569Y1472496D01*
X1657081Y1471052D01*
X1656594Y1470331D01*
X1655620Y1469609D01*
X1654645D01*
X1653671Y1470331D01*
X1653184Y1471052D01*
G01X1647337Y1469609D02*
X1646850D01*
Y1470331D01*
X1647337Y1469609D01*
G01X1653682Y1487330D02*
X1652708Y1488052D01*
X1652221Y1488773D01*
X1651733Y1490217D01*
Y1493104D01*
X1652221Y1494548D01*
X1652708Y1495269D01*
X1653682Y1495991D01*
X1654657Y1495269D01*
X1655144Y1494548D01*
X1655631Y1493104D01*
Y1490217D01*
X1655144Y1488773D01*
X1654657Y1488052D01*
X1653682Y1487330D01*
G01X1645887D02*
X1644912Y1488052D01*
X1644425Y1488773D01*
X1643938Y1490217D01*
Y1493104D01*
X1644425Y1494548D01*
X1644912Y1495269D01*
X1645887Y1495991D01*
X1646861Y1495269D01*
X1647348Y1494548D01*
X1647836Y1493104D01*
Y1490217D01*
X1647348Y1488773D01*
X1646861Y1488052D01*
X1645887Y1487330D01*
G01X1641004Y1473939D02*
X1641978Y1472496D01*
Y1471774D01*
G01X1660795Y1430609D02*
X1660853Y1430469D01*
X1660858Y1430229D01*
G01X1682914Y1495991D02*
X1684863D01*
X1685838Y1495269D01*
X1686812Y1493826D01*
G01X1675606Y1490217D02*
X1678530D01*
G01X1683878Y1478270D02*
X1688750D01*
G01X1664877D02*
X1661953D01*
X1661466Y1474661D01*
X1662441Y1475383D01*
X1663415D01*
X1664389Y1474661D01*
X1664877Y1473939D01*
X1665364Y1472496D01*
X1664877Y1471052D01*
X1664389Y1470331D01*
X1663415Y1469609D01*
X1662441D01*
X1661466Y1470331D01*
X1660979Y1471052D01*
G01X1692160Y1473939D02*
X1696058D01*
G01X1692171Y1495991D02*
X1693146Y1494548D01*
X1693633Y1492382D01*
Y1490939D01*
X1693146Y1488773D01*
X1692171Y1487330D01*
G01X1701417Y1478270D02*
X1702391Y1476827D01*
X1702879Y1474661D01*
Y1473218D01*
X1702391Y1471052D01*
X1701417Y1469609D01*
G01X1686812Y1493826D02*
X1687299Y1491660D01*
X1686812Y1489495D01*
X1686325Y1488773D01*
X1685838Y1488052D01*
X1684863Y1487330D01*
X1682914D01*
Y1495991D01*
G01X1706300Y1487330D02*
Y1495991D01*
X1710198Y1487330D01*
Y1495991D01*
G01X1696058Y1478270D02*
Y1469609D01*
G01X1692160Y1478270D02*
Y1469609D01*
G01X1686314Y1478270D02*
Y1469609D01*
G01X1676570D02*
Y1478270D01*
X1679006D01*
X1679980Y1477548D01*
X1680467Y1476827D01*
Y1475383D01*
X1679980Y1474661D01*
X1679006Y1473939D01*
X1676570D01*
G01X1700941Y1495991D02*
X1699967Y1494548D01*
X1699479Y1492382D01*
Y1490939D01*
X1699967Y1488773D01*
X1700941Y1487330D01*
G01X1671210Y1478270D02*
X1670236Y1476827D01*
X1669749Y1474661D01*
Y1473218D01*
X1670236Y1471052D01*
X1671210Y1469609D01*
G01X1674632Y1487330D02*
X1677068Y1495991D01*
X1679504Y1487330D01*
G01X1667324D02*
Y1495991D01*
X1669760D01*
X1670734Y1495269D01*
X1671221Y1494548D01*
Y1493104D01*
X1670734Y1492382D01*
X1669760Y1491660D01*
X1667324D01*
G01X1661965Y1495991D02*
X1660990Y1494548D01*
X1660503Y1492382D01*
Y1490939D01*
X1660990Y1488773D01*
X1661965Y1487330D01*
G01X1649513Y1718061D02*
X1649486Y1718057D01*
X1649460Y1718046D01*
X1649436Y1718028D01*
X1649415Y1718003D01*
X1649397Y1717974D01*
X1649385Y1717940D01*
X1649377Y1717903D01*
X1649374Y1717864D01*
G01X1649513Y1714911D02*
X1649486Y1714908D01*
X1649460Y1714896D01*
X1649436Y1714878D01*
X1649415Y1714854D01*
X1649397Y1714824D01*
X1649385Y1714790D01*
X1649377Y1714753D01*
X1649374Y1714714D01*
G01X1649513Y1711762D02*
X1649486Y1711758D01*
X1649460Y1711747D01*
X1649436Y1711729D01*
X1649415Y1711704D01*
X1649397Y1711674D01*
X1649385Y1711641D01*
X1649377Y1711604D01*
X1649374Y1711565D01*
G01X1649513Y1708612D02*
X1649486Y1708608D01*
X1649460Y1708597D01*
X1649436Y1708579D01*
X1649415Y1708554D01*
X1649397Y1708525D01*
X1649385Y1708491D01*
X1649377Y1708454D01*
X1649374Y1708415D01*
G01X1649513Y1705463D02*
X1649486Y1705459D01*
X1649460Y1705448D01*
X1649436Y1705430D01*
X1649415Y1705405D01*
X1649397Y1705375D01*
X1649385Y1705341D01*
X1649377Y1705305D01*
X1649374Y1705266D01*
G01X1649513Y1702313D02*
X1649486Y1702309D01*
X1649460Y1702298D01*
X1649436Y1702280D01*
X1649415Y1702255D01*
X1649397Y1702226D01*
X1649385Y1702192D01*
X1649377Y1702155D01*
X1649374Y1702116D01*
G01X1649513Y1699163D02*
X1649486Y1699160D01*
X1649460Y1699148D01*
X1649436Y1699130D01*
X1649415Y1699106D01*
X1649397Y1699076D01*
X1649385Y1699042D01*
X1649377Y1699005D01*
X1649374Y1698966D01*
G01X1649513Y1696014D02*
X1649486Y1696010D01*
X1649460Y1695999D01*
X1649436Y1695981D01*
X1649415Y1695956D01*
X1649397Y1695926D01*
X1649385Y1695892D01*
X1649377Y1695856D01*
X1649374Y1695817D01*
G01X1654561Y1720423D02*
X1654689Y1720451D01*
X1654777Y1720524D01*
X1654809Y1720620D01*
G01X1654561Y1717274D02*
X1654689Y1717301D01*
X1654777Y1717374D01*
X1654809Y1717470D01*
G01X1654561Y1714124D02*
X1654689Y1714152D01*
X1654777Y1714225D01*
X1654809Y1714321D01*
G01X1654561Y1710974D02*
X1654689Y1711002D01*
X1654777Y1711075D01*
X1654809Y1711171D01*
G01X1654561Y1707825D02*
X1654689Y1707852D01*
X1654777Y1707925D01*
X1654809Y1708022D01*
G01X1654561Y1704675D02*
X1654689Y1704703D01*
X1654777Y1704776D01*
X1654809Y1704872D01*
G01X1654561Y1701525D02*
X1654689Y1701553D01*
X1654777Y1701626D01*
X1654809Y1701722D01*
G01X1654561Y1698376D02*
X1654689Y1698404D01*
X1654777Y1698477D01*
X1654809Y1698573D01*
G01X1654561Y1695226D02*
X1654689Y1695254D01*
X1654777Y1695327D01*
X1654809Y1695423D01*
G01Y1720620D02*
X1648197D01*
G01X1654561Y1720423D02*
X1648477D01*
G01X1654531Y1719852D02*
X1648786D01*
G01X1648359Y1719262D02*
X1654945D01*
G01X1648359Y1718868D02*
X1654945D01*
G01X1654531Y1718277D02*
X1648786D01*
G01X1654561Y1718061D02*
X1648477D01*
G01X1648197Y1717864D02*
X1654809D01*
G01Y1717470D02*
X1648197D01*
G01X1654561Y1717274D02*
X1648477D01*
G01X1654561Y1714911D02*
X1648477D01*
G01X1654531Y1714852D02*
X1648786D01*
G01X1648197Y1714714D02*
X1654809D01*
G01Y1714321D02*
X1648197D01*
G01X1648359Y1714262D02*
X1654945D01*
G01X1654561Y1714124D02*
X1648477D01*
G01X1648359Y1713868D02*
X1654945D01*
G01X1654531Y1713277D02*
X1648786D01*
G01X1654561Y1711762D02*
X1648477D01*
G01X1648197Y1711565D02*
X1654809D01*
G01Y1711171D02*
X1648197D01*
G01X1654561Y1710974D02*
X1648477D01*
G01X1654531Y1709852D02*
X1648786D01*
G01X1648359Y1709262D02*
X1654945D01*
G01X1648359Y1708868D02*
X1654945D01*
G01X1654561Y1708612D02*
X1648477D01*
G01X1648197Y1708415D02*
X1654809D01*
G01X1654531Y1708277D02*
X1648786D01*
G01X1654809Y1708022D02*
X1648197D01*
G01X1654561Y1707825D02*
X1648477D01*
G01X1654561Y1705463D02*
X1648477D01*
G01X1648197Y1705266D02*
X1654809D01*
G01Y1704872D02*
X1648197D01*
G01X1654531Y1704852D02*
X1648786D01*
G01X1654561Y1704675D02*
X1648477D01*
G01X1648359Y1704262D02*
X1654945D01*
G01X1648359Y1703868D02*
X1654945D01*
G01X1654531Y1703277D02*
X1648786D01*
G01X1654561Y1702313D02*
X1648477D01*
G01X1648197Y1702116D02*
X1654809D01*
G01Y1701722D02*
X1648197D01*
G01X1654561Y1701525D02*
X1648477D01*
G01X1654531Y1699852D02*
X1648786D01*
G01X1648359Y1699262D02*
X1654945D01*
G01X1654561Y1699163D02*
X1648477D01*
G01X1648197Y1698966D02*
X1654809D01*
G01X1648359Y1698868D02*
X1654945D01*
G01X1654809Y1698573D02*
X1648197D01*
G01X1654561Y1698376D02*
X1648477D01*
G01X1654531Y1698277D02*
X1648786D01*
G01X1654561Y1696014D02*
X1648477D01*
G01X1648197Y1695817D02*
X1654809D01*
G01Y1695423D02*
X1648197D01*
G01X1654561Y1695226D02*
X1648477D01*
G01X1654531Y1694852D02*
X1648786D01*
G01X1648359Y1694262D02*
X1654945D01*
G01X1648359Y1693868D02*
X1654945D01*
G01X1654531Y1693277D02*
X1648786D01*
G01X1662079Y1685325D02*
X1658795D01*
G01X1649964Y1720423D02*
X1649925Y1720450D01*
X1649897Y1720522D01*
X1649887Y1720620D01*
G01X1649964Y1717274D02*
X1649925Y1717300D01*
X1649897Y1717372D01*
X1649887Y1717470D01*
G01X1649964Y1714124D02*
X1649925Y1714150D01*
X1649897Y1714222D01*
X1649887Y1714321D01*
G01X1649964Y1710974D02*
X1649925Y1711001D01*
X1649897Y1711073D01*
X1649887Y1711171D01*
G01X1649964Y1707825D02*
X1649925Y1707851D01*
X1649897Y1707923D01*
X1649887Y1708022D01*
G01X1649964Y1704675D02*
X1649925Y1704702D01*
X1649897Y1704774D01*
X1649887Y1704872D01*
G01X1649964Y1701525D02*
X1649925Y1701552D01*
X1649897Y1701624D01*
X1649887Y1701722D01*
G01X1649964Y1698376D02*
X1649925Y1698402D01*
X1649897Y1698474D01*
X1649887Y1698573D01*
G01X1649964Y1695226D02*
X1649925Y1695253D01*
X1649897Y1695325D01*
X1649887Y1695423D01*
G01X1658795Y1688277D02*
X1656827Y1690246D01*
G01X1654945Y1719262D02*
X1654808Y1719459D01*
X1654670Y1719656D01*
X1654531Y1719852D01*
G01X1654945Y1714262D02*
X1654808Y1714459D01*
X1654670Y1714656D01*
X1654531Y1714852D01*
G01X1654945Y1709262D02*
X1654808Y1709459D01*
X1654670Y1709656D01*
X1654531Y1709852D01*
G01X1654945Y1704262D02*
X1654808Y1704459D01*
X1654670Y1704656D01*
X1654531Y1704852D01*
G01X1654945Y1699262D02*
X1654808Y1699459D01*
X1654670Y1699656D01*
X1654531Y1699852D01*
G01X1654945Y1694262D02*
X1654808Y1694459D01*
X1654670Y1694656D01*
X1654531Y1694852D01*
G01X1648786Y1718277D02*
X1648359Y1718868D01*
G01X1648786Y1713277D02*
X1648359Y1713868D01*
G01X1648786Y1708277D02*
X1648359Y1708868D01*
G01X1648786Y1703277D02*
X1648359Y1703868D01*
G01X1648786Y1698277D02*
X1648359Y1698868D01*
G01X1648786Y1693277D02*
X1648359Y1693868D01*
G01X1649476Y1718277D02*
X1649203Y1718868D01*
G01X1649476Y1713277D02*
X1649203Y1713868D01*
G01X1649476Y1708277D02*
X1649203Y1708868D01*
G01X1649476Y1703277D02*
X1649203Y1703868D01*
G01X1649476Y1698277D02*
X1649203Y1698868D01*
G01X1649476Y1693277D02*
X1649203Y1693868D01*
G01X1654809Y1721014D02*
X1654777Y1721111D01*
X1654689Y1721183D01*
X1654561Y1721211D01*
G01X1654809Y1717864D02*
X1654777Y1717961D01*
X1654689Y1718033D01*
X1654561Y1718061D01*
G01X1654809Y1714714D02*
X1654777Y1714811D01*
X1654689Y1714884D01*
X1654561Y1714911D01*
G01X1654809Y1711565D02*
X1654777Y1711662D01*
X1654689Y1711734D01*
X1654561Y1711762D01*
G01X1654809Y1708415D02*
X1654777Y1708512D01*
X1654689Y1708584D01*
X1654561Y1708612D01*
G01X1654809Y1705266D02*
X1654777Y1705363D01*
X1654689Y1705435D01*
X1654561Y1705463D01*
G01X1654809Y1702116D02*
X1654777Y1702213D01*
X1654689Y1702285D01*
X1654561Y1702313D01*
G01X1654809Y1698966D02*
X1654777Y1699063D01*
X1654689Y1699136D01*
X1654561Y1699163D01*
G01X1654809Y1695817D02*
X1654777Y1695914D01*
X1654689Y1695986D01*
X1654561Y1696014D01*
G01X1650328Y1718868D02*
X1650405Y1718277D01*
G01X1650328Y1713868D02*
X1650405Y1713277D01*
G01X1650328Y1708868D02*
X1650405Y1708277D01*
G01X1650328Y1703868D02*
X1650405Y1703277D01*
G01X1650328Y1698868D02*
X1650405Y1698277D01*
G01X1650328Y1693868D02*
X1650405Y1693277D01*
G01X1649374Y1720620D02*
X1649377Y1720582D01*
X1649385Y1720545D01*
X1649397Y1720511D01*
X1649415Y1720481D01*
X1649436Y1720456D01*
X1649459Y1720438D01*
X1649485Y1720427D01*
X1649513Y1720423D01*
G01X1649374Y1717470D02*
X1649377Y1717432D01*
X1649385Y1717395D01*
X1649397Y1717361D01*
X1649415Y1717331D01*
X1649436Y1717307D01*
X1649459Y1717289D01*
X1649485Y1717277D01*
X1649513Y1717274D01*
G01X1649374Y1714321D02*
X1649377Y1714283D01*
X1649385Y1714246D01*
X1649397Y1714212D01*
X1649415Y1714182D01*
X1649436Y1714157D01*
X1649459Y1714139D01*
X1649485Y1714128D01*
X1649513Y1714124D01*
G01X1649374Y1711171D02*
X1649377Y1711133D01*
X1649385Y1711096D01*
X1649397Y1711062D01*
X1649415Y1711032D01*
X1649436Y1711008D01*
X1649459Y1710989D01*
X1649485Y1710978D01*
X1649513Y1710974D01*
G01X1649374Y1708022D02*
X1649377Y1707983D01*
X1649385Y1707947D01*
X1649397Y1707913D01*
X1649415Y1707882D01*
X1649436Y1707858D01*
X1649459Y1707840D01*
X1649485Y1707829D01*
X1649513Y1707825D01*
G01X1649374Y1704872D02*
X1649377Y1704834D01*
X1649385Y1704797D01*
X1649397Y1704763D01*
X1649415Y1704733D01*
X1649436Y1704708D01*
X1649459Y1704690D01*
X1649485Y1704679D01*
X1649513Y1704675D01*
G01X1649374Y1701722D02*
X1649377Y1701684D01*
X1649385Y1701647D01*
X1649397Y1701613D01*
X1649415Y1701583D01*
X1649436Y1701559D01*
X1649459Y1701541D01*
X1649485Y1701529D01*
X1649513Y1701525D01*
G01X1649374Y1698573D02*
X1649377Y1698535D01*
X1649385Y1698498D01*
X1649397Y1698464D01*
X1649415Y1698434D01*
X1649436Y1698409D01*
X1649459Y1698391D01*
X1649485Y1698380D01*
X1649513Y1698376D01*
G01X1649374Y1695423D02*
X1649377Y1695385D01*
X1649385Y1695348D01*
X1649397Y1695314D01*
X1649415Y1695284D01*
X1649436Y1695260D01*
X1649459Y1695241D01*
X1649485Y1695230D01*
X1649513Y1695226D01*
G01X1650328Y1694262D02*
X1650405Y1694852D01*
G01X1650328Y1699262D02*
X1650405Y1699852D01*
G01X1650328Y1704262D02*
X1650405Y1704852D01*
G01X1650328Y1709262D02*
X1650405Y1709852D01*
G01X1650328Y1714262D02*
X1650405Y1714852D01*
G01X1650328Y1719262D02*
X1650405Y1719852D01*
G01X1649887Y1698966D02*
X1649897Y1699065D01*
X1649925Y1699137D01*
X1649964Y1699163D01*
G01X1649887Y1702116D02*
X1649897Y1702214D01*
X1649925Y1702286D01*
X1649964Y1702313D01*
G01X1649887Y1714714D02*
X1649897Y1714813D01*
X1649925Y1714885D01*
X1649964Y1714911D01*
G01X1649887Y1717864D02*
X1649897Y1717962D01*
X1649925Y1718035D01*
X1649964Y1718061D01*
G01X1658795Y1685325D02*
Y1827805D01*
G01X1657784Y1725844D02*
Y1720463D01*
G01X1657673Y1823277D02*
Y1689852D01*
G01X1657614Y1720463D02*
Y1689459D01*
G01X1656827Y1690246D02*
Y1822884D01*
G01X1654945Y1694262D02*
Y1693868D01*
G01Y1699262D02*
Y1698868D01*
G01Y1704262D02*
Y1703868D01*
G01Y1709262D02*
Y1708868D01*
G01Y1714262D02*
Y1713868D01*
G01Y1719262D02*
Y1718868D01*
G01X1654809Y1717470D02*
Y1717864D01*
G01Y1720620D02*
Y1721014D01*
G01Y1714321D02*
Y1714714D01*
G01Y1708022D02*
Y1708415D01*
G01Y1711171D02*
Y1711565D01*
G01Y1704872D02*
Y1705266D01*
G01Y1698573D02*
Y1698966D01*
G01Y1701722D02*
Y1702116D01*
G01Y1695423D02*
Y1695817D01*
G01X1650328Y1694262D02*
Y1693868D01*
G01Y1699262D02*
Y1698868D01*
G01Y1704262D02*
Y1703868D01*
G01Y1709262D02*
Y1708868D01*
G01Y1714262D02*
Y1713868D01*
G01Y1719262D02*
Y1718868D01*
G01X1649887Y1717470D02*
Y1717864D01*
G01Y1720620D02*
Y1721014D01*
G01Y1714321D02*
Y1714714D01*
G01Y1708022D02*
Y1708415D01*
G01Y1711171D02*
Y1711565D01*
G01Y1704872D02*
Y1705266D01*
G01Y1698573D02*
Y1698966D01*
G01Y1701722D02*
Y1702116D01*
G01Y1695423D02*
Y1695817D01*
G01X1649374D02*
Y1695423D01*
G01Y1698966D02*
Y1698573D01*
G01Y1702116D02*
Y1701722D01*
G01Y1705266D02*
Y1704872D01*
G01Y1708415D02*
Y1708022D01*
G01Y1711565D02*
Y1711171D01*
G01Y1714714D02*
Y1714321D01*
G01Y1717864D02*
Y1717470D01*
G01Y1721014D02*
Y1720620D01*
G01X1649203Y1718868D02*
Y1719262D01*
G01Y1713868D02*
Y1714262D01*
G01Y1708868D02*
Y1709262D01*
G01Y1703868D02*
Y1704262D01*
G01Y1698868D02*
Y1699262D01*
G01Y1693868D02*
Y1694262D01*
G01X1648359Y1718868D02*
Y1719262D01*
G01Y1713868D02*
Y1714262D01*
G01Y1708868D02*
Y1709262D01*
G01Y1703868D02*
Y1704262D01*
G01Y1698868D02*
Y1699262D01*
G01Y1693868D02*
Y1694262D01*
G01X1648197Y1695817D02*
Y1695423D01*
G01Y1698966D02*
Y1698573D01*
G01Y1702116D02*
Y1701722D01*
G01Y1705266D02*
Y1704872D01*
G01Y1708415D02*
Y1708022D01*
G01Y1711565D02*
Y1711171D01*
G01Y1714714D02*
Y1714321D01*
G01Y1717864D02*
Y1717470D01*
G01Y1721014D02*
Y1720620D01*
G01X1658795Y1687293D02*
X1656827Y1685325D01*
G01X1648786Y1694852D02*
X1648359Y1694262D01*
G01X1648786Y1699852D02*
X1648359Y1699262D01*
G01X1648786Y1704852D02*
X1648359Y1704262D01*
G01X1648786Y1709852D02*
X1648359Y1709262D01*
G01X1648786Y1714852D02*
X1648359Y1714262D01*
G01X1648786Y1719852D02*
X1648359Y1719262D01*
G01X1654531Y1693277D02*
X1654670Y1693473D01*
X1654808Y1693670D01*
X1654945Y1693868D01*
G01X1654531Y1698277D02*
X1654670Y1698473D01*
X1654808Y1698670D01*
X1654945Y1698868D01*
G01X1654531Y1703277D02*
X1654670Y1703473D01*
X1654808Y1703670D01*
X1654945Y1703868D01*
G01X1654531Y1708277D02*
X1654670Y1708473D01*
X1654808Y1708670D01*
X1654945Y1708868D01*
G01X1654531Y1713277D02*
X1654670Y1713473D01*
X1654808Y1713670D01*
X1654945Y1713868D01*
G01X1654531Y1718277D02*
X1654670Y1718473D01*
X1654808Y1718670D01*
X1654945Y1718868D01*
G01X1649203Y1694262D02*
X1649476Y1694852D01*
G01X1649203Y1699262D02*
X1649476Y1699852D01*
G01X1649203Y1704262D02*
X1649476Y1704852D01*
G01X1649203Y1709262D02*
X1649476Y1709852D01*
G01X1649203Y1714262D02*
X1649476Y1714852D01*
G01X1649203Y1719262D02*
X1649476Y1719852D01*
G01X1649964Y1696014D02*
X1649925Y1695987D01*
X1649897Y1695915D01*
X1649887Y1695817D01*
G01X1649964Y1705463D02*
X1649925Y1705436D01*
X1649897Y1705364D01*
X1649887Y1705266D01*
G01X1649964Y1708612D02*
X1649925Y1708586D01*
X1649897Y1708514D01*
X1649887Y1708415D01*
G01X1649964Y1711762D02*
X1649925Y1711735D01*
X1649897Y1711663D01*
X1649887Y1711565D01*
G01X1662079Y1685325D02*
X1665488Y1683356D01*
G01X1660823Y1677700D02*
X1660768Y1678086D01*
G01X1665488Y1683356D02*
Y1681624D01*
G01X1660764Y1678159D02*
Y1685325D01*
G01X1660795Y1677009D02*
X1660852Y1677144D01*
X1660858Y1677379D01*
X1660822Y1677708D01*
G01X1660795Y1677009D02*
X1660853Y1677149D01*
X1660858Y1677389D01*
G01X1665488Y1681624D02*
X1660764Y1676978D01*
G01X1665488Y1682727D02*
X1660768Y1678086D01*
G01X1649513Y1724360D02*
X1649486Y1724356D01*
X1649460Y1724345D01*
X1649436Y1724327D01*
X1649415Y1724302D01*
X1649397Y1724273D01*
X1649385Y1724239D01*
X1649377Y1724202D01*
X1649374Y1724163D01*
G01X1649513Y1721211D02*
X1649486Y1721207D01*
X1649460Y1721196D01*
X1649436Y1721178D01*
X1649415Y1721153D01*
X1649397Y1721123D01*
X1649385Y1721089D01*
X1649377Y1721053D01*
X1649374Y1721014D01*
G01X1654561Y1723573D02*
X1654689Y1723600D01*
X1654777Y1723673D01*
X1654809Y1723770D01*
G01X1648197Y1724163D02*
X1654809D01*
G01X1648294Y1723868D02*
X1655036D01*
G01X1654809Y1723770D02*
X1648197D01*
G01X1654561Y1723573D02*
X1648477D01*
G01X1654631Y1723277D02*
X1648718D01*
G01X1654561Y1721211D02*
X1648477D01*
G01X1648197Y1721014D02*
X1654809D01*
G01X1649964Y1723573D02*
X1649925Y1723599D01*
X1649897Y1723671D01*
X1649887Y1723770D01*
G01X1648718Y1723277D02*
X1648294Y1723868D01*
G01X1649476Y1723277D02*
X1649203Y1723868D01*
G01X1654809Y1724163D02*
X1654777Y1724260D01*
X1654689Y1724332D01*
X1654561Y1724360D01*
G01X1650328Y1723868D02*
X1650405Y1723277D01*
G01X1649374Y1723770D02*
X1649377Y1723731D01*
X1649385Y1723695D01*
X1649397Y1723661D01*
X1649415Y1723630D01*
X1649436Y1723606D01*
X1649459Y1723588D01*
X1649485Y1723577D01*
X1649513Y1723573D01*
G01X1655036Y1724262D02*
Y1723868D01*
G01X1654809Y1723770D02*
Y1724163D01*
G01X1650328Y1724262D02*
Y1723868D01*
G01X1649887Y1723770D02*
Y1724163D01*
G01X1649374D02*
Y1723770D01*
G01X1649203Y1723868D02*
Y1724262D01*
G01X1648294Y1723868D02*
Y1724262D01*
G01X1648197Y1724163D02*
Y1723770D01*
G01X1654631Y1723277D02*
X1654767Y1723474D01*
X1654902Y1723670D01*
X1655036Y1723868D01*
G01X1649964Y1721211D02*
X1649925Y1721184D01*
X1649897Y1721112D01*
X1649887Y1721014D01*
G01X1649964Y1724360D02*
X1649925Y1724334D01*
X1649897Y1724262D01*
X1649887Y1724163D01*
G01X1649513Y1793651D02*
X1649486Y1793648D01*
X1649460Y1793637D01*
X1649436Y1793619D01*
X1649415Y1793594D01*
X1649397Y1793564D01*
X1649385Y1793530D01*
X1649377Y1793494D01*
X1649374Y1793455D01*
G01X1649513Y1790502D02*
X1649486Y1790498D01*
X1649460Y1790487D01*
X1649436Y1790469D01*
X1649415Y1790444D01*
X1649397Y1790415D01*
X1649385Y1790381D01*
X1649377Y1790344D01*
X1649374Y1790305D01*
G01X1649513Y1787352D02*
X1649486Y1787349D01*
X1649460Y1787337D01*
X1649436Y1787319D01*
X1649415Y1787295D01*
X1649397Y1787265D01*
X1649385Y1787231D01*
X1649377Y1787194D01*
X1649374Y1787155D01*
G01X1649513Y1784203D02*
X1649486Y1784199D01*
X1649460Y1784188D01*
X1649436Y1784170D01*
X1649415Y1784145D01*
X1649397Y1784115D01*
X1649385Y1784081D01*
X1649377Y1784045D01*
X1649374Y1784006D01*
G01X1649513Y1781053D02*
X1649486Y1781049D01*
X1649460Y1781038D01*
X1649436Y1781020D01*
X1649415Y1780995D01*
X1649397Y1780966D01*
X1649385Y1780932D01*
X1649377Y1780895D01*
X1649374Y1780856D01*
G01X1649513Y1777903D02*
X1649486Y1777900D01*
X1649460Y1777889D01*
X1649436Y1777871D01*
X1649415Y1777846D01*
X1649397Y1777816D01*
X1649385Y1777782D01*
X1649377Y1777746D01*
X1649374Y1777707D01*
G01X1649513Y1774754D02*
X1649486Y1774750D01*
X1649460Y1774739D01*
X1649436Y1774721D01*
X1649415Y1774696D01*
X1649397Y1774667D01*
X1649385Y1774633D01*
X1649377Y1774596D01*
X1649374Y1774557D01*
G01X1654561Y1792864D02*
X1654689Y1792892D01*
X1654777Y1792965D01*
X1654809Y1793061D01*
G01X1654561Y1789714D02*
X1654689Y1789742D01*
X1654777Y1789815D01*
X1654809Y1789911D01*
G01X1654561Y1786565D02*
X1654689Y1786593D01*
X1654777Y1786665D01*
X1654809Y1786762D01*
G01X1654561Y1783415D02*
X1654689Y1783443D01*
X1654777Y1783516D01*
X1654809Y1783612D01*
G01X1654561Y1780266D02*
X1654689Y1780293D01*
X1654777Y1780366D01*
X1654809Y1780463D01*
G01X1654561Y1773966D02*
X1654689Y1773994D01*
X1654777Y1774067D01*
X1654809Y1774163D01*
G01X1654561Y1770817D02*
X1654689Y1770845D01*
X1654777Y1770917D01*
X1654809Y1771014D01*
G01X1654561Y1767667D02*
X1654689Y1767695D01*
X1654777Y1767768D01*
X1654809Y1767864D01*
G01X1654561Y1764518D02*
X1654689Y1764545D01*
X1654777Y1764618D01*
X1654809Y1764714D01*
G01X1654561Y1761368D02*
X1654689Y1761396D01*
X1654777Y1761469D01*
X1654809Y1761565D01*
G01X1654561Y1758218D02*
X1654689Y1758246D01*
X1654777Y1758319D01*
X1654809Y1758415D01*
G01X1654561Y1793651D02*
X1648477D01*
G01X1648197Y1793455D02*
X1654809D01*
G01X1654531Y1793277D02*
X1648786D01*
G01X1654809Y1793061D02*
X1648197D01*
G01X1654561Y1792864D02*
X1648477D01*
G01X1654561Y1790502D02*
X1648477D01*
G01X1648197Y1790305D02*
X1654809D01*
G01Y1789911D02*
X1648197D01*
G01X1654531Y1789852D02*
X1648786D01*
G01X1654561Y1789714D02*
X1648477D01*
G01X1648359Y1789262D02*
X1654945D01*
G01X1648359Y1788868D02*
X1654945D01*
G01X1654531Y1788277D02*
X1648786D01*
G01X1654561Y1787352D02*
X1648477D01*
G01X1648197Y1787155D02*
X1654809D01*
G01Y1786762D02*
X1648197D01*
G01X1654561Y1786565D02*
X1648477D01*
G01X1654531Y1784852D02*
X1648786D01*
G01X1648359Y1784262D02*
X1654945D01*
G01X1654561Y1784203D02*
X1648477D01*
G01X1648197Y1784006D02*
X1654809D01*
G01X1648359Y1783868D02*
X1654945D01*
G01X1654809Y1783612D02*
X1648197D01*
G01X1654561Y1783415D02*
X1648477D01*
G01X1654531Y1783277D02*
X1648786D01*
G01X1654561Y1781053D02*
X1648477D01*
G01X1648197Y1780856D02*
X1654809D01*
G01Y1780463D02*
X1648197D01*
G01X1654561Y1780266D02*
X1648477D01*
G01X1654531Y1779852D02*
X1648786D01*
G01X1648359Y1779262D02*
X1654945D01*
G01X1648359Y1778868D02*
X1654945D01*
G01X1654531Y1778277D02*
X1648786D01*
G01X1654561Y1777903D02*
X1648477D01*
G01X1648197Y1777707D02*
X1654809D01*
G01Y1777313D02*
X1648197D01*
G01X1654561Y1777116D02*
X1648477D01*
G01X1654531Y1774852D02*
X1648786D01*
G01X1654561Y1774754D02*
X1648477D01*
G01X1648197Y1774557D02*
X1654809D01*
G01X1648359Y1774262D02*
X1654945D01*
G01X1654809Y1774163D02*
X1648197D01*
G01X1654561Y1773966D02*
X1648477D01*
G01X1648359Y1773868D02*
X1654945D01*
G01X1654531Y1773277D02*
X1648786D01*
G01X1654561Y1771604D02*
X1648477D01*
G01X1648197Y1771407D02*
X1654809D01*
G01Y1771014D02*
X1648197D01*
G01X1654561Y1770817D02*
X1648477D01*
G01X1654531Y1769852D02*
X1648786D01*
G01X1648359Y1769262D02*
X1654945D01*
G01X1648359Y1768868D02*
X1654945D01*
G01X1654561Y1768455D02*
X1648477D01*
G01X1654531Y1768277D02*
X1648786D01*
G01X1648197Y1768258D02*
X1654809D01*
G01Y1767864D02*
X1648197D01*
G01X1654561Y1767667D02*
X1648477D01*
G01X1654561Y1765305D02*
X1648477D01*
G01X1648197Y1765108D02*
X1654809D01*
G01X1656500Y1764852D02*
X1650754D01*
G01X1654809Y1764714D02*
X1648197D01*
G01X1654561Y1764518D02*
X1648477D01*
G01X1650328Y1764262D02*
X1656914D01*
G01X1650328Y1763868D02*
X1656914D01*
G01X1656500Y1763277D02*
X1650754D01*
G01X1654561Y1762155D02*
X1648477D01*
G01X1648197Y1761959D02*
X1654809D01*
G01Y1761565D02*
X1648197D01*
G01X1654561Y1761368D02*
X1648477D01*
G01X1654531Y1759852D02*
X1648786D01*
G01X1648359Y1759262D02*
X1654945D01*
G01X1654561Y1759006D02*
X1648477D01*
G01X1648359Y1758868D02*
X1654945D01*
G01X1648197Y1758809D02*
X1654809D01*
G01Y1758415D02*
X1648197D01*
G01X1654531Y1758277D02*
X1648786D01*
G01X1654561Y1758218D02*
X1648477D01*
G01X1654561Y1755856D02*
X1648477D01*
G01X1648197Y1755659D02*
X1654809D01*
G01Y1755266D02*
X1648197D01*
G01X1654561Y1755069D02*
X1648477D01*
G01X1654531Y1754852D02*
X1648786D01*
G01X1648359Y1754262D02*
X1654945D01*
G01X1648359Y1753868D02*
X1654945D01*
G01X1654531Y1753277D02*
X1648786D01*
G01X1654561Y1752707D02*
X1648477D01*
G01X1648197Y1752510D02*
X1654809D01*
G01Y1752116D02*
X1648197D01*
G01X1654561Y1751919D02*
X1648477D01*
G01X1654631Y1749852D02*
X1648718D01*
G01X1654561Y1749557D02*
X1648477D01*
G01X1648197Y1749360D02*
X1654809D01*
G01X1648294Y1749262D02*
X1655036D01*
G01X1654809Y1748966D02*
X1648197D01*
G01X1648294Y1748868D02*
X1655036D01*
G01X1654561Y1748770D02*
X1648477D01*
G01X1654631Y1748277D02*
X1648718D01*
G01X1652326Y1747490D02*
X1658795D01*
G01X1654561Y1746407D02*
X1648477D01*
G01X1648197Y1746211D02*
X1654809D01*
G01Y1745817D02*
X1648197D01*
G01X1654561Y1745620D02*
X1648477D01*
G01X1648763Y1745130D02*
X1654571D01*
G01X1654819Y1744933D02*
X1648501D01*
G01Y1743949D02*
X1654819D01*
G01X1648763Y1743752D02*
X1654571D01*
G01X1654561Y1743258D02*
X1648477D01*
G01X1648197Y1743061D02*
X1654809D01*
G01Y1742667D02*
X1648197D01*
G01X1654561Y1742470D02*
X1648477D01*
G01X1648763Y1741980D02*
X1654571D01*
G01X1654819Y1741784D02*
X1648501D01*
G01Y1740799D02*
X1654819D01*
G01X1648763Y1740602D02*
X1654571D01*
G01X1654561Y1740108D02*
X1648477D01*
G01X1648197Y1739911D02*
X1654809D01*
G01Y1739518D02*
X1648197D01*
G01X1654561Y1739321D02*
X1648477D01*
G01X1648763Y1738831D02*
X1654571D01*
G01X1654819Y1738634D02*
X1648501D01*
G01Y1737650D02*
X1654819D01*
G01X1648763Y1737453D02*
X1654571D01*
G01X1654561Y1736959D02*
X1648477D01*
G01X1648197Y1736762D02*
X1654809D01*
G01Y1736368D02*
X1648197D01*
G01X1654561Y1736171D02*
X1648477D01*
G01X1649513Y1771604D02*
X1649486Y1771600D01*
X1649460Y1771589D01*
X1649436Y1771571D01*
X1649415Y1771547D01*
X1649397Y1771517D01*
X1649385Y1771483D01*
X1649377Y1771446D01*
X1649374Y1771407D01*
G01X1649513Y1768455D02*
X1649486Y1768451D01*
X1649460Y1768440D01*
X1649436Y1768422D01*
X1649415Y1768397D01*
X1649397Y1768367D01*
X1649385Y1768333D01*
X1649377Y1768297D01*
X1649374Y1768258D01*
G01X1649513Y1765305D02*
X1649486Y1765301D01*
X1649460Y1765290D01*
X1649436Y1765272D01*
X1649415Y1765247D01*
X1649397Y1765218D01*
X1649385Y1765184D01*
X1649377Y1765147D01*
X1649374Y1765108D01*
G01X1649513Y1762155D02*
X1649486Y1762152D01*
X1649460Y1762141D01*
X1649436Y1762123D01*
X1649415Y1762098D01*
X1649397Y1762068D01*
X1649385Y1762034D01*
X1649377Y1761997D01*
X1649374Y1761959D01*
G01X1649513Y1759006D02*
X1649486Y1759002D01*
X1649460Y1758991D01*
X1649436Y1758973D01*
X1649415Y1758948D01*
X1649397Y1758918D01*
X1649385Y1758885D01*
X1649377Y1758848D01*
X1649374Y1758809D01*
G01X1649513Y1755856D02*
X1649486Y1755852D01*
X1649460Y1755841D01*
X1649436Y1755823D01*
X1649415Y1755799D01*
X1649397Y1755769D01*
X1649385Y1755735D01*
X1649377Y1755698D01*
X1649374Y1755659D01*
G01X1649513Y1752707D02*
X1649486Y1752703D01*
X1649460Y1752692D01*
X1649436Y1752674D01*
X1649415Y1752649D01*
X1649397Y1752619D01*
X1649385Y1752585D01*
X1649377Y1752549D01*
X1649374Y1752510D01*
G01X1649513Y1749557D02*
X1649486Y1749553D01*
X1649460Y1749542D01*
X1649436Y1749524D01*
X1649415Y1749499D01*
X1649397Y1749470D01*
X1649385Y1749436D01*
X1649377Y1749399D01*
X1649374Y1749360D01*
G01X1649513Y1746407D02*
X1649486Y1746404D01*
X1649460Y1746393D01*
X1649436Y1746375D01*
X1649415Y1746350D01*
X1649397Y1746320D01*
X1649385Y1746286D01*
X1649377Y1746249D01*
X1649374Y1746211D01*
G01X1649513Y1743258D02*
X1649486Y1743254D01*
X1649460Y1743243D01*
X1649436Y1743225D01*
X1649415Y1743200D01*
X1649397Y1743170D01*
X1649385Y1743137D01*
X1649377Y1743100D01*
X1649374Y1743061D01*
G01X1649513Y1740108D02*
X1649486Y1740104D01*
X1649460Y1740093D01*
X1649436Y1740075D01*
X1649415Y1740051D01*
X1649397Y1740021D01*
X1649385Y1739987D01*
X1649377Y1739950D01*
X1649374Y1739911D01*
G01X1649513Y1736959D02*
X1649486Y1736955D01*
X1649460Y1736944D01*
X1649436Y1736926D01*
X1649415Y1736901D01*
X1649397Y1736871D01*
X1649385Y1736837D01*
X1649377Y1736801D01*
X1649374Y1736762D01*
G01X1649513Y1733809D02*
X1649486Y1733805D01*
X1649460Y1733794D01*
X1649436Y1733776D01*
X1649415Y1733751D01*
X1649397Y1733722D01*
X1649385Y1733688D01*
X1649377Y1733651D01*
X1649374Y1733612D01*
G01X1649513Y1730659D02*
X1649486Y1730656D01*
X1649460Y1730645D01*
X1649436Y1730626D01*
X1649415Y1730602D01*
X1649397Y1730572D01*
X1649385Y1730538D01*
X1649377Y1730501D01*
X1649374Y1730463D01*
G01X1649513Y1727510D02*
X1649486Y1727506D01*
X1649460Y1727495D01*
X1649436Y1727477D01*
X1649415Y1727452D01*
X1649397Y1727422D01*
X1649385Y1727389D01*
X1649377Y1727352D01*
X1649374Y1727313D01*
G01X1654571Y1743752D02*
X1654698Y1743779D01*
X1654787Y1743852D01*
X1654819Y1743949D01*
G01X1654571Y1740602D02*
X1654698Y1740630D01*
X1654787Y1740703D01*
X1654819Y1740799D01*
G01X1654571Y1737453D02*
X1654698Y1737480D01*
X1654787Y1737553D01*
X1654819Y1737650D01*
G01X1654571Y1734303D02*
X1654698Y1734331D01*
X1654787Y1734403D01*
X1654819Y1734500D01*
G01X1654571Y1731154D02*
X1654698Y1731181D01*
X1654787Y1731254D01*
X1654819Y1731350D01*
G01X1654571Y1728004D02*
X1654698Y1728031D01*
X1654787Y1728104D01*
X1654819Y1728201D01*
G01X1654561Y1755069D02*
X1654689Y1755097D01*
X1654777Y1755169D01*
X1654809Y1755266D01*
G01X1654561Y1751919D02*
X1654689Y1751947D01*
X1654777Y1752020D01*
X1654809Y1752116D01*
G01X1654561Y1748770D02*
X1654689Y1748797D01*
X1654777Y1748870D01*
X1654809Y1748966D01*
G01X1654561Y1745620D02*
X1654689Y1745648D01*
X1654777Y1745721D01*
X1654809Y1745817D01*
G01X1654561Y1742470D02*
X1654689Y1742498D01*
X1654777Y1742571D01*
X1654809Y1742667D01*
G01X1654561Y1739321D02*
X1654689Y1739349D01*
X1654777Y1739421D01*
X1654809Y1739518D01*
G01X1654561Y1736171D02*
X1654689Y1736199D01*
X1654777Y1736272D01*
X1654809Y1736368D01*
G01X1654561Y1733022D02*
X1654689Y1733049D01*
X1654777Y1733122D01*
X1654809Y1733218D01*
G01X1654561Y1729872D02*
X1654689Y1729900D01*
X1654777Y1729973D01*
X1654809Y1730069D01*
G01X1654561Y1726722D02*
X1654689Y1726750D01*
X1654777Y1726823D01*
X1654809Y1726919D01*
G01X1654561Y1777903D02*
X1654688Y1777876D01*
X1654777Y1777803D01*
X1654809Y1777707D01*
G01X1649590Y1743752D02*
X1649562Y1743756D01*
X1649534Y1743767D01*
X1649509Y1743785D01*
X1649486Y1743810D01*
X1649468Y1743839D01*
X1649454Y1743873D01*
X1649446Y1743910D01*
X1649443Y1743949D01*
G01X1649590Y1740602D02*
X1649562Y1740606D01*
X1649534Y1740617D01*
X1649509Y1740635D01*
X1649486Y1740660D01*
X1649468Y1740690D01*
X1649454Y1740724D01*
X1649446Y1740760D01*
X1649443Y1740799D01*
G01X1649590Y1737453D02*
X1649562Y1737457D01*
X1649534Y1737468D01*
X1649509Y1737486D01*
X1649486Y1737511D01*
X1649468Y1737540D01*
X1649454Y1737574D01*
X1649446Y1737611D01*
X1649443Y1737650D01*
G01X1649590Y1734303D02*
X1649562Y1734307D01*
X1649534Y1734318D01*
X1649509Y1734336D01*
X1649486Y1734361D01*
X1649468Y1734391D01*
X1649454Y1734424D01*
X1649446Y1734461D01*
X1649443Y1734500D01*
G01X1649590Y1731154D02*
X1649562Y1731157D01*
X1649534Y1731168D01*
X1649509Y1731187D01*
X1649486Y1731211D01*
X1649468Y1731241D01*
X1649454Y1731275D01*
X1649446Y1731312D01*
X1649443Y1731350D01*
G01X1649590Y1728004D02*
X1649562Y1728008D01*
X1649534Y1728019D01*
X1649509Y1728037D01*
X1649486Y1728062D01*
X1649468Y1728091D01*
X1649454Y1728125D01*
X1649446Y1728162D01*
X1649443Y1728201D01*
G01X1648763Y1735681D02*
X1654571D01*
G01X1654819Y1735484D02*
X1648501D01*
G01Y1734500D02*
X1654819D01*
G01X1648763Y1734303D02*
X1654571D01*
G01X1654561Y1733809D02*
X1648477D01*
G01X1648197Y1733612D02*
X1654809D01*
G01Y1733218D02*
X1648197D01*
G01X1654561Y1733022D02*
X1648477D01*
G01X1648763Y1732532D02*
X1654571D01*
G01X1654819Y1732335D02*
X1648501D01*
G01Y1731350D02*
X1654819D01*
G01X1648763Y1731154D02*
X1654571D01*
G01X1654561Y1730659D02*
X1648477D01*
G01X1648197Y1730463D02*
X1654809D01*
G01Y1730069D02*
X1648197D01*
G01X1654561Y1729872D02*
X1648477D01*
G01X1648763Y1729382D02*
X1654571D01*
G01X1654819Y1729185D02*
X1648501D01*
G01Y1728201D02*
X1654819D01*
G01X1648763Y1728004D02*
X1654571D01*
G01X1654561Y1727510D02*
X1648477D01*
G01X1648197Y1727313D02*
X1654809D01*
G01Y1726919D02*
X1648197D01*
G01X1654561Y1726722D02*
X1648477D01*
G01X1658795Y1725640D02*
X1652326D01*
G01X1654631Y1724852D02*
X1648718D01*
G01X1654561Y1724360D02*
X1648477D01*
G01X1648294Y1724262D02*
X1655036D01*
G01X1649964Y1792864D02*
X1649925Y1792891D01*
X1649897Y1792963D01*
X1649887Y1793061D01*
G01X1649964Y1789714D02*
X1649925Y1789741D01*
X1649897Y1789813D01*
X1649887Y1789911D01*
G01X1649964Y1786565D02*
X1649925Y1786591D01*
X1649897Y1786663D01*
X1649887Y1786762D01*
G01X1649964Y1783415D02*
X1649925Y1783442D01*
X1649897Y1783514D01*
X1649887Y1783612D01*
G01X1649964Y1780266D02*
X1649925Y1780292D01*
X1649897Y1780364D01*
X1649887Y1780463D01*
G01X1649964Y1777116D02*
X1649925Y1777142D01*
X1649897Y1777215D01*
X1649887Y1777313D01*
G01X1650627Y1743752D02*
X1650621Y1743756D01*
X1650615Y1743767D01*
X1650609Y1743785D01*
X1650604Y1743810D01*
X1650600Y1743839D01*
X1650597Y1743873D01*
X1650595Y1743910D01*
Y1743949D01*
G01X1650627Y1740602D02*
X1650621Y1740606D01*
X1650615Y1740617D01*
X1650609Y1740635D01*
X1650604Y1740660D01*
X1650600Y1740690D01*
X1650597Y1740724D01*
X1650595Y1740760D01*
Y1740799D01*
G01X1650627Y1737453D02*
X1650621Y1737457D01*
X1650615Y1737468D01*
X1650609Y1737486D01*
X1650604Y1737511D01*
X1650600Y1737540D01*
X1650597Y1737574D01*
X1650595Y1737611D01*
Y1737650D01*
G01X1650627Y1734303D02*
X1650621Y1734307D01*
X1650615Y1734318D01*
X1650609Y1734336D01*
X1650604Y1734361D01*
X1650600Y1734391D01*
X1650597Y1734424D01*
X1650595Y1734461D01*
Y1734500D01*
G01X1649964Y1773966D02*
X1649925Y1773993D01*
X1649897Y1774065D01*
X1649887Y1774163D01*
G01X1649964Y1770817D02*
X1649925Y1770843D01*
X1649897Y1770915D01*
X1649887Y1771014D01*
G01X1649964Y1767667D02*
X1649925Y1767694D01*
X1649897Y1767766D01*
X1649887Y1767864D01*
G01X1649964Y1764518D02*
X1649925Y1764544D01*
X1649897Y1764616D01*
X1649887Y1764714D01*
G01X1649964Y1761368D02*
X1649925Y1761394D01*
X1649897Y1761467D01*
X1649887Y1761565D01*
G01X1649964Y1758218D02*
X1649925Y1758245D01*
X1649897Y1758317D01*
X1649887Y1758415D01*
G01X1649964Y1755069D02*
X1649925Y1755095D01*
X1649897Y1755167D01*
X1649887Y1755266D01*
G01X1649964Y1751919D02*
X1649925Y1751946D01*
X1649897Y1752018D01*
X1649887Y1752116D01*
G01X1649964Y1748770D02*
X1649925Y1748796D01*
X1649897Y1748868D01*
X1649887Y1748966D01*
G01X1649964Y1745620D02*
X1649925Y1745646D01*
X1649897Y1745718D01*
X1649887Y1745817D01*
G01X1649964Y1742470D02*
X1649925Y1742497D01*
X1649897Y1742569D01*
X1649887Y1742667D01*
G01X1649964Y1739321D02*
X1649925Y1739347D01*
X1649897Y1739419D01*
X1649887Y1739518D01*
G01X1649964Y1736171D02*
X1649925Y1736198D01*
X1649897Y1736270D01*
X1649887Y1736368D01*
G01X1649964Y1733022D02*
X1649925Y1733048D01*
X1649897Y1733120D01*
X1649887Y1733218D01*
G01X1649964Y1729872D02*
X1649925Y1729898D01*
X1649897Y1729970D01*
X1649887Y1730069D01*
G01X1649964Y1726722D02*
X1649925Y1726749D01*
X1649897Y1726821D01*
X1649887Y1726919D01*
G01X1650627Y1731154D02*
X1650621Y1731157D01*
X1650615Y1731168D01*
X1650609Y1731187D01*
X1650604Y1731211D01*
X1650600Y1731241D01*
X1650597Y1731275D01*
X1650595Y1731312D01*
Y1731350D01*
G01X1650627Y1728004D02*
X1650621Y1728008D01*
X1650615Y1728019D01*
X1650609Y1728037D01*
X1650604Y1728062D01*
X1650600Y1728091D01*
X1650597Y1728125D01*
X1650595Y1728162D01*
Y1728201D01*
G01X1656827Y1726801D02*
X1658795Y1724833D01*
G01X1655036Y1749262D02*
X1654902Y1749459D01*
X1654767Y1749656D01*
X1654631Y1749852D01*
G01X1654945Y1789262D02*
X1654808Y1789459D01*
X1654670Y1789656D01*
X1654531Y1789852D01*
G01X1654945Y1784262D02*
X1654808Y1784459D01*
X1654670Y1784656D01*
X1654531Y1784852D01*
G01X1654945Y1779262D02*
X1654808Y1779459D01*
X1654670Y1779656D01*
X1654531Y1779852D01*
G01X1654945Y1774262D02*
X1654808Y1774459D01*
X1654670Y1774656D01*
X1654531Y1774852D01*
G01X1654945Y1769262D02*
X1654808Y1769459D01*
X1654670Y1769656D01*
X1654531Y1769852D01*
G01X1656914Y1764262D02*
X1656777Y1764459D01*
X1656639Y1764656D01*
X1656500Y1764852D01*
G01X1654945Y1759262D02*
X1654808Y1759459D01*
X1654670Y1759656D01*
X1654531Y1759852D01*
G01X1654945Y1754262D02*
X1654808Y1754459D01*
X1654670Y1754656D01*
X1654531Y1754852D01*
G01X1648718Y1748277D02*
X1648294Y1748868D01*
G01X1648786Y1793277D02*
X1648359Y1793868D01*
G01X1648786Y1788277D02*
X1648359Y1788868D01*
G01X1648786Y1783277D02*
X1648359Y1783868D01*
G01X1648786Y1778277D02*
X1648359Y1778868D01*
G01X1648786Y1773277D02*
X1648359Y1773868D01*
G01X1648786Y1768277D02*
X1648359Y1768868D01*
G01X1650754Y1763277D02*
X1650328Y1763868D01*
G01X1648786Y1758277D02*
X1648359Y1758868D01*
G01X1648786Y1753277D02*
X1648359Y1753868D01*
G01X1655036Y1724262D02*
X1654902Y1724459D01*
X1654767Y1724656D01*
X1654631Y1724852D01*
G01X1654809Y1793455D02*
X1654777Y1793552D01*
X1654689Y1793624D01*
X1654561Y1793651D01*
G01X1654809Y1790305D02*
X1654777Y1790402D01*
X1654689Y1790474D01*
X1654561Y1790502D01*
G01X1654809Y1787155D02*
X1654777Y1787252D01*
X1654689Y1787325D01*
X1654561Y1787352D01*
G01X1654809Y1784006D02*
X1654777Y1784103D01*
X1654689Y1784175D01*
X1654561Y1784203D01*
G01X1654809Y1780856D02*
X1654777Y1780953D01*
X1654689Y1781025D01*
X1654561Y1781053D01*
G01X1654809Y1774557D02*
X1654777Y1774654D01*
X1654689Y1774726D01*
X1654561Y1774754D01*
G01X1654809Y1771407D02*
X1654777Y1771504D01*
X1654689Y1771577D01*
X1654561Y1771604D01*
G01X1654809Y1768258D02*
X1654777Y1768355D01*
X1654689Y1768427D01*
X1654561Y1768455D01*
G01X1654809Y1765108D02*
X1654777Y1765205D01*
X1654689Y1765277D01*
X1654561Y1765305D01*
G01X1654809Y1761959D02*
X1654777Y1762056D01*
X1654689Y1762128D01*
X1654561Y1762155D01*
G01X1654809Y1758809D02*
X1654777Y1758906D01*
X1654689Y1758978D01*
X1654561Y1759006D01*
G01X1654819Y1744933D02*
X1654785Y1745032D01*
X1654697Y1745103D01*
X1654571Y1745130D01*
G01X1649476Y1793277D02*
X1649203Y1793868D01*
G01X1649476Y1788277D02*
X1649203Y1788868D01*
G01X1649476Y1783277D02*
X1649203Y1783868D01*
G01X1649476Y1778277D02*
X1649203Y1778868D01*
G01X1649476Y1773277D02*
X1649203Y1773868D01*
G01X1649476Y1768277D02*
X1649203Y1768868D01*
G01X1651444Y1763277D02*
X1651172Y1763868D01*
G01X1649476Y1758277D02*
X1649203Y1758868D01*
G01X1649476Y1753277D02*
X1649203Y1753868D01*
G01X1649476Y1748277D02*
X1649203Y1748868D01*
G01X1654809Y1755659D02*
X1654777Y1755756D01*
X1654689Y1755829D01*
X1654561Y1755856D01*
G01X1654809Y1752510D02*
X1654777Y1752607D01*
X1654689Y1752679D01*
X1654561Y1752707D01*
G01X1654809Y1749360D02*
X1654777Y1749457D01*
X1654689Y1749529D01*
X1654561Y1749557D01*
G01X1654809Y1746211D02*
X1654777Y1746308D01*
X1654689Y1746380D01*
X1654561Y1746407D01*
G01X1654809Y1743061D02*
X1654777Y1743158D01*
X1654689Y1743230D01*
X1654561Y1743258D01*
G01X1654809Y1739911D02*
X1654777Y1740008D01*
X1654689Y1740081D01*
X1654561Y1740108D01*
G01X1654809Y1736762D02*
X1654777Y1736859D01*
X1654689Y1736931D01*
X1654561Y1736959D01*
G01X1654809Y1733612D02*
X1654777Y1733709D01*
X1654689Y1733781D01*
X1654561Y1733809D01*
G01X1654809Y1730463D02*
X1654777Y1730560D01*
X1654689Y1730632D01*
X1654561Y1730659D01*
G01X1654809Y1727313D02*
X1654777Y1727410D01*
X1654689Y1727482D01*
X1654561Y1727510D01*
G01X1654819Y1741784D02*
X1654785Y1741883D01*
X1654697Y1741953D01*
X1654571Y1741980D01*
G01X1654819Y1738634D02*
X1654785Y1738733D01*
X1654697Y1738804D01*
X1654571Y1738831D01*
G01X1654819Y1735484D02*
X1654785Y1735583D01*
X1654697Y1735654D01*
X1654571Y1735681D01*
G01X1654819Y1732335D02*
X1654785Y1732434D01*
X1654697Y1732505D01*
X1654571Y1732532D01*
G01X1654819Y1729185D02*
X1654785Y1729284D01*
X1654697Y1729355D01*
X1654571Y1729382D01*
G01X1650328Y1793868D02*
X1650405Y1793277D01*
G01X1650328Y1788868D02*
X1650405Y1788277D01*
G01X1650328Y1783868D02*
X1650405Y1783277D01*
G01X1650328Y1778868D02*
X1650405Y1778277D01*
G01X1652296Y1763868D02*
X1652374Y1763277D01*
G01X1650328Y1773868D02*
X1650405Y1773277D01*
G01X1650328Y1768868D02*
X1650405Y1768277D01*
G01X1650328Y1758868D02*
X1650405Y1758277D01*
G01X1650328Y1753868D02*
X1650405Y1753277D01*
G01X1650328Y1748868D02*
X1650405Y1748277D01*
G01X1649374Y1793061D02*
X1649377Y1793023D01*
X1649385Y1792986D01*
X1649397Y1792952D01*
X1649415Y1792922D01*
X1649436Y1792897D01*
X1649459Y1792879D01*
X1649485Y1792868D01*
X1649513Y1792864D01*
G01X1649374Y1789911D02*
X1649377Y1789873D01*
X1649385Y1789836D01*
X1649397Y1789802D01*
X1649415Y1789772D01*
X1649436Y1789748D01*
X1649459Y1789730D01*
X1649485Y1789718D01*
X1649513Y1789714D01*
G01X1649374Y1786762D02*
X1649377Y1786723D01*
X1649385Y1786687D01*
X1649397Y1786653D01*
X1649415Y1786623D01*
X1649436Y1786598D01*
X1649459Y1786580D01*
X1649485Y1786569D01*
X1649513Y1786565D01*
G01X1649374Y1783612D02*
X1649377Y1783574D01*
X1649385Y1783537D01*
X1649397Y1783503D01*
X1649415Y1783473D01*
X1649436Y1783449D01*
X1649459Y1783430D01*
X1649485Y1783419D01*
X1649513Y1783415D01*
G01X1649374Y1780463D02*
X1649377Y1780424D01*
X1649385Y1780387D01*
X1649397Y1780354D01*
X1649415Y1780323D01*
X1649436Y1780299D01*
X1649459Y1780281D01*
X1649485Y1780270D01*
X1649513Y1780266D01*
G01X1649374Y1777313D02*
X1649377Y1777275D01*
X1649385Y1777238D01*
X1649397Y1777204D01*
X1649415Y1777174D01*
X1649436Y1777149D01*
X1649459Y1777131D01*
X1649485Y1777120D01*
X1649513Y1777116D01*
G01X1649374Y1774163D02*
X1649377Y1774125D01*
X1649385Y1774088D01*
X1649397Y1774054D01*
X1649415Y1774024D01*
X1649436Y1774000D01*
X1649459Y1773982D01*
X1649485Y1773970D01*
X1649513Y1773966D01*
G01X1649374Y1771014D02*
X1649377Y1770975D01*
X1649385Y1770939D01*
X1649397Y1770905D01*
X1649415Y1770874D01*
X1649436Y1770850D01*
X1649459Y1770832D01*
X1649485Y1770821D01*
X1649513Y1770817D01*
G01X1649374Y1767864D02*
X1649377Y1767826D01*
X1649385Y1767789D01*
X1649397Y1767755D01*
X1649415Y1767725D01*
X1649436Y1767701D01*
X1649459Y1767682D01*
X1649485Y1767671D01*
X1649513Y1767667D01*
G01X1649374Y1764714D02*
X1649377Y1764676D01*
X1649385Y1764639D01*
X1649397Y1764606D01*
X1649415Y1764575D01*
X1649436Y1764551D01*
X1649459Y1764533D01*
X1649485Y1764521D01*
X1649513Y1764518D01*
G01X1649374Y1761565D02*
X1649377Y1761527D01*
X1649385Y1761490D01*
X1649397Y1761456D01*
X1649415Y1761426D01*
X1649436Y1761401D01*
X1649459Y1761383D01*
X1649485Y1761372D01*
X1649513Y1761368D01*
G01X1649374Y1758415D02*
X1649377Y1758377D01*
X1649385Y1758340D01*
X1649397Y1758306D01*
X1649415Y1758276D01*
X1649436Y1758252D01*
X1649459Y1758234D01*
X1649485Y1758222D01*
X1649513Y1758218D01*
G01X1649374Y1755266D02*
X1649377Y1755227D01*
X1649385Y1755191D01*
X1649397Y1755157D01*
X1649415Y1755126D01*
X1649436Y1755102D01*
X1649459Y1755084D01*
X1649485Y1755073D01*
X1649513Y1755069D01*
G01X1649374Y1752116D02*
X1649377Y1752078D01*
X1649385Y1752041D01*
X1649397Y1752007D01*
X1649415Y1751977D01*
X1649436Y1751952D01*
X1649459Y1751934D01*
X1649485Y1751923D01*
X1649513Y1751919D01*
G01X1649374Y1748966D02*
X1649377Y1748928D01*
X1649385Y1748891D01*
X1649397Y1748857D01*
X1649415Y1748827D01*
X1649436Y1748803D01*
X1649459Y1748785D01*
X1649485Y1748773D01*
X1649513Y1748770D01*
G01X1649374Y1745817D02*
X1649377Y1745779D01*
X1649385Y1745742D01*
X1649397Y1745708D01*
X1649415Y1745678D01*
X1649436Y1745653D01*
X1649459Y1745635D01*
X1649485Y1745624D01*
X1649513Y1745620D01*
G01X1649374Y1742667D02*
X1649377Y1742629D01*
X1649385Y1742592D01*
X1649397Y1742558D01*
X1649415Y1742528D01*
X1649436Y1742504D01*
X1649459Y1742485D01*
X1649485Y1742474D01*
X1649513Y1742470D01*
G01X1649374Y1739518D02*
X1649377Y1739479D01*
X1649385Y1739443D01*
X1649397Y1739409D01*
X1649415Y1739378D01*
X1649436Y1739354D01*
X1649459Y1739336D01*
X1649485Y1739325D01*
X1649513Y1739321D01*
G01X1649374Y1736368D02*
X1649377Y1736330D01*
X1649385Y1736293D01*
X1649397Y1736259D01*
X1649415Y1736229D01*
X1649436Y1736204D01*
X1649459Y1736186D01*
X1649485Y1736175D01*
X1649513Y1736171D01*
G01X1649374Y1733218D02*
X1649377Y1733180D01*
X1649385Y1733143D01*
X1649397Y1733109D01*
X1649415Y1733079D01*
X1649436Y1733055D01*
X1649459Y1733037D01*
X1649485Y1733025D01*
X1649513Y1733022D01*
G01X1649374Y1730069D02*
X1649377Y1730031D01*
X1649385Y1729994D01*
X1649397Y1729960D01*
X1649415Y1729930D01*
X1649436Y1729905D01*
X1649459Y1729887D01*
X1649485Y1729876D01*
X1649513Y1729872D01*
G01X1649374Y1726919D02*
X1649377Y1726881D01*
X1649385Y1726844D01*
X1649397Y1726810D01*
X1649415Y1726780D01*
X1649436Y1726756D01*
X1649459Y1726737D01*
X1649485Y1726726D01*
X1649513Y1726722D01*
G01X1649887Y1727313D02*
X1649897Y1727411D01*
X1649925Y1727483D01*
X1649964Y1727510D01*
G01X1649887Y1730463D02*
X1649897Y1730561D01*
X1649925Y1730633D01*
X1649964Y1730659D01*
G01X1649887Y1733612D02*
X1649897Y1733710D01*
X1649925Y1733783D01*
X1649964Y1733809D01*
G01X1649887Y1736762D02*
X1649897Y1736860D01*
X1649925Y1736932D01*
X1649964Y1736959D01*
G01X1649887Y1743061D02*
X1649897Y1743159D01*
X1649925Y1743231D01*
X1649964Y1743258D01*
G01X1649887Y1746211D02*
X1649897Y1746309D01*
X1649925Y1746381D01*
X1649964Y1746407D01*
G01X1649887Y1749360D02*
X1649897Y1749458D01*
X1649925Y1749531D01*
X1649964Y1749557D01*
G01X1649887Y1752510D02*
X1649897Y1752608D01*
X1649925Y1752680D01*
X1649964Y1752707D01*
G01X1649887Y1755659D02*
X1649897Y1755758D01*
X1649925Y1755830D01*
X1649964Y1755856D01*
G01X1649887Y1758809D02*
X1649897Y1758907D01*
X1649925Y1758979D01*
X1649964Y1759006D01*
G01X1649887Y1761959D02*
X1649897Y1762057D01*
X1649925Y1762129D01*
X1649964Y1762155D01*
G01X1649887Y1765108D02*
X1649897Y1765207D01*
X1649925Y1765279D01*
X1649964Y1765305D01*
G01X1649887Y1768258D02*
X1649897Y1768356D01*
X1649925Y1768428D01*
X1649964Y1768455D01*
G01X1649887Y1771407D02*
X1649897Y1771506D01*
X1649925Y1771578D01*
X1649964Y1771604D01*
G01X1649887Y1774557D02*
X1649897Y1774655D01*
X1649925Y1774727D01*
X1649964Y1774754D01*
G01X1649887Y1777707D02*
X1649897Y1777805D01*
X1649925Y1777877D01*
X1649964Y1777903D01*
G01X1649887Y1780856D02*
X1649897Y1780955D01*
X1649925Y1781027D01*
X1649964Y1781053D01*
G01X1649887Y1784006D02*
X1649897Y1784104D01*
X1649925Y1784176D01*
X1649964Y1784203D01*
G01X1649887Y1787155D02*
X1649897Y1787254D01*
X1649925Y1787326D01*
X1649964Y1787352D01*
G01X1649887Y1790305D02*
X1649897Y1790403D01*
X1649925Y1790475D01*
X1649964Y1790502D01*
G01X1649887Y1793455D02*
X1649897Y1793553D01*
X1649925Y1793625D01*
X1649964Y1793651D01*
G01X1649443Y1729185D02*
X1649445Y1729223D01*
X1649454Y1729260D01*
X1649467Y1729294D01*
X1649486Y1729324D01*
X1649508Y1729349D01*
X1649534Y1729367D01*
X1649561Y1729378D01*
X1649590Y1729382D01*
G01X1649443Y1732335D02*
X1649445Y1732373D01*
X1649454Y1732410D01*
X1649467Y1732444D01*
X1649486Y1732474D01*
X1649508Y1732498D01*
X1649534Y1732516D01*
X1649561Y1732528D01*
X1649590Y1732532D01*
G01X1649443Y1735484D02*
X1649445Y1735523D01*
X1649454Y1735559D01*
X1649467Y1735593D01*
X1649486Y1735624D01*
X1649508Y1735648D01*
X1649534Y1735666D01*
X1649561Y1735677D01*
X1649590Y1735681D01*
G01X1649443Y1738634D02*
X1649445Y1738672D01*
X1649454Y1738709D01*
X1649467Y1738743D01*
X1649486Y1738773D01*
X1649508Y1738798D01*
X1649534Y1738816D01*
X1649561Y1738827D01*
X1649590Y1738831D01*
G01X1649443Y1741784D02*
X1649445Y1741822D01*
X1649454Y1741859D01*
X1649467Y1741892D01*
X1649486Y1741923D01*
X1649508Y1741947D01*
X1649534Y1741965D01*
X1649561Y1741977D01*
X1649590Y1741980D01*
G01X1649443Y1744933D02*
X1649445Y1744971D01*
X1649454Y1745008D01*
X1649467Y1745042D01*
X1649486Y1745072D01*
X1649508Y1745097D01*
X1649534Y1745115D01*
X1649561Y1745126D01*
X1649590Y1745130D01*
G01X1650595Y1729185D02*
Y1729223D01*
X1650597Y1729260D01*
X1650600Y1729294D01*
X1650604Y1729324D01*
X1650609Y1729349D01*
X1650615Y1729367D01*
X1650621Y1729378D01*
X1650627Y1729382D01*
G01X1650595Y1732335D02*
Y1732373D01*
X1650597Y1732410D01*
X1650600Y1732444D01*
X1650604Y1732474D01*
X1650609Y1732498D01*
X1650615Y1732516D01*
X1650621Y1732528D01*
X1650627Y1732532D01*
G01X1650595Y1735484D02*
Y1735523D01*
X1650597Y1735559D01*
X1650600Y1735593D01*
X1650604Y1735624D01*
X1650609Y1735648D01*
X1650615Y1735666D01*
X1650621Y1735677D01*
X1650627Y1735681D01*
G01X1650595Y1738634D02*
Y1738672D01*
X1650597Y1738709D01*
X1650600Y1738743D01*
X1650604Y1738773D01*
X1650609Y1738798D01*
X1650615Y1738816D01*
X1650621Y1738827D01*
X1650627Y1738831D01*
G01X1650595Y1741784D02*
Y1741822D01*
X1650597Y1741859D01*
X1650600Y1741892D01*
X1650604Y1741923D01*
X1650609Y1741947D01*
X1650615Y1741965D01*
X1650621Y1741977D01*
X1650627Y1741980D01*
G01X1650595Y1744933D02*
Y1744971D01*
X1650597Y1745008D01*
X1650600Y1745042D01*
X1650604Y1745072D01*
X1650609Y1745097D01*
X1650615Y1745115D01*
X1650621Y1745126D01*
X1650627Y1745130D01*
G01X1657784Y1752766D02*
Y1747286D01*
G01X1657614Y1725640D02*
Y1747490D01*
G01Y1823671D02*
Y1752766D01*
G01X1656914Y1764262D02*
Y1763868D01*
G01X1655036Y1749262D02*
Y1748868D01*
G01X1654945Y1754262D02*
Y1753868D01*
G01Y1759262D02*
Y1758868D01*
G01Y1769262D02*
Y1768868D01*
G01Y1774262D02*
Y1773868D01*
G01Y1779262D02*
Y1778868D01*
G01Y1784262D02*
Y1783868D01*
G01Y1789262D02*
Y1788868D01*
G01X1654819Y1729185D02*
Y1728201D01*
G01Y1735484D02*
Y1734500D01*
G01Y1732335D02*
Y1731350D01*
G01Y1738634D02*
Y1737650D01*
G01Y1741784D02*
Y1740799D01*
G01Y1744933D02*
Y1743949D01*
G01X1654809Y1793061D02*
Y1793455D01*
G01Y1789911D02*
Y1790305D01*
G01Y1786762D02*
Y1787155D01*
G01Y1783612D02*
Y1784006D01*
G01Y1777313D02*
Y1777707D01*
G01Y1780463D02*
Y1780856D01*
G01Y1774163D02*
Y1774557D01*
G01Y1771014D02*
Y1771407D01*
G01Y1767864D02*
Y1768258D01*
G01Y1764714D02*
Y1765108D01*
G01Y1761565D02*
Y1761959D01*
G01Y1755266D02*
Y1755659D01*
G01Y1758415D02*
Y1758809D01*
G01Y1752116D02*
Y1752510D01*
G01Y1745817D02*
Y1746211D01*
G01Y1748966D02*
Y1749360D01*
G01Y1742667D02*
Y1743061D01*
G01Y1739518D02*
Y1739911D01*
G01Y1736368D02*
Y1736762D01*
G01Y1733218D02*
Y1733612D01*
G01Y1730069D02*
Y1730463D01*
G01Y1726919D02*
Y1727313D01*
G01X1652326Y1726821D02*
Y1725640D01*
G01Y1747490D02*
Y1746309D01*
G01X1652296Y1764262D02*
Y1763868D01*
G01X1651172D02*
Y1764262D01*
G01X1650595Y1743949D02*
Y1744933D01*
G01Y1740799D02*
Y1741784D01*
G01Y1737650D02*
Y1738634D01*
G01Y1734500D02*
Y1735484D01*
G01Y1731350D02*
Y1732335D01*
G01Y1728201D02*
Y1729185D01*
G01X1650328Y1763868D02*
Y1764262D01*
G01Y1749262D02*
Y1748868D01*
G01Y1754262D02*
Y1753868D01*
G01Y1759262D02*
Y1758868D01*
G01Y1769262D02*
Y1768868D01*
G01Y1774262D02*
Y1773868D01*
G01Y1779262D02*
Y1778868D01*
G01Y1784262D02*
Y1783868D01*
G01Y1789262D02*
Y1788868D01*
G01X1649887Y1793061D02*
Y1793455D01*
G01Y1789911D02*
Y1790305D01*
G01Y1786762D02*
Y1787155D01*
G01Y1783612D02*
Y1784006D01*
G01Y1777313D02*
Y1777707D01*
G01Y1780463D02*
Y1780856D01*
G01Y1774163D02*
Y1774557D01*
G01Y1771014D02*
Y1771407D01*
G01Y1767864D02*
Y1768258D01*
G01Y1764714D02*
Y1765108D01*
G01Y1761565D02*
Y1761959D01*
G01Y1755266D02*
Y1755659D01*
G01Y1758415D02*
Y1758809D01*
G01Y1752116D02*
Y1752510D01*
G01Y1745817D02*
Y1746211D01*
G01Y1748966D02*
Y1749360D01*
G01Y1742667D02*
Y1743061D01*
G01Y1739518D02*
Y1739911D01*
G01Y1736368D02*
Y1736762D01*
G01Y1733218D02*
Y1733612D01*
G01Y1730069D02*
Y1730463D01*
G01Y1726919D02*
Y1727313D01*
G01X1649443Y1743949D02*
Y1744933D01*
G01Y1740799D02*
Y1741784D01*
G01Y1737650D02*
Y1738634D01*
G01Y1734500D02*
Y1735484D01*
G01Y1731350D02*
Y1732335D01*
G01Y1728201D02*
Y1729185D01*
G01X1649374Y1730463D02*
Y1730069D01*
G01Y1727313D02*
Y1726919D01*
G01Y1733612D02*
Y1733218D01*
G01Y1739911D02*
Y1739518D01*
G01Y1736762D02*
Y1736368D01*
G01Y1743061D02*
Y1742667D01*
G01Y1746211D02*
Y1745817D01*
G01Y1749360D02*
Y1748966D01*
G01Y1752510D02*
Y1752116D01*
G01Y1755659D02*
Y1755266D01*
G01Y1758809D02*
Y1758415D01*
G01Y1761959D02*
Y1761565D01*
G01Y1768258D02*
Y1767864D01*
G01Y1765108D02*
Y1764714D01*
G01Y1771407D02*
Y1771014D01*
G01Y1774557D02*
Y1774163D01*
G01Y1777707D02*
Y1777313D01*
G01Y1780856D02*
Y1780463D01*
G01Y1784006D02*
Y1783612D01*
G01Y1790305D02*
Y1789911D01*
G01Y1787155D02*
Y1786762D01*
G01Y1793455D02*
Y1793061D01*
G01X1649203Y1788868D02*
Y1789262D01*
G01Y1783868D02*
Y1784262D01*
G01Y1778868D02*
Y1779262D01*
G01Y1773868D02*
Y1774262D01*
G01Y1768868D02*
Y1769262D01*
G01Y1758868D02*
Y1759262D01*
G01Y1753868D02*
Y1754262D01*
G01Y1748868D02*
Y1749262D01*
G01X1648501Y1743949D02*
Y1744933D01*
G01Y1740799D02*
Y1741784D01*
G01Y1737650D02*
Y1738634D01*
G01Y1734500D02*
Y1735484D01*
G01Y1731350D02*
Y1732335D01*
G01Y1728201D02*
Y1729185D01*
G01X1648359Y1788868D02*
Y1789262D01*
G01Y1783868D02*
Y1784262D01*
G01Y1778868D02*
Y1779262D01*
G01Y1773868D02*
Y1774262D01*
G01Y1768868D02*
Y1769262D01*
G01Y1758868D02*
Y1759262D01*
G01Y1753868D02*
Y1754262D01*
G01X1648294Y1748868D02*
Y1749262D01*
G01X1648197Y1730463D02*
Y1730069D01*
G01Y1727313D02*
Y1726919D01*
G01Y1733612D02*
Y1733218D01*
G01Y1739911D02*
Y1739518D01*
G01Y1736762D02*
Y1736368D01*
G01Y1743061D02*
Y1742667D01*
G01Y1746211D02*
Y1745817D01*
G01Y1749360D02*
Y1748966D01*
G01Y1752510D02*
Y1752116D01*
G01Y1755659D02*
Y1755266D01*
G01Y1758809D02*
Y1758415D01*
G01Y1761959D02*
Y1761565D01*
G01Y1768258D02*
Y1767864D01*
G01Y1765108D02*
Y1764714D01*
G01Y1771407D02*
Y1771014D01*
G01Y1774557D02*
Y1774163D01*
G01Y1777707D02*
Y1777313D01*
G01Y1780856D02*
Y1780463D01*
G01Y1784006D02*
Y1783612D01*
G01Y1790305D02*
Y1789911D01*
G01Y1787155D02*
Y1786762D01*
G01Y1793455D02*
Y1793061D01*
G01X1650328Y1724262D02*
X1650405Y1724852D01*
G01X1650328Y1749262D02*
X1650405Y1749852D01*
G01X1652296Y1764262D02*
X1652374Y1764852D01*
G01X1650328Y1754262D02*
X1650405Y1754852D01*
G01X1650328Y1759262D02*
X1650405Y1759852D01*
G01X1650328Y1769262D02*
X1650405Y1769852D01*
G01X1650328Y1774262D02*
X1650405Y1774852D01*
G01X1650328Y1779262D02*
X1650405Y1779852D01*
G01X1650328Y1784262D02*
X1650405Y1784852D01*
G01X1650328Y1789262D02*
X1650405Y1789852D01*
G01X1648718Y1724852D02*
X1648294Y1724262D01*
G01X1649203D02*
X1649476Y1724852D01*
G01X1649203Y1749262D02*
X1649476Y1749852D01*
G01X1649203Y1754262D02*
X1649476Y1754852D01*
G01X1649203Y1759262D02*
X1649476Y1759852D01*
G01X1651172Y1764262D02*
X1651444Y1764852D01*
G01X1649203Y1769262D02*
X1649476Y1769852D01*
G01X1649203Y1774262D02*
X1649476Y1774852D01*
G01X1649203Y1779262D02*
X1649476Y1779852D01*
G01X1649203Y1784262D02*
X1649476Y1784852D01*
G01X1649203Y1789262D02*
X1649476Y1789852D01*
G01X1654809Y1777313D02*
X1654775Y1777214D01*
X1654687Y1777143D01*
X1654561Y1777116D01*
G01X1649964Y1740108D02*
X1649925Y1740082D01*
X1649897Y1740010D01*
X1649887Y1739911D01*
G01X1658795Y1748297D02*
X1656827Y1746329D01*
G01X1648786Y1754852D02*
X1648359Y1754262D01*
G01X1648786Y1759852D02*
X1648359Y1759262D01*
G01X1650754Y1764852D02*
X1650328Y1764262D01*
G01X1648786Y1769852D02*
X1648359Y1769262D01*
G01X1648786Y1774852D02*
X1648359Y1774262D01*
G01X1648786Y1779852D02*
X1648359Y1779262D01*
G01X1648786Y1784852D02*
X1648359Y1784262D01*
G01X1648786Y1789852D02*
X1648359Y1789262D01*
G01X1648718Y1749852D02*
X1648294Y1749262D01*
G01X1654531Y1753277D02*
X1654670Y1753473D01*
X1654808Y1753670D01*
X1654945Y1753868D01*
G01X1654531Y1758277D02*
X1654670Y1758473D01*
X1654808Y1758670D01*
X1654945Y1758868D01*
G01X1656500Y1763277D02*
X1656639Y1763473D01*
X1656777Y1763670D01*
X1656914Y1763868D01*
G01X1654531Y1768277D02*
X1654670Y1768473D01*
X1654808Y1768670D01*
X1654945Y1768868D01*
G01X1654531Y1773277D02*
X1654670Y1773473D01*
X1654808Y1773670D01*
X1654945Y1773868D01*
G01X1654531Y1778277D02*
X1654670Y1778473D01*
X1654808Y1778670D01*
X1654945Y1778868D01*
G01X1654531Y1783277D02*
X1654670Y1783473D01*
X1654808Y1783670D01*
X1654945Y1783868D01*
G01X1654531Y1788277D02*
X1654670Y1788473D01*
X1654808Y1788670D01*
X1654945Y1788868D01*
G01X1654531Y1793277D02*
X1654670Y1793473D01*
X1654808Y1793670D01*
X1654945Y1793868D01*
G01X1654631Y1748277D02*
X1654767Y1748474D01*
X1654902Y1748670D01*
X1655036Y1748868D01*
G01X1742653Y1763770D02*
G03I-15748J0D01*
G01X1649513Y1796801D02*
X1649486Y1796797D01*
X1649460Y1796786D01*
X1649436Y1796768D01*
X1649415Y1796743D01*
X1649397Y1796714D01*
X1649385Y1796680D01*
X1649377Y1796643D01*
X1649374Y1796604D01*
G01X1654561Y1796014D02*
X1654689Y1796041D01*
X1654777Y1796114D01*
X1654809Y1796211D01*
G01X1654561Y1796801D02*
X1648477D01*
G01X1648197Y1796604D02*
X1654809D01*
G01Y1796211D02*
X1648197D01*
G01X1654561Y1796014D02*
X1648477D01*
G01X1654531Y1794852D02*
X1648786D01*
G01X1648359Y1794262D02*
X1654945D01*
G01X1648359Y1793868D02*
X1654945D01*
G01X1649964Y1796014D02*
X1649925Y1796040D01*
X1649897Y1796112D01*
X1649887Y1796211D01*
G01X1654945Y1794262D02*
X1654808Y1794459D01*
X1654670Y1794656D01*
X1654531Y1794852D01*
G01X1654809Y1796604D02*
X1654777Y1796701D01*
X1654689Y1796773D01*
X1654561Y1796801D01*
G01X1649374Y1796211D02*
X1649377Y1796172D01*
X1649385Y1796136D01*
X1649397Y1796102D01*
X1649415Y1796071D01*
X1649436Y1796047D01*
X1649459Y1796029D01*
X1649485Y1796018D01*
X1649513Y1796014D01*
G01X1649887Y1796604D02*
X1649897Y1796703D01*
X1649925Y1796775D01*
X1649964Y1796801D01*
G01X1654945Y1794262D02*
Y1793868D01*
G01X1654809Y1796211D02*
Y1796604D01*
G01X1650328Y1794262D02*
Y1793868D01*
G01X1649887Y1796211D02*
Y1796604D01*
G01X1649374D02*
Y1796211D01*
G01X1649203Y1793868D02*
Y1794262D01*
G01X1648359Y1793868D02*
Y1794262D01*
G01X1648197Y1796604D02*
Y1796211D01*
G01X1650328Y1794262D02*
X1650405Y1794852D01*
G01X1649203Y1794262D02*
X1649476Y1794852D01*
G01X1648786D02*
X1648359Y1794262D01*
G01X1662079Y1827805D02*
X1658795D01*
G01X1654531Y1819852D02*
X1648786D01*
G01X1648359Y1819262D02*
X1654945D01*
G01X1648359Y1818868D02*
X1654945D01*
G01X1654561Y1818848D02*
X1648477D01*
G01X1648197Y1818651D02*
X1654809D01*
G01X1654531Y1818277D02*
X1648786D01*
G01X1654809Y1818258D02*
X1648197D01*
G01X1654561Y1818061D02*
X1648477D01*
G01X1654561Y1815699D02*
X1648477D01*
G01X1648197Y1815502D02*
X1654809D01*
G01Y1815108D02*
X1648197D01*
G01X1654561Y1814911D02*
X1648477D01*
G01X1654531Y1814852D02*
X1648786D01*
G01X1648359Y1814262D02*
X1654945D01*
G01X1648359Y1813868D02*
X1654945D01*
G01X1654531Y1813277D02*
X1648786D01*
G01X1649513Y1818848D02*
X1649486Y1818845D01*
X1649460Y1818833D01*
X1649436Y1818815D01*
X1649415Y1818791D01*
X1649397Y1818761D01*
X1649385Y1818727D01*
X1649377Y1818690D01*
X1649374Y1818651D01*
G01X1649513Y1815699D02*
X1649486Y1815695D01*
X1649460Y1815684D01*
X1649436Y1815666D01*
X1649415Y1815641D01*
X1649397Y1815611D01*
X1649385Y1815578D01*
X1649377Y1815541D01*
X1649374Y1815502D01*
G01X1649513Y1812549D02*
X1649486Y1812545D01*
X1649460Y1812534D01*
X1649436Y1812516D01*
X1649415Y1812491D01*
X1649397Y1812462D01*
X1649385Y1812428D01*
X1649377Y1812391D01*
X1649374Y1812352D01*
G01X1649513Y1809400D02*
X1649486Y1809396D01*
X1649460Y1809385D01*
X1649436Y1809367D01*
X1649415Y1809342D01*
X1649397Y1809312D01*
X1649385Y1809278D01*
X1649377Y1809242D01*
X1649374Y1809203D01*
G01X1649513Y1806250D02*
X1649486Y1806246D01*
X1649460Y1806235D01*
X1649436Y1806217D01*
X1649415Y1806192D01*
X1649397Y1806163D01*
X1649385Y1806129D01*
X1649377Y1806092D01*
X1649374Y1806053D01*
G01X1649513Y1803100D02*
X1649486Y1803097D01*
X1649460Y1803085D01*
X1649436Y1803067D01*
X1649415Y1803043D01*
X1649397Y1803013D01*
X1649385Y1802979D01*
X1649377Y1802942D01*
X1649374Y1802903D01*
G01X1649513Y1799951D02*
X1649486Y1799947D01*
X1649460Y1799936D01*
X1649436Y1799918D01*
X1649415Y1799893D01*
X1649397Y1799863D01*
X1649385Y1799829D01*
X1649377Y1799793D01*
X1649374Y1799754D01*
G01X1654561Y1818061D02*
X1654689Y1818089D01*
X1654777Y1818162D01*
X1654809Y1818258D01*
G01X1654561Y1814911D02*
X1654689Y1814939D01*
X1654777Y1815012D01*
X1654809Y1815108D01*
G01X1654561Y1811762D02*
X1654689Y1811789D01*
X1654777Y1811862D01*
X1654809Y1811959D01*
G01X1654561Y1808612D02*
X1654689Y1808640D01*
X1654777Y1808713D01*
X1654809Y1808809D01*
G01X1654561Y1802313D02*
X1654689Y1802341D01*
X1654777Y1802414D01*
X1654809Y1802510D01*
G01X1654561Y1799163D02*
X1654689Y1799191D01*
X1654777Y1799264D01*
X1654809Y1799360D01*
G01X1654561Y1812549D02*
X1648477D01*
G01X1648197Y1812352D02*
X1654809D01*
G01Y1811959D02*
X1648197D01*
G01X1654561Y1811762D02*
X1648477D01*
G01X1654531Y1809852D02*
X1648786D01*
G01X1654561Y1809400D02*
X1648477D01*
G01X1648359Y1809262D02*
X1654945D01*
G01X1648197Y1809203D02*
X1654809D01*
G01X1648359Y1808868D02*
X1654945D01*
G01X1654809Y1808809D02*
X1648197D01*
G01X1654561Y1808612D02*
X1648477D01*
G01X1654531Y1808277D02*
X1648786D01*
G01X1654561Y1806250D02*
X1648477D01*
G01X1648197Y1806053D02*
X1654809D01*
G01Y1805659D02*
X1648197D01*
G01X1654561Y1805463D02*
X1648477D01*
G01X1656500Y1804852D02*
X1650754D01*
G01X1650328Y1804262D02*
X1656914D01*
G01X1650328Y1803868D02*
X1656914D01*
G01X1656500Y1803277D02*
X1650754D01*
G01X1654561Y1803100D02*
X1648477D01*
G01X1648197Y1802903D02*
X1654809D01*
G01Y1802510D02*
X1648197D01*
G01X1654561Y1802313D02*
X1648477D01*
G01X1654561Y1799951D02*
X1648477D01*
G01X1654531Y1799852D02*
X1648786D01*
G01X1648197Y1799754D02*
X1654809D01*
G01Y1799360D02*
X1648197D01*
G01X1648359Y1799262D02*
X1654945D01*
G01X1654561Y1799163D02*
X1648477D01*
G01X1648359Y1798868D02*
X1654945D01*
G01X1654531Y1798277D02*
X1648786D01*
G01X1654561Y1806250D02*
X1654688Y1806223D01*
X1654777Y1806150D01*
X1654809Y1806053D01*
G01X1649964Y1818061D02*
X1649925Y1818087D01*
X1649897Y1818159D01*
X1649887Y1818258D01*
G01X1649964Y1814911D02*
X1649925Y1814938D01*
X1649897Y1815010D01*
X1649887Y1815108D01*
G01X1649964Y1811762D02*
X1649925Y1811788D01*
X1649897Y1811860D01*
X1649887Y1811959D01*
G01X1649964Y1808612D02*
X1649925Y1808639D01*
X1649897Y1808711D01*
X1649887Y1808809D01*
G01X1649964Y1805463D02*
X1649925Y1805489D01*
X1649897Y1805561D01*
X1649887Y1805659D01*
G01X1649964Y1802313D02*
X1649925Y1802339D01*
X1649897Y1802411D01*
X1649887Y1802510D01*
G01X1649964Y1799163D02*
X1649925Y1799190D01*
X1649897Y1799262D01*
X1649887Y1799360D01*
G01X1656827Y1827805D02*
X1658795Y1825837D01*
G01X1654945Y1819262D02*
X1654808Y1819459D01*
X1654670Y1819656D01*
X1654531Y1819852D01*
G01X1654945Y1814262D02*
X1654808Y1814459D01*
X1654670Y1814656D01*
X1654531Y1814852D01*
G01X1654945Y1809262D02*
X1654808Y1809459D01*
X1654670Y1809656D01*
X1654531Y1809852D01*
G01X1656914Y1804262D02*
X1656777Y1804459D01*
X1656639Y1804656D01*
X1656500Y1804852D01*
G01X1654945Y1799262D02*
X1654808Y1799459D01*
X1654670Y1799656D01*
X1654531Y1799852D01*
G01X1648786Y1818277D02*
X1648359Y1818868D01*
G01X1648786Y1813277D02*
X1648359Y1813868D01*
G01X1648786Y1808277D02*
X1648359Y1808868D01*
G01X1650754Y1803277D02*
X1650328Y1803868D01*
G01X1648786Y1798277D02*
X1648359Y1798868D01*
G01X1649476Y1818277D02*
X1649203Y1818868D01*
G01X1649476Y1813277D02*
X1649203Y1813868D01*
G01X1649476Y1808277D02*
X1649203Y1808868D01*
G01X1651444Y1803277D02*
X1651172Y1803868D01*
G01X1649476Y1798277D02*
X1649203Y1798868D01*
G01X1654809Y1818651D02*
X1654777Y1818748D01*
X1654689Y1818821D01*
X1654561Y1818848D01*
G01X1654809Y1815502D02*
X1654777Y1815599D01*
X1654689Y1815671D01*
X1654561Y1815699D01*
G01X1654809Y1812352D02*
X1654777Y1812449D01*
X1654689Y1812521D01*
X1654561Y1812549D01*
G01X1654809Y1809203D02*
X1654777Y1809300D01*
X1654689Y1809372D01*
X1654561Y1809400D01*
G01X1654809Y1802903D02*
X1654777Y1803000D01*
X1654689Y1803073D01*
X1654561Y1803100D01*
G01X1654809Y1799754D02*
X1654777Y1799851D01*
X1654689Y1799923D01*
X1654561Y1799951D01*
G01X1650328Y1818868D02*
X1650405Y1818277D01*
G01X1652296Y1803868D02*
X1652374Y1803277D01*
G01X1650405Y1813277D02*
X1650328Y1813868D01*
G01Y1808868D02*
X1650405Y1808277D01*
G01X1650328Y1798868D02*
X1650405Y1798277D01*
G01X1649374Y1818258D02*
X1649377Y1818220D01*
X1649385Y1818183D01*
X1649397Y1818149D01*
X1649415Y1818119D01*
X1649436Y1818094D01*
X1649459Y1818076D01*
X1649485Y1818065D01*
X1649513Y1818061D01*
G01X1649374Y1815108D02*
X1649377Y1815070D01*
X1649385Y1815033D01*
X1649397Y1814999D01*
X1649415Y1814969D01*
X1649436Y1814945D01*
X1649459Y1814926D01*
X1649485Y1814915D01*
X1649513Y1814911D01*
G01X1649374Y1811959D02*
X1649377Y1811920D01*
X1649385Y1811884D01*
X1649397Y1811850D01*
X1649415Y1811819D01*
X1649436Y1811795D01*
X1649459Y1811777D01*
X1649485Y1811766D01*
X1649513Y1811762D01*
G01X1649374Y1808809D02*
X1649377Y1808771D01*
X1649385Y1808734D01*
X1649397Y1808700D01*
X1649415Y1808670D01*
X1649436Y1808645D01*
X1649459Y1808627D01*
X1649485Y1808616D01*
X1649513Y1808612D01*
G01X1649374Y1805659D02*
X1649377Y1805621D01*
X1649385Y1805584D01*
X1649397Y1805550D01*
X1649415Y1805520D01*
X1649436Y1805496D01*
X1649459Y1805478D01*
X1649485Y1805466D01*
X1649513Y1805463D01*
G01X1649374Y1802510D02*
X1649377Y1802472D01*
X1649385Y1802435D01*
X1649397Y1802401D01*
X1649415Y1802371D01*
X1649436Y1802346D01*
X1649459Y1802328D01*
X1649485Y1802317D01*
X1649513Y1802313D01*
G01X1649374Y1799360D02*
X1649377Y1799322D01*
X1649385Y1799285D01*
X1649397Y1799251D01*
X1649415Y1799221D01*
X1649436Y1799197D01*
X1649459Y1799178D01*
X1649485Y1799167D01*
X1649513Y1799163D01*
G01X1649887Y1799754D02*
X1649897Y1799852D01*
X1649925Y1799924D01*
X1649964Y1799951D01*
G01X1649887Y1802903D02*
X1649897Y1803002D01*
X1649925Y1803074D01*
X1649964Y1803100D01*
G01X1649887Y1806053D02*
X1649897Y1806151D01*
X1649925Y1806223D01*
X1649964Y1806250D01*
G01X1649887Y1809203D02*
X1649897Y1809301D01*
X1649925Y1809373D01*
X1649964Y1809400D01*
G01X1649887Y1812352D02*
X1649897Y1812451D01*
X1649925Y1812523D01*
X1649964Y1812549D01*
G01X1649887Y1815502D02*
X1649897Y1815600D01*
X1649925Y1815672D01*
X1649964Y1815699D01*
G01X1649887Y1818651D02*
X1649897Y1818750D01*
X1649925Y1818822D01*
X1649964Y1818848D01*
G01X1656914Y1804262D02*
Y1803868D01*
G01X1654945Y1799262D02*
Y1798868D01*
G01Y1809262D02*
Y1808868D01*
G01Y1814262D02*
Y1813868D01*
G01Y1819262D02*
Y1818868D01*
G01X1654809Y1815108D02*
Y1815502D01*
G01Y1818258D02*
Y1818651D01*
G01Y1811959D02*
Y1812352D01*
G01Y1808809D02*
Y1809203D01*
G01Y1805659D02*
Y1806053D01*
G01Y1802510D02*
Y1802903D01*
G01Y1799360D02*
Y1799754D01*
G01X1652296Y1804262D02*
Y1803868D01*
G01X1651172D02*
Y1804262D01*
G01X1650328Y1803868D02*
Y1804262D01*
G01Y1813868D02*
Y1814262D01*
G01Y1799262D02*
Y1798868D01*
G01Y1809262D02*
Y1808868D01*
G01Y1819262D02*
Y1818868D01*
G01X1649887Y1815108D02*
Y1815502D01*
G01Y1818258D02*
Y1818651D01*
G01Y1811959D02*
Y1812352D01*
G01Y1808809D02*
Y1809203D01*
G01Y1805659D02*
Y1806053D01*
G01Y1802510D02*
Y1802903D01*
G01Y1799360D02*
Y1799754D01*
G01X1649374D02*
Y1799360D01*
G01Y1802903D02*
Y1802510D01*
G01Y1809203D02*
Y1808809D01*
G01Y1806053D02*
Y1805659D01*
G01Y1812352D02*
Y1811959D01*
G01Y1815502D02*
Y1815108D01*
G01Y1818651D02*
Y1818258D01*
G01X1649203Y1818868D02*
Y1819262D01*
G01Y1813868D02*
Y1814262D01*
G01Y1808868D02*
Y1809262D01*
G01Y1798868D02*
Y1799262D01*
G01X1648359Y1818868D02*
Y1819262D01*
G01Y1813868D02*
Y1814262D01*
G01Y1808868D02*
Y1809262D01*
G01Y1798868D02*
Y1799262D01*
G01X1648197Y1799754D02*
Y1799360D01*
G01Y1802903D02*
Y1802510D01*
G01Y1809203D02*
Y1808809D01*
G01Y1806053D02*
Y1805659D01*
G01Y1812352D02*
Y1811959D01*
G01Y1815502D02*
Y1815108D01*
G01Y1818651D02*
Y1818258D01*
G01X1652296Y1804262D02*
X1652374Y1804852D01*
G01X1650328Y1799262D02*
X1650405Y1799852D01*
G01X1650328Y1809262D02*
X1650405Y1809852D01*
G01Y1814852D02*
X1650328Y1814262D01*
G01Y1819262D02*
X1650405Y1819852D01*
G01X1649203Y1799262D02*
X1649476Y1799852D01*
G01X1651172Y1804262D02*
X1651444Y1804852D01*
G01X1649203Y1809262D02*
X1649476Y1809852D01*
G01X1649203Y1814262D02*
X1649476Y1814852D01*
G01X1649203Y1819262D02*
X1649476Y1819852D01*
G01X1654809Y1805659D02*
X1654775Y1805560D01*
X1654687Y1805489D01*
X1654561Y1805463D01*
G01X1648786Y1799852D02*
X1648359Y1799262D01*
G01X1650754Y1804852D02*
X1650328Y1804262D01*
G01X1648786Y1809852D02*
X1648359Y1809262D01*
G01X1648786Y1814852D02*
X1648359Y1814262D01*
G01X1648786Y1819852D02*
X1648359Y1819262D01*
G01X1654531Y1798277D02*
X1654670Y1798473D01*
X1654808Y1798670D01*
X1654945Y1798868D01*
G01X1656500Y1803277D02*
X1656639Y1803473D01*
X1656777Y1803670D01*
X1656914Y1803868D01*
G01X1654531Y1808277D02*
X1654670Y1808473D01*
X1654808Y1808670D01*
X1654945Y1808868D01*
G01X1654531Y1813277D02*
X1654670Y1813473D01*
X1654808Y1813670D01*
X1654945Y1813868D01*
G01X1654531Y1818277D02*
X1654670Y1818473D01*
X1654808Y1818670D01*
X1654945Y1818868D01*
G01X1656827Y1822884D02*
X1658795Y1824852D01*
G01X1665488Y1831506D02*
X1660764Y1836151D01*
G01X1660768Y1835044D02*
X1665488Y1830403D01*
G01X1660795Y1836120D02*
X1660853Y1835980D01*
X1660858Y1835741D01*
G01X1660821Y1835420D02*
X1660858Y1835743D01*
X1660852Y1835984D01*
X1660795Y1836120D01*
G01X1665488Y1829774D02*
Y1831506D01*
G01X1660764Y1827805D02*
Y1834970D01*
G01X1660822Y1835421D02*
X1660768Y1835044D01*
G01X1662079Y1827805D02*
X1665488Y1829774D01*
G01X1660823Y2083212D02*
X1660768Y2083598D01*
G01X1660764Y2083671D02*
Y2090837D01*
G01X1660795Y2082521D02*
X1660852Y2082656D01*
X1660858Y2082891D01*
X1660822Y2083220D01*
G01X1660795Y2082521D02*
X1660853Y2082661D01*
X1660858Y2082901D01*
G01X1665488Y2087136D02*
X1660764Y2082490D01*
G01X1665488Y2088239D02*
X1660768Y2083598D01*
G01X1654561Y2157431D02*
X1654689Y2157459D01*
X1654777Y2157532D01*
X1654809Y2157628D01*
G01X1654561Y2154281D02*
X1654689Y2154309D01*
X1654777Y2154382D01*
X1654809Y2154478D01*
G01X1654561Y2151132D02*
X1654689Y2151160D01*
X1654777Y2151232D01*
X1654809Y2151329D01*
G01X1654561Y2157431D02*
X1648477D01*
G01X1654631Y2155364D02*
X1648718D01*
G01X1654561Y2155069D02*
X1648477D01*
G01X1648197Y2154872D02*
X1654809D01*
G01X1648294Y2154774D02*
X1655036D01*
G01X1654809Y2154478D02*
X1648197D01*
G01X1648294Y2154380D02*
X1655036D01*
G01X1654561Y2154281D02*
X1648477D01*
G01X1654631Y2153789D02*
X1648718D01*
G01X1652326Y2153002D02*
X1658795D01*
G01X1654561Y2151919D02*
X1648477D01*
G01X1648197Y2151722D02*
X1654809D01*
G01Y2151329D02*
X1648197D01*
G01X1654561Y2151132D02*
X1648477D01*
G01X1648763Y2150642D02*
X1654571D01*
G01X1654819Y2150445D02*
X1648501D01*
G01Y2149461D02*
X1654819D01*
G01X1648763Y2149264D02*
X1654571D01*
G01X1654561Y2148770D02*
X1648477D01*
G01X1648197Y2148573D02*
X1654809D01*
G01Y2148179D02*
X1648197D01*
G01X1654561Y2147982D02*
X1648477D01*
G01X1648763Y2147492D02*
X1654571D01*
G01X1654819Y2147295D02*
X1648501D01*
G01Y2146311D02*
X1654819D01*
G01X1648763Y2146114D02*
X1654571D01*
G01X1654561Y2145620D02*
X1648477D01*
G01X1648197Y2145423D02*
X1654809D01*
G01Y2145029D02*
X1648197D01*
G01X1654561Y2144833D02*
X1648477D01*
G01X1648763Y2144343D02*
X1654571D01*
G01X1654819Y2144146D02*
X1648501D01*
G01Y2143162D02*
X1654819D01*
G01X1648763Y2142965D02*
X1654571D01*
G01X1654561Y2142470D02*
X1648477D01*
G01X1648197Y2142274D02*
X1654809D01*
G01Y2141880D02*
X1648197D01*
G01X1654561Y2141683D02*
X1648477D01*
G01X1648763Y2141193D02*
X1654571D01*
G01X1654819Y2140996D02*
X1648501D01*
G01Y2140012D02*
X1654819D01*
G01X1648763Y2139815D02*
X1654571D01*
G01X1654561Y2139321D02*
X1648477D01*
G01X1648197Y2139124D02*
X1654809D01*
G01Y2138730D02*
X1648197D01*
G01X1654561Y2138533D02*
X1648477D01*
G01X1648763Y2138043D02*
X1654571D01*
G01X1654819Y2137847D02*
X1648501D01*
G01Y2136862D02*
X1654819D01*
G01X1648763Y2136665D02*
X1654571D01*
G01X1654561Y2136171D02*
X1648477D01*
G01X1648197Y2135974D02*
X1654809D01*
G01Y2135581D02*
X1648197D01*
G01X1654561Y2135384D02*
X1648477D01*
G01X1648763Y2134894D02*
X1654571D01*
G01X1654819Y2134697D02*
X1648501D01*
G01Y2133713D02*
X1654819D01*
G01X1648763Y2133516D02*
X1654571D01*
G01X1654561Y2133022D02*
X1648477D01*
G01X1648197Y2132825D02*
X1654809D01*
G01Y2132431D02*
X1648197D01*
G01X1654561Y2132234D02*
X1648477D01*
G01X1658795Y2131151D02*
X1652326D01*
G01X1654631Y2130364D02*
X1648718D01*
G01X1654561Y2129872D02*
X1648477D01*
G01X1648294Y2129774D02*
X1655036D01*
G01X1648197Y2129675D02*
X1654809D01*
G01X1648294Y2129380D02*
X1655036D01*
G01X1654809Y2129281D02*
X1648197D01*
G01X1654561Y2129085D02*
X1648477D01*
G01X1654631Y2128789D02*
X1648718D01*
G01X1654561Y2126722D02*
X1648477D01*
G01X1648197Y2126525D02*
X1654809D01*
G01Y2126132D02*
X1648197D01*
G01X1654561Y2125935D02*
X1648477D01*
G01X1654531Y2125364D02*
X1648786D01*
G01X1648359Y2124774D02*
X1654945D01*
G01X1648359Y2124380D02*
X1654945D01*
G01X1654531Y2123789D02*
X1648786D01*
G01X1654561Y2123573D02*
X1648477D01*
G01X1648197Y2123376D02*
X1654809D01*
G01Y2122982D02*
X1648197D01*
G01X1654561Y2122785D02*
X1648477D01*
G01X1649513Y2155069D02*
X1649486Y2155065D01*
X1649460Y2155054D01*
X1649436Y2155036D01*
X1649415Y2155011D01*
X1649397Y2154981D01*
X1649385Y2154948D01*
X1649377Y2154911D01*
X1649374Y2154872D01*
G01X1649513Y2151919D02*
X1649486Y2151915D01*
X1649460Y2151904D01*
X1649436Y2151886D01*
X1649415Y2151862D01*
X1649397Y2151832D01*
X1649385Y2151798D01*
X1649377Y2151761D01*
X1649374Y2151722D01*
G01X1649513Y2148770D02*
X1649486Y2148766D01*
X1649460Y2148755D01*
X1649436Y2148737D01*
X1649415Y2148712D01*
X1649397Y2148682D01*
X1649385Y2148648D01*
X1649377Y2148612D01*
X1649374Y2148573D01*
G01X1649513Y2145620D02*
X1649486Y2145616D01*
X1649460Y2145605D01*
X1649436Y2145587D01*
X1649415Y2145562D01*
X1649397Y2145533D01*
X1649385Y2145499D01*
X1649377Y2145462D01*
X1649374Y2145423D01*
G01X1649513Y2142470D02*
X1649486Y2142467D01*
X1649460Y2142456D01*
X1649436Y2142437D01*
X1649415Y2142413D01*
X1649397Y2142383D01*
X1649385Y2142349D01*
X1649377Y2142312D01*
X1649374Y2142274D01*
G01X1649513Y2139321D02*
X1649486Y2139317D01*
X1649460Y2139306D01*
X1649436Y2139288D01*
X1649415Y2139263D01*
X1649397Y2139233D01*
X1649385Y2139200D01*
X1649377Y2139163D01*
X1649374Y2139124D01*
G01X1649513Y2136171D02*
X1649486Y2136167D01*
X1649460Y2136156D01*
X1649436Y2136138D01*
X1649415Y2136114D01*
X1649397Y2136084D01*
X1649385Y2136050D01*
X1649377Y2136013D01*
X1649374Y2135974D01*
G01X1649513Y2133022D02*
X1649486Y2133018D01*
X1649460Y2133007D01*
X1649436Y2132989D01*
X1649415Y2132964D01*
X1649397Y2132934D01*
X1649385Y2132900D01*
X1649377Y2132864D01*
X1649374Y2132825D01*
G01X1649513Y2129872D02*
X1649486Y2129868D01*
X1649460Y2129857D01*
X1649436Y2129839D01*
X1649415Y2129814D01*
X1649397Y2129785D01*
X1649385Y2129751D01*
X1649377Y2129714D01*
X1649374Y2129675D01*
G01X1649513Y2126722D02*
X1649486Y2126719D01*
X1649460Y2126707D01*
X1649436Y2126689D01*
X1649415Y2126665D01*
X1649397Y2126635D01*
X1649385Y2126601D01*
X1649377Y2126564D01*
X1649374Y2126525D01*
G01X1649513Y2123573D02*
X1649486Y2123569D01*
X1649460Y2123558D01*
X1649436Y2123540D01*
X1649415Y2123515D01*
X1649397Y2123485D01*
X1649385Y2123452D01*
X1649377Y2123415D01*
X1649374Y2123376D01*
G01X1649513Y2120423D02*
X1649486Y2120419D01*
X1649460Y2120408D01*
X1649436Y2120390D01*
X1649415Y2120365D01*
X1649397Y2120336D01*
X1649385Y2120302D01*
X1649377Y2120265D01*
X1649374Y2120226D01*
G01X1649513Y2117274D02*
X1649486Y2117270D01*
X1649460Y2117259D01*
X1649436Y2117241D01*
X1649415Y2117216D01*
X1649397Y2117186D01*
X1649385Y2117152D01*
X1649377Y2117116D01*
X1649374Y2117077D01*
G01X1649513Y2114124D02*
X1649486Y2114120D01*
X1649460Y2114109D01*
X1649436Y2114091D01*
X1649415Y2114066D01*
X1649397Y2114037D01*
X1649385Y2114003D01*
X1649377Y2113966D01*
X1649374Y2113927D01*
G01X1649513Y2110974D02*
X1649486Y2110971D01*
X1649460Y2110959D01*
X1649436Y2110941D01*
X1649415Y2110917D01*
X1649397Y2110887D01*
X1649385Y2110853D01*
X1649377Y2110816D01*
X1649374Y2110777D01*
G01X1649513Y2107825D02*
X1649486Y2107821D01*
X1649460Y2107810D01*
X1649436Y2107792D01*
X1649415Y2107767D01*
X1649397Y2107737D01*
X1649385Y2107704D01*
X1649377Y2107667D01*
X1649374Y2107628D01*
G01X1649513Y2104675D02*
X1649486Y2104671D01*
X1649460Y2104660D01*
X1649436Y2104642D01*
X1649415Y2104617D01*
X1649397Y2104588D01*
X1649385Y2104554D01*
X1649377Y2104517D01*
X1649374Y2104478D01*
G01X1649513Y2101525D02*
X1649486Y2101522D01*
X1649460Y2101511D01*
X1649436Y2101493D01*
X1649415Y2101468D01*
X1649397Y2101438D01*
X1649385Y2101404D01*
X1649377Y2101368D01*
X1649374Y2101329D01*
G01X1654571Y2149264D02*
X1654698Y2149291D01*
X1654787Y2149364D01*
X1654819Y2149461D01*
G01X1654571Y2146114D02*
X1654698Y2146142D01*
X1654787Y2146214D01*
X1654819Y2146311D01*
G01X1654571Y2142965D02*
X1654698Y2142992D01*
X1654787Y2143065D01*
X1654819Y2143162D01*
G01X1654571Y2139815D02*
X1654698Y2139842D01*
X1654787Y2139915D01*
X1654819Y2140012D01*
G01X1654571Y2136665D02*
X1654698Y2136693D01*
X1654787Y2136766D01*
X1654819Y2136862D01*
G01X1654571Y2133516D02*
X1654698Y2133543D01*
X1654787Y2133616D01*
X1654819Y2133713D01*
G01X1654561Y2147982D02*
X1654689Y2148010D01*
X1654777Y2148083D01*
X1654809Y2148179D01*
G01X1654561Y2144833D02*
X1654689Y2144860D01*
X1654777Y2144933D01*
X1654809Y2145029D01*
G01X1654561Y2141683D02*
X1654689Y2141711D01*
X1654777Y2141784D01*
X1654809Y2141880D01*
G01X1654561Y2138533D02*
X1654689Y2138561D01*
X1654777Y2138634D01*
X1654809Y2138730D01*
G01X1654561Y2135384D02*
X1654689Y2135412D01*
X1654777Y2135484D01*
X1654809Y2135581D01*
G01X1654561Y2132234D02*
X1654689Y2132262D01*
X1654777Y2132335D01*
X1654809Y2132431D01*
G01X1654561Y2129085D02*
X1654689Y2129112D01*
X1654777Y2129185D01*
X1654809Y2129281D01*
G01X1654561Y2125935D02*
X1654689Y2125963D01*
X1654777Y2126036D01*
X1654809Y2126132D01*
G01X1654561Y2122785D02*
X1654689Y2122813D01*
X1654777Y2122886D01*
X1654809Y2122982D01*
G01X1654561Y2119636D02*
X1654689Y2119663D01*
X1654777Y2119736D01*
X1654809Y2119833D01*
G01X1654561Y2116486D02*
X1654689Y2116514D01*
X1654777Y2116587D01*
X1654809Y2116683D01*
G01X1654561Y2113337D02*
X1654689Y2113364D01*
X1654777Y2113437D01*
X1654809Y2113533D01*
G01X1654561Y2110187D02*
X1654689Y2110215D01*
X1654777Y2110288D01*
X1654809Y2110384D01*
G01X1654561Y2107037D02*
X1654689Y2107065D01*
X1654777Y2107138D01*
X1654809Y2107234D01*
G01X1654561Y2103888D02*
X1654689Y2103915D01*
X1654777Y2103988D01*
X1654809Y2104085D01*
G01X1654561Y2100738D02*
X1654689Y2100766D01*
X1654777Y2100839D01*
X1654809Y2100935D01*
G01X1649590Y2149264D02*
X1649562Y2149268D01*
X1649534Y2149279D01*
X1649509Y2149297D01*
X1649486Y2149322D01*
X1649468Y2149351D01*
X1649454Y2149385D01*
X1649446Y2149422D01*
X1649443Y2149461D01*
G01X1649590Y2146114D02*
X1649562Y2146118D01*
X1649534Y2146129D01*
X1649509Y2146147D01*
X1649486Y2146172D01*
X1649468Y2146202D01*
X1649454Y2146235D01*
X1649446Y2146272D01*
X1649443Y2146311D01*
G01X1649590Y2142965D02*
X1649562Y2142968D01*
X1649534Y2142980D01*
X1649509Y2142998D01*
X1649486Y2143022D01*
X1649468Y2143052D01*
X1649454Y2143086D01*
X1649446Y2143123D01*
X1649443Y2143162D01*
G01X1649590Y2139815D02*
X1649562Y2139819D01*
X1649534Y2139830D01*
X1649509Y2139848D01*
X1649486Y2139873D01*
X1649468Y2139902D01*
X1649454Y2139936D01*
X1649446Y2139973D01*
X1649443Y2140012D01*
G01X1649590Y2136665D02*
X1649562Y2136669D01*
X1649534Y2136680D01*
X1649509Y2136698D01*
X1649486Y2136723D01*
X1649468Y2136753D01*
X1649454Y2136787D01*
X1649446Y2136823D01*
X1649443Y2136862D01*
G01X1649590Y2133516D02*
X1649562Y2133520D01*
X1649534Y2133531D01*
X1649509Y2133549D01*
X1649486Y2133573D01*
X1649468Y2133603D01*
X1649454Y2133637D01*
X1649446Y2133674D01*
X1649443Y2133713D01*
G01X1654561Y2120423D02*
X1648477D01*
G01X1654531Y2120364D02*
X1648786D01*
G01X1648197Y2120226D02*
X1654809D01*
G01Y2119833D02*
X1648197D01*
G01X1648359Y2119774D02*
X1654945D01*
G01X1654561Y2119636D02*
X1648477D01*
G01X1648359Y2119380D02*
X1654945D01*
G01X1654531Y2118789D02*
X1648786D01*
G01X1654561Y2117274D02*
X1648477D01*
G01X1648197Y2117077D02*
X1654809D01*
G01Y2116683D02*
X1648197D01*
G01X1654561Y2116486D02*
X1648477D01*
G01X1654531Y2115364D02*
X1648786D01*
G01X1648359Y2114774D02*
X1654945D01*
G01X1648359Y2114380D02*
X1654945D01*
G01X1654561Y2114124D02*
X1648477D01*
G01X1648197Y2113927D02*
X1654809D01*
G01X1654531Y2113789D02*
X1648786D01*
G01X1654809Y2113533D02*
X1648197D01*
G01X1654561Y2113337D02*
X1648477D01*
G01X1654561Y2110974D02*
X1648477D01*
G01X1648197Y2110777D02*
X1654809D01*
G01Y2110384D02*
X1648197D01*
G01X1654531Y2110364D02*
X1648786D01*
G01X1654561Y2110187D02*
X1648477D01*
G01X1648359Y2109774D02*
X1654945D01*
G01X1648359Y2109380D02*
X1654945D01*
G01X1654531Y2108789D02*
X1648786D01*
G01X1654561Y2107825D02*
X1648477D01*
G01X1648197Y2107628D02*
X1654809D01*
G01Y2107234D02*
X1648197D01*
G01X1654561Y2107037D02*
X1648477D01*
G01X1654531Y2105364D02*
X1648786D01*
G01X1648359Y2104774D02*
X1654945D01*
G01X1654561Y2104675D02*
X1648477D01*
G01X1648197Y2104478D02*
X1654809D01*
G01X1648359Y2104380D02*
X1654945D01*
G01X1654809Y2104085D02*
X1648197D01*
G01X1654561Y2103888D02*
X1648477D01*
G01X1654531Y2103789D02*
X1648786D01*
G01X1654561Y2101525D02*
X1648477D01*
G01X1648197Y2101329D02*
X1654809D01*
G01Y2100935D02*
X1648197D01*
G01X1654561Y2100738D02*
X1648477D01*
G01X1654531Y2100364D02*
X1648786D01*
G01X1648359Y2099774D02*
X1654945D01*
G01X1648359Y2099380D02*
X1654945D01*
G01X1654531Y2098789D02*
X1648786D01*
G01X1662079Y2090837D02*
X1658795D01*
G01X1649964Y2157431D02*
X1649925Y2157457D01*
X1649897Y2157529D01*
X1649887Y2157628D01*
G01X1649964Y2154281D02*
X1649925Y2154308D01*
X1649897Y2154380D01*
X1649887Y2154478D01*
G01X1649964Y2151132D02*
X1649925Y2151158D01*
X1649897Y2151230D01*
X1649887Y2151329D01*
G01X1650627Y2149264D02*
X1650621Y2149268D01*
X1650615Y2149279D01*
X1650609Y2149297D01*
X1650604Y2149322D01*
X1650600Y2149351D01*
X1650597Y2149385D01*
X1650595Y2149422D01*
Y2149461D01*
G01X1650627Y2146114D02*
X1650621Y2146118D01*
X1650615Y2146129D01*
X1650609Y2146147D01*
X1650604Y2146172D01*
X1650600Y2146202D01*
X1650597Y2146235D01*
X1650595Y2146272D01*
Y2146311D01*
G01X1650627Y2142965D02*
X1650621Y2142968D01*
X1650615Y2142980D01*
X1650609Y2142998D01*
X1650604Y2143022D01*
X1650600Y2143052D01*
X1650597Y2143086D01*
X1650595Y2143123D01*
Y2143162D01*
G01X1650627Y2139815D02*
X1650621Y2139819D01*
X1650615Y2139830D01*
X1650609Y2139848D01*
X1650604Y2139873D01*
X1650600Y2139902D01*
X1650597Y2139936D01*
X1650595Y2139973D01*
Y2140012D01*
G01X1650627Y2136665D02*
X1650621Y2136669D01*
X1650615Y2136680D01*
X1650609Y2136698D01*
X1650604Y2136723D01*
X1650600Y2136753D01*
X1650597Y2136787D01*
X1650595Y2136823D01*
Y2136862D01*
G01X1650627Y2133516D02*
X1650621Y2133520D01*
X1650615Y2133531D01*
X1650609Y2133549D01*
X1650604Y2133573D01*
X1650600Y2133603D01*
X1650597Y2133637D01*
X1650595Y2133674D01*
Y2133713D01*
G01X1649964Y2147982D02*
X1649925Y2148009D01*
X1649897Y2148081D01*
X1649887Y2148179D01*
G01X1649964Y2144833D02*
X1649925Y2144859D01*
X1649897Y2144931D01*
X1649887Y2145029D01*
G01X1649964Y2141683D02*
X1649925Y2141709D01*
X1649897Y2141781D01*
X1649887Y2141880D01*
G01X1649964Y2138533D02*
X1649925Y2138560D01*
X1649897Y2138632D01*
X1649887Y2138730D01*
G01X1649964Y2135384D02*
X1649925Y2135410D01*
X1649897Y2135482D01*
X1649887Y2135581D01*
G01X1649964Y2132234D02*
X1649925Y2132261D01*
X1649897Y2132333D01*
X1649887Y2132431D01*
G01X1649964Y2129085D02*
X1649925Y2129111D01*
X1649897Y2129183D01*
X1649887Y2129281D01*
G01X1649964Y2125935D02*
X1649925Y2125961D01*
X1649897Y2126033D01*
X1649887Y2126132D01*
G01X1649964Y2122785D02*
X1649925Y2122812D01*
X1649897Y2122884D01*
X1649887Y2122982D01*
G01X1649964Y2119636D02*
X1649925Y2119662D01*
X1649897Y2119734D01*
X1649887Y2119833D01*
G01X1649964Y2116486D02*
X1649925Y2116513D01*
X1649897Y2116585D01*
X1649887Y2116683D01*
G01X1649964Y2113337D02*
X1649925Y2113363D01*
X1649897Y2113435D01*
X1649887Y2113533D01*
G01X1649964Y2110187D02*
X1649925Y2110213D01*
X1649897Y2110285D01*
X1649887Y2110384D01*
G01X1649964Y2107037D02*
X1649925Y2107064D01*
X1649897Y2107136D01*
X1649887Y2107234D01*
G01X1649964Y2103888D02*
X1649925Y2103914D01*
X1649897Y2103986D01*
X1649887Y2104085D01*
G01X1649964Y2100738D02*
X1649925Y2100765D01*
X1649897Y2100837D01*
X1649887Y2100935D01*
G01X1656827Y2132313D02*
X1658795Y2130344D01*
G01Y2093789D02*
X1656827Y2095758D01*
G01X1655036Y2154774D02*
X1654902Y2154971D01*
X1654767Y2155168D01*
X1654631Y2155364D01*
G01X1648718Y2153789D02*
X1648294Y2154380D01*
G01X1648718Y2128789D02*
X1648294Y2129380D01*
G01X1648786Y2123789D02*
X1648359Y2124380D01*
G01X1648786Y2118789D02*
X1648359Y2119380D01*
G01X1655036Y2129774D02*
X1654902Y2129971D01*
X1654767Y2130168D01*
X1654631Y2130364D01*
G01X1654945Y2124774D02*
X1654808Y2124971D01*
X1654670Y2125168D01*
X1654531Y2125364D01*
G01X1654945Y2119774D02*
X1654808Y2119971D01*
X1654670Y2120168D01*
X1654531Y2120364D01*
G01X1654945Y2114774D02*
X1654808Y2114971D01*
X1654670Y2115168D01*
X1654531Y2115364D01*
G01X1654945Y2109774D02*
X1654808Y2109971D01*
X1654670Y2110168D01*
X1654531Y2110364D01*
G01X1654945Y2104774D02*
X1654808Y2104971D01*
X1654670Y2105168D01*
X1654531Y2105364D01*
G01X1654945Y2099774D02*
X1654808Y2099971D01*
X1654670Y2100168D01*
X1654531Y2100364D01*
G01X1648786Y2113789D02*
X1648359Y2114380D01*
G01X1648786Y2108789D02*
X1648359Y2109380D01*
G01X1648786Y2103789D02*
X1648359Y2104380D01*
G01X1648786Y2098789D02*
X1648359Y2099380D01*
G01X1649476Y2153789D02*
X1649203Y2154380D01*
G01X1649476Y2128789D02*
X1649203Y2129380D01*
G01X1649476Y2123789D02*
X1649203Y2124380D01*
G01X1649476Y2118789D02*
X1649203Y2119380D01*
G01X1649476Y2113789D02*
X1649203Y2114380D01*
G01X1649476Y2108789D02*
X1649203Y2109380D01*
G01X1649476Y2103789D02*
X1649203Y2104380D01*
G01X1649476Y2098789D02*
X1649203Y2099380D01*
G01X1654809Y2154872D02*
X1654777Y2154969D01*
X1654689Y2155041D01*
X1654561Y2155069D01*
G01X1654809Y2151722D02*
X1654777Y2151819D01*
X1654689Y2151892D01*
X1654561Y2151919D01*
G01X1654809Y2148573D02*
X1654777Y2148670D01*
X1654689Y2148742D01*
X1654561Y2148770D01*
G01X1654809Y2145423D02*
X1654777Y2145520D01*
X1654689Y2145592D01*
X1654561Y2145620D01*
G01X1654809Y2142274D02*
X1654777Y2142371D01*
X1654689Y2142443D01*
X1654561Y2142470D01*
G01X1654809Y2139124D02*
X1654777Y2139221D01*
X1654689Y2139293D01*
X1654561Y2139321D01*
G01X1654809Y2135974D02*
X1654777Y2136071D01*
X1654689Y2136144D01*
X1654561Y2136171D01*
G01X1654809Y2132825D02*
X1654777Y2132922D01*
X1654689Y2132994D01*
X1654561Y2133022D01*
G01X1654809Y2129675D02*
X1654777Y2129772D01*
X1654689Y2129844D01*
X1654561Y2129872D01*
G01X1654809Y2126525D02*
X1654777Y2126623D01*
X1654689Y2126695D01*
X1654561Y2126722D01*
G01X1654809Y2123376D02*
X1654777Y2123473D01*
X1654689Y2123545D01*
X1654561Y2123573D01*
G01X1654809Y2120226D02*
X1654777Y2120323D01*
X1654689Y2120395D01*
X1654561Y2120423D01*
G01X1654809Y2117077D02*
X1654777Y2117174D01*
X1654689Y2117246D01*
X1654561Y2117274D01*
G01X1654809Y2113927D02*
X1654777Y2114024D01*
X1654689Y2114096D01*
X1654561Y2114124D01*
G01X1654809Y2110777D02*
X1654777Y2110874D01*
X1654689Y2110947D01*
X1654561Y2110974D01*
G01X1654809Y2107628D02*
X1654777Y2107725D01*
X1654689Y2107797D01*
X1654561Y2107825D01*
G01X1654809Y2104478D02*
X1654777Y2104575D01*
X1654689Y2104647D01*
X1654561Y2104675D01*
G01X1654809Y2101329D02*
X1654777Y2101426D01*
X1654689Y2101498D01*
X1654561Y2101525D01*
G01X1654819Y2150445D02*
X1654785Y2150544D01*
X1654697Y2150615D01*
X1654571Y2150642D01*
G01X1654819Y2147295D02*
X1654785Y2147394D01*
X1654697Y2147465D01*
X1654571Y2147492D01*
G01X1654819Y2144146D02*
X1654785Y2144245D01*
X1654697Y2144316D01*
X1654571Y2144343D01*
G01X1654819Y2140996D02*
X1654785Y2141095D01*
X1654697Y2141166D01*
X1654571Y2141193D01*
G01X1654819Y2137847D02*
X1654785Y2137946D01*
X1654697Y2138016D01*
X1654571Y2138043D01*
G01X1654819Y2134697D02*
X1654785Y2134796D01*
X1654697Y2134867D01*
X1654571Y2134894D01*
G01X1650328Y2154380D02*
X1650405Y2153789D01*
G01X1650328Y2129380D02*
X1650405Y2128789D01*
G01X1650328Y2124380D02*
X1650405Y2123789D01*
G01X1650328Y2119380D02*
X1650405Y2118789D01*
G01X1650328Y2114380D02*
X1650405Y2113789D01*
G01X1650328Y2109380D02*
X1650405Y2108789D01*
G01X1650328Y2104380D02*
X1650405Y2103789D01*
G01X1650328Y2099380D02*
X1650405Y2098789D01*
G01X1649374Y2157628D02*
X1649377Y2157590D01*
X1649385Y2157553D01*
X1649397Y2157519D01*
X1649415Y2157489D01*
X1649436Y2157464D01*
X1649459Y2157446D01*
X1649485Y2157435D01*
X1649513Y2157431D01*
G01X1649374Y2154478D02*
X1649377Y2154440D01*
X1649385Y2154403D01*
X1649397Y2154369D01*
X1649415Y2154339D01*
X1649436Y2154315D01*
X1649459Y2154297D01*
X1649485Y2154285D01*
X1649513Y2154281D01*
G01X1649374Y2151329D02*
X1649377Y2151290D01*
X1649385Y2151254D01*
X1649397Y2151220D01*
X1649415Y2151189D01*
X1649436Y2151165D01*
X1649459Y2151147D01*
X1649485Y2151136D01*
X1649513Y2151132D01*
G01X1649374Y2148179D02*
X1649377Y2148141D01*
X1649385Y2148104D01*
X1649397Y2148070D01*
X1649415Y2148040D01*
X1649436Y2148015D01*
X1649459Y2147997D01*
X1649485Y2147986D01*
X1649513Y2147982D01*
G01X1649374Y2145029D02*
X1649377Y2144991D01*
X1649385Y2144954D01*
X1649397Y2144921D01*
X1649415Y2144890D01*
X1649436Y2144866D01*
X1649459Y2144848D01*
X1649485Y2144836D01*
X1649513Y2144833D01*
G01X1649374Y2141880D02*
X1649377Y2141842D01*
X1649385Y2141805D01*
X1649397Y2141771D01*
X1649415Y2141741D01*
X1649436Y2141716D01*
X1649459Y2141698D01*
X1649485Y2141687D01*
X1649513Y2141683D01*
G01X1649374Y2138730D02*
X1649377Y2138692D01*
X1649385Y2138655D01*
X1649397Y2138621D01*
X1649415Y2138591D01*
X1649436Y2138567D01*
X1649459Y2138548D01*
X1649485Y2138537D01*
X1649513Y2138533D01*
G01X1649374Y2135581D02*
X1649377Y2135542D01*
X1649385Y2135506D01*
X1649397Y2135472D01*
X1649415Y2135441D01*
X1649436Y2135417D01*
X1649459Y2135399D01*
X1649485Y2135388D01*
X1649513Y2135384D01*
G01X1649374Y2132431D02*
X1649377Y2132393D01*
X1649385Y2132356D01*
X1649397Y2132322D01*
X1649415Y2132292D01*
X1649436Y2132267D01*
X1649459Y2132249D01*
X1649485Y2132238D01*
X1649513Y2132234D01*
G01X1649374Y2129281D02*
X1649377Y2129243D01*
X1649385Y2129206D01*
X1649397Y2129172D01*
X1649415Y2129142D01*
X1649436Y2129118D01*
X1649459Y2129100D01*
X1649485Y2129088D01*
X1649513Y2129085D01*
G01X1649374Y2126132D02*
X1649377Y2126094D01*
X1649385Y2126057D01*
X1649397Y2126023D01*
X1649415Y2125993D01*
X1649436Y2125968D01*
X1649459Y2125950D01*
X1649485Y2125939D01*
X1649513Y2125935D01*
G01X1649374Y2122982D02*
X1649377Y2122944D01*
X1649385Y2122907D01*
X1649397Y2122873D01*
X1649415Y2122843D01*
X1649436Y2122819D01*
X1649459Y2122800D01*
X1649485Y2122789D01*
X1649513Y2122785D01*
G01X1649374Y2119833D02*
X1649377Y2119794D01*
X1649385Y2119758D01*
X1649397Y2119724D01*
X1649415Y2119693D01*
X1649436Y2119669D01*
X1649459Y2119651D01*
X1649485Y2119640D01*
X1649513Y2119636D01*
G01X1649374Y2116683D02*
X1649377Y2116645D01*
X1649385Y2116608D01*
X1649397Y2116574D01*
X1649415Y2116544D01*
X1649436Y2116519D01*
X1649459Y2116501D01*
X1649485Y2116490D01*
X1649513Y2116486D01*
G01X1649374Y2113533D02*
X1649377Y2113495D01*
X1649385Y2113458D01*
X1649397Y2113424D01*
X1649415Y2113394D01*
X1649436Y2113370D01*
X1649459Y2113352D01*
X1649485Y2113340D01*
X1649513Y2113337D01*
G01X1649374Y2110384D02*
X1649377Y2110346D01*
X1649385Y2110309D01*
X1649397Y2110275D01*
X1649415Y2110245D01*
X1649436Y2110220D01*
X1649459Y2110202D01*
X1649485Y2110191D01*
X1649513Y2110187D01*
G01X1649374Y2107234D02*
X1649377Y2107196D01*
X1649385Y2107159D01*
X1649397Y2107125D01*
X1649415Y2107095D01*
X1649436Y2107071D01*
X1649459Y2107052D01*
X1649485Y2107041D01*
X1649513Y2107037D01*
G01X1649374Y2104085D02*
X1649377Y2104046D01*
X1649385Y2104010D01*
X1649397Y2103976D01*
X1649415Y2103945D01*
X1649436Y2103921D01*
X1649459Y2103903D01*
X1649485Y2103892D01*
X1649513Y2103888D01*
G01X1649374Y2100935D02*
X1649377Y2100897D01*
X1649385Y2100860D01*
X1649397Y2100826D01*
X1649415Y2100796D01*
X1649436Y2100771D01*
X1649459Y2100753D01*
X1649485Y2100742D01*
X1649513Y2100738D01*
G01X1650595Y2134697D02*
Y2134735D01*
X1650597Y2134772D01*
X1650600Y2134806D01*
X1650604Y2134836D01*
X1650609Y2134861D01*
X1650615Y2134879D01*
X1650621Y2134890D01*
X1650627Y2134894D01*
G01X1650595Y2137847D02*
Y2137885D01*
X1650597Y2137922D01*
X1650600Y2137955D01*
X1650604Y2137986D01*
X1650609Y2138010D01*
X1650615Y2138028D01*
X1650621Y2138040D01*
X1650627Y2138043D01*
G01X1650595Y2140996D02*
Y2141034D01*
X1650597Y2141071D01*
X1650600Y2141105D01*
X1650604Y2141135D01*
X1650609Y2141160D01*
X1650615Y2141178D01*
X1650621Y2141189D01*
X1650627Y2141193D01*
G01X1650595Y2144146D02*
Y2144184D01*
X1650597Y2144221D01*
X1650600Y2144255D01*
X1650604Y2144285D01*
X1650609Y2144309D01*
X1650615Y2144327D01*
X1650621Y2144339D01*
X1650627Y2144343D01*
G01X1650595Y2147295D02*
Y2147334D01*
X1650597Y2147370D01*
X1650600Y2147404D01*
X1650604Y2147435D01*
X1650609Y2147459D01*
X1650615Y2147477D01*
X1650621Y2147488D01*
X1650627Y2147492D01*
G01X1650595Y2150445D02*
Y2150483D01*
X1650597Y2150520D01*
X1650600Y2150554D01*
X1650604Y2150584D01*
X1650609Y2150609D01*
X1650615Y2150627D01*
X1650621Y2150638D01*
X1650627Y2150642D01*
G01X1658795Y2090837D02*
Y2233317D01*
G01X1657784Y2131356D02*
Y2125974D01*
G01Y2158277D02*
Y2152798D01*
G01X1657673Y2228789D02*
Y2095364D01*
G01X1657614Y2131151D02*
Y2153002D01*
G01Y2125974D02*
Y2094970D01*
G01X1656827Y2095758D02*
Y2228396D01*
G01X1655036Y2129774D02*
Y2129380D01*
G01Y2154774D02*
Y2154380D01*
G01X1654945Y2099774D02*
Y2099380D01*
G01Y2104774D02*
Y2104380D01*
G01Y2109774D02*
Y2109380D01*
G01Y2114774D02*
Y2114380D01*
G01Y2119774D02*
Y2119380D01*
G01Y2124774D02*
Y2124380D01*
G01X1654819Y2134697D02*
Y2133713D01*
G01Y2137847D02*
Y2136862D01*
G01Y2140996D02*
Y2140012D01*
G01Y2144146D02*
Y2143162D01*
G01Y2147295D02*
Y2146311D01*
G01Y2150445D02*
Y2149461D01*
G01X1654809Y2154478D02*
Y2154872D01*
G01Y2151329D02*
Y2151722D01*
G01Y2148179D02*
Y2148573D01*
G01Y2145029D02*
Y2145423D01*
G01Y2141880D02*
Y2142274D01*
G01Y2138730D02*
Y2139124D01*
G01Y2135581D02*
Y2135974D01*
G01Y2129281D02*
Y2129675D01*
G01Y2132431D02*
Y2132825D01*
G01Y2126132D02*
Y2126525D01*
G01Y2122982D02*
Y2123376D01*
G01Y2119833D02*
Y2120226D01*
G01Y2116683D02*
Y2117077D01*
G01Y2113533D02*
Y2113927D01*
G01Y2110384D02*
Y2110777D01*
G01Y2107234D02*
Y2107628D01*
G01Y2100935D02*
Y2101329D01*
G01Y2104085D02*
Y2104478D01*
G01X1652326Y2132333D02*
Y2131151D01*
G01Y2153002D02*
Y2151821D01*
G01X1650595Y2149461D02*
Y2150445D01*
G01Y2143162D02*
Y2144146D01*
G01Y2146311D02*
Y2147295D01*
G01Y2140012D02*
Y2140996D01*
G01Y2133713D02*
Y2134697D01*
G01Y2136862D02*
Y2137847D01*
G01X1650328Y2099774D02*
Y2099380D01*
G01Y2104774D02*
Y2104380D01*
G01Y2109774D02*
Y2109380D01*
G01Y2114774D02*
Y2114380D01*
G01Y2119774D02*
Y2119380D01*
G01Y2124774D02*
Y2124380D01*
G01Y2129774D02*
Y2129380D01*
G01Y2154774D02*
Y2154380D01*
G01X1649887Y2154478D02*
Y2154872D01*
G01Y2151329D02*
Y2151722D01*
G01Y2148179D02*
Y2148573D01*
G01Y2145029D02*
Y2145423D01*
G01Y2141880D02*
Y2142274D01*
G01Y2138730D02*
Y2139124D01*
G01Y2135581D02*
Y2135974D01*
G01Y2129281D02*
Y2129675D01*
G01Y2132431D02*
Y2132825D01*
G01Y2126132D02*
Y2126525D01*
G01Y2122982D02*
Y2123376D01*
G01Y2119833D02*
Y2120226D01*
G01Y2116683D02*
Y2117077D01*
G01Y2113533D02*
Y2113927D01*
G01Y2110384D02*
Y2110777D01*
G01Y2107234D02*
Y2107628D01*
G01Y2100935D02*
Y2101329D01*
G01Y2104085D02*
Y2104478D01*
G01X1649443Y2149461D02*
Y2150445D01*
G01Y2143162D02*
Y2144146D01*
G01Y2146311D02*
Y2147295D01*
G01Y2140012D02*
Y2140996D01*
G01Y2133713D02*
Y2134697D01*
G01Y2136862D02*
Y2137847D01*
G01X1649374Y2101329D02*
Y2100935D01*
G01Y2104478D02*
Y2104085D01*
G01Y2107628D02*
Y2107234D01*
G01Y2113927D02*
Y2113533D01*
G01Y2110777D02*
Y2110384D01*
G01Y2117077D02*
Y2116683D01*
G01Y2123376D02*
Y2122982D01*
G01Y2120226D02*
Y2119833D01*
G01Y2126525D02*
Y2126132D01*
G01Y2129675D02*
Y2129281D01*
G01Y2132825D02*
Y2132431D01*
G01Y2135974D02*
Y2135581D01*
G01Y2142274D02*
Y2141880D01*
G01Y2139124D02*
Y2138730D01*
G01Y2145423D02*
Y2145029D01*
G01Y2151722D02*
Y2151329D01*
G01Y2148573D02*
Y2148179D01*
G01Y2154872D02*
Y2154478D01*
G01X1649203Y2154380D02*
Y2154774D01*
G01Y2129380D02*
Y2129774D01*
G01Y2124380D02*
Y2124774D01*
G01Y2119380D02*
Y2119774D01*
G01Y2114380D02*
Y2114774D01*
G01Y2109380D02*
Y2109774D01*
G01Y2104380D02*
Y2104774D01*
G01Y2099380D02*
Y2099774D01*
G01X1648501Y2149461D02*
Y2150445D01*
G01Y2143162D02*
Y2144146D01*
G01Y2146311D02*
Y2147295D01*
G01Y2140012D02*
Y2140996D01*
G01Y2133713D02*
Y2134697D01*
G01Y2136862D02*
Y2137847D01*
G01X1648359Y2124380D02*
Y2124774D01*
G01Y2119380D02*
Y2119774D01*
G01Y2114380D02*
Y2114774D01*
G01Y2109380D02*
Y2109774D01*
G01Y2104380D02*
Y2104774D01*
G01Y2099380D02*
Y2099774D01*
G01X1648294Y2154380D02*
Y2154774D01*
G01Y2129380D02*
Y2129774D01*
G01X1648197Y2101329D02*
Y2100935D01*
G01Y2104478D02*
Y2104085D01*
G01Y2107628D02*
Y2107234D01*
G01Y2113927D02*
Y2113533D01*
G01Y2110777D02*
Y2110384D01*
G01Y2117077D02*
Y2116683D01*
G01Y2123376D02*
Y2122982D01*
G01Y2120226D02*
Y2119833D01*
G01Y2126525D02*
Y2126132D01*
G01Y2129675D02*
Y2129281D01*
G01Y2132825D02*
Y2132431D01*
G01Y2135974D02*
Y2135581D01*
G01Y2142274D02*
Y2141880D01*
G01Y2139124D02*
Y2138730D01*
G01Y2145423D02*
Y2145029D01*
G01Y2151722D02*
Y2151329D01*
G01Y2148573D02*
Y2148179D01*
G01Y2154872D02*
Y2154478D01*
G01X1650328Y2099774D02*
X1650405Y2100364D01*
G01X1650328Y2104774D02*
X1650405Y2105364D01*
G01X1650328Y2109774D02*
X1650405Y2110364D01*
G01X1650328Y2114774D02*
X1650405Y2115364D01*
G01X1650328Y2119774D02*
X1650405Y2120364D01*
G01X1650328Y2124774D02*
X1650405Y2125364D01*
G01X1650328Y2129774D02*
X1650405Y2130364D01*
G01X1650328Y2154774D02*
X1650405Y2155364D01*
G01X1649887Y2104478D02*
X1649897Y2104577D01*
X1649925Y2104649D01*
X1649964Y2104675D01*
G01X1649887Y2107628D02*
X1649897Y2107726D01*
X1649925Y2107798D01*
X1649964Y2107825D01*
G01X1649887Y2120226D02*
X1649897Y2120325D01*
X1649925Y2120397D01*
X1649964Y2120423D01*
G01X1649887Y2123376D02*
X1649897Y2123474D01*
X1649925Y2123546D01*
X1649964Y2123573D01*
G01X1649887Y2132825D02*
X1649897Y2132923D01*
X1649925Y2132995D01*
X1649964Y2133022D01*
G01X1649887Y2135974D02*
X1649897Y2136073D01*
X1649925Y2136145D01*
X1649964Y2136171D01*
G01X1649887Y2139124D02*
X1649897Y2139222D01*
X1649925Y2139294D01*
X1649964Y2139321D01*
G01X1649887Y2142274D02*
X1649897Y2142372D01*
X1649925Y2142444D01*
X1649964Y2142470D01*
G01X1649887Y2148573D02*
X1649897Y2148671D01*
X1649925Y2148743D01*
X1649964Y2148770D01*
G01X1649887Y2151722D02*
X1649897Y2151821D01*
X1649925Y2151893D01*
X1649964Y2151919D01*
G01X1649887Y2154872D02*
X1649897Y2154970D01*
X1649925Y2155042D01*
X1649964Y2155069D01*
G01X1649443Y2134697D02*
X1649445Y2134735D01*
X1649454Y2134772D01*
X1649467Y2134806D01*
X1649486Y2134836D01*
X1649508Y2134861D01*
X1649534Y2134879D01*
X1649561Y2134890D01*
X1649590Y2134894D01*
G01X1649443Y2137847D02*
X1649445Y2137885D01*
X1649454Y2137922D01*
X1649467Y2137955D01*
X1649486Y2137986D01*
X1649508Y2138010D01*
X1649534Y2138028D01*
X1649561Y2138040D01*
X1649590Y2138043D01*
G01X1649443Y2140996D02*
X1649445Y2141034D01*
X1649454Y2141071D01*
X1649467Y2141105D01*
X1649486Y2141135D01*
X1649508Y2141160D01*
X1649534Y2141178D01*
X1649561Y2141189D01*
X1649590Y2141193D01*
G01X1649443Y2144146D02*
X1649445Y2144184D01*
X1649454Y2144221D01*
X1649467Y2144255D01*
X1649486Y2144285D01*
X1649508Y2144309D01*
X1649534Y2144327D01*
X1649561Y2144339D01*
X1649590Y2144343D01*
G01X1649443Y2147295D02*
X1649445Y2147334D01*
X1649454Y2147370D01*
X1649467Y2147404D01*
X1649486Y2147435D01*
X1649508Y2147459D01*
X1649534Y2147477D01*
X1649561Y2147488D01*
X1649590Y2147492D01*
G01X1649443Y2150445D02*
X1649445Y2150483D01*
X1649454Y2150520D01*
X1649467Y2150554D01*
X1649486Y2150584D01*
X1649508Y2150609D01*
X1649534Y2150627D01*
X1649561Y2150638D01*
X1649590Y2150642D01*
G01X1649203Y2099774D02*
X1649476Y2100364D01*
G01X1649203Y2104774D02*
X1649476Y2105364D01*
G01X1649203Y2109774D02*
X1649476Y2110364D01*
G01X1649203Y2114774D02*
X1649476Y2115364D01*
G01X1649203Y2119774D02*
X1649476Y2120364D01*
G01X1649203Y2124774D02*
X1649476Y2125364D01*
G01X1649203Y2129774D02*
X1649476Y2130364D01*
G01X1649203Y2154774D02*
X1649476Y2155364D01*
G01X1648786Y2100364D02*
X1648359Y2099774D01*
G01X1648786Y2105364D02*
X1648359Y2104774D01*
G01X1648786Y2110364D02*
X1648359Y2109774D01*
G01X1648786Y2115364D02*
X1648359Y2114774D01*
G01X1654531Y2098789D02*
X1654670Y2098985D01*
X1654808Y2099182D01*
X1654945Y2099380D01*
G01X1654531Y2103789D02*
X1654670Y2103985D01*
X1654808Y2104182D01*
X1654945Y2104380D01*
G01X1654531Y2108789D02*
X1654670Y2108985D01*
X1654808Y2109182D01*
X1654945Y2109380D01*
G01X1654531Y2113789D02*
X1654670Y2113985D01*
X1654808Y2114182D01*
X1654945Y2114380D01*
G01X1654531Y2118789D02*
X1654670Y2118985D01*
X1654808Y2119182D01*
X1654945Y2119380D01*
G01X1654531Y2123789D02*
X1654670Y2123985D01*
X1654808Y2124182D01*
X1654945Y2124380D01*
G01X1654631Y2128789D02*
X1654767Y2128985D01*
X1654902Y2129182D01*
X1655036Y2129380D01*
G01X1658795Y2092805D02*
X1656827Y2090837D01*
G01X1648786Y2120364D02*
X1648359Y2119774D01*
G01X1648786Y2125364D02*
X1648359Y2124774D01*
G01X1648718Y2130364D02*
X1648294Y2129774D01*
G01X1648718Y2155364D02*
X1648294Y2154774D01*
G01X1654631Y2153789D02*
X1654767Y2153985D01*
X1654902Y2154182D01*
X1655036Y2154380D01*
G01X1649964Y2101525D02*
X1649925Y2101499D01*
X1649897Y2101427D01*
X1649887Y2101329D01*
G01X1649964Y2110974D02*
X1649925Y2110948D01*
X1649897Y2110876D01*
X1649887Y2110777D01*
G01X1649964Y2114124D02*
X1649925Y2114097D01*
X1649897Y2114025D01*
X1649887Y2113927D01*
G01X1649964Y2117274D02*
X1649925Y2117247D01*
X1649897Y2117175D01*
X1649887Y2117077D01*
G01X1649964Y2126722D02*
X1649925Y2126696D01*
X1649897Y2126624D01*
X1649887Y2126525D01*
G01X1649964Y2129872D02*
X1649925Y2129846D01*
X1649897Y2129773D01*
X1649887Y2129675D01*
G01X1649964Y2145620D02*
X1649925Y2145594D01*
X1649897Y2145521D01*
X1649887Y2145423D01*
G01X1658795Y2153809D02*
X1656827Y2151840D01*
G01X1665488Y2088868D02*
Y2087136D01*
G01X1662079Y2090837D02*
X1665488Y2088868D01*
G01X1654561Y2160581D02*
X1654689Y2160608D01*
X1654777Y2160681D01*
X1654809Y2160777D01*
G01X1654561Y2161368D02*
X1648477D01*
G01X1648197Y2161171D02*
X1654809D01*
G01Y2160777D02*
X1648197D01*
G01X1654561Y2160581D02*
X1648477D01*
G01X1654531Y2160364D02*
X1648786D01*
G01X1648359Y2159774D02*
X1654945D01*
G01X1648359Y2159380D02*
X1654945D01*
G01X1654531Y2158789D02*
X1648786D01*
G01X1654561Y2158218D02*
X1648477D01*
G01X1648197Y2158022D02*
X1654809D01*
G01Y2157628D02*
X1648197D01*
G01X1649513Y2161368D02*
X1649486Y2161364D01*
X1649460Y2161353D01*
X1649436Y2161335D01*
X1649415Y2161310D01*
X1649397Y2161281D01*
X1649385Y2161247D01*
X1649377Y2161210D01*
X1649374Y2161171D01*
G01X1649513Y2158218D02*
X1649486Y2158215D01*
X1649460Y2158204D01*
X1649436Y2158186D01*
X1649415Y2158161D01*
X1649397Y2158131D01*
X1649385Y2158097D01*
X1649377Y2158060D01*
X1649374Y2158022D01*
G01X1649964Y2160581D02*
X1649925Y2160607D01*
X1649897Y2160679D01*
X1649887Y2160777D01*
G01X1654945Y2159774D02*
X1654808Y2159971D01*
X1654670Y2160168D01*
X1654531Y2160364D01*
G01X1648786Y2158789D02*
X1648359Y2159380D01*
G01X1649476Y2158789D02*
X1649203Y2159380D01*
G01X1654809Y2161171D02*
X1654777Y2161268D01*
X1654689Y2161340D01*
X1654561Y2161368D01*
G01X1654809Y2158022D02*
X1654777Y2158119D01*
X1654689Y2158191D01*
X1654561Y2158218D01*
G01X1650328Y2159380D02*
X1650405Y2158789D01*
G01X1649374Y2160777D02*
X1649377Y2160739D01*
X1649385Y2160702D01*
X1649397Y2160669D01*
X1649415Y2160638D01*
X1649436Y2160614D01*
X1649459Y2160596D01*
X1649485Y2160585D01*
X1649513Y2160581D01*
G01X1657614Y2229183D02*
Y2158277D01*
G01X1654945Y2159774D02*
Y2159380D01*
G01X1654809Y2160777D02*
Y2161171D01*
G01Y2157628D02*
Y2158022D01*
G01X1650328Y2159774D02*
Y2159380D01*
G01X1649887Y2160777D02*
Y2161171D01*
G01Y2157628D02*
Y2158022D01*
G01X1649374Y2161171D02*
Y2160777D01*
G01Y2158022D02*
Y2157628D01*
G01X1649203Y2159380D02*
Y2159774D01*
G01X1648359Y2159380D02*
Y2159774D01*
G01X1648197Y2161171D02*
Y2160777D01*
G01Y2158022D02*
Y2157628D01*
G01X1650328Y2159774D02*
X1650405Y2160364D01*
G01X1649887Y2158022D02*
X1649897Y2158120D01*
X1649925Y2158192D01*
X1649964Y2158218D01*
G01X1649887Y2161171D02*
X1649897Y2161270D01*
X1649925Y2161342D01*
X1649964Y2161368D01*
G01X1649203Y2159774D02*
X1649476Y2160364D01*
G01X1648786D02*
X1648359Y2159774D01*
G01X1654531Y2158789D02*
X1654670Y2158985D01*
X1654808Y2159182D01*
X1654945Y2159380D01*
G01X1654531Y2225364D02*
X1648786D01*
G01X1648359Y2224774D02*
X1654945D01*
G01X1648359Y2224380D02*
X1654945D01*
G01X1654561Y2224360D02*
X1648477D01*
G01X1648197Y2224163D02*
X1654809D01*
G01X1654531Y2223789D02*
X1648786D01*
G01X1654809Y2223770D02*
X1648197D01*
G01X1654561Y2223573D02*
X1648477D01*
G01X1654561Y2221211D02*
X1648477D01*
G01X1648197Y2221014D02*
X1654809D01*
G01Y2220620D02*
X1648197D01*
G01X1654561Y2220423D02*
X1648477D01*
G01X1654531Y2220364D02*
X1648786D01*
G01X1648359Y2219774D02*
X1654945D01*
G01X1648359Y2219380D02*
X1654945D01*
G01X1654531Y2218789D02*
X1648786D01*
G01X1654561Y2218061D02*
X1648477D01*
G01X1648197Y2217864D02*
X1654809D01*
G01Y2217470D02*
X1648197D01*
G01X1654561Y2217274D02*
X1648477D01*
G01X1654531Y2215364D02*
X1648786D01*
G01X1654561Y2214911D02*
X1648477D01*
G01X1648359Y2214774D02*
X1654945D01*
G01X1648197Y2214714D02*
X1654809D01*
G01X1648359Y2214380D02*
X1654945D01*
G01X1654809Y2214321D02*
X1648197D01*
G01X1654561Y2214124D02*
X1648477D01*
G01X1654531Y2213789D02*
X1648786D01*
G01X1654561Y2211762D02*
X1648477D01*
G01X1648197Y2211565D02*
X1654809D01*
G01Y2211171D02*
X1648197D01*
G01X1654561Y2210974D02*
X1648477D01*
G01X1656500Y2210364D02*
X1650754D01*
G01X1650328Y2209774D02*
X1656914D01*
G01X1650328Y2209380D02*
X1656914D01*
G01X1656500Y2208789D02*
X1650754D01*
G01X1654561Y2208612D02*
X1648477D01*
G01X1648197Y2208415D02*
X1654809D01*
G01Y2208022D02*
X1648197D01*
G01X1654561Y2207825D02*
X1648477D01*
G01X1654561Y2205463D02*
X1648477D01*
G01X1654531Y2205364D02*
X1648786D01*
G01X1648197Y2205266D02*
X1654809D01*
G01Y2204872D02*
X1648197D01*
G01X1648359Y2204774D02*
X1654945D01*
G01X1654561Y2204675D02*
X1648477D01*
G01X1648359Y2204380D02*
X1654945D01*
G01X1654531Y2203789D02*
X1648786D01*
G01X1654561Y2202313D02*
X1648477D01*
G01X1648197Y2202116D02*
X1654809D01*
G01Y2201722D02*
X1648197D01*
G01X1654561Y2201525D02*
X1648477D01*
G01X1654531Y2200364D02*
X1648786D01*
G01X1648359Y2199774D02*
X1654945D01*
G01X1648359Y2199380D02*
X1654945D01*
G01X1654561Y2199163D02*
X1648477D01*
G01X1648197Y2198966D02*
X1654809D01*
G01X1654531Y2198789D02*
X1648786D01*
G01X1654809Y2198573D02*
X1648197D01*
G01X1654561Y2198376D02*
X1648477D01*
G01X1649513Y2224360D02*
X1649486Y2224356D01*
X1649460Y2224345D01*
X1649436Y2224327D01*
X1649415Y2224302D01*
X1649397Y2224273D01*
X1649385Y2224239D01*
X1649377Y2224202D01*
X1649374Y2224163D01*
G01X1649513Y2221211D02*
X1649486Y2221207D01*
X1649460Y2221196D01*
X1649436Y2221178D01*
X1649415Y2221153D01*
X1649397Y2221123D01*
X1649385Y2221089D01*
X1649377Y2221053D01*
X1649374Y2221014D01*
G01X1649513Y2218061D02*
X1649486Y2218057D01*
X1649460Y2218046D01*
X1649436Y2218028D01*
X1649415Y2218003D01*
X1649397Y2217974D01*
X1649385Y2217940D01*
X1649377Y2217903D01*
X1649374Y2217864D01*
G01X1649513Y2214911D02*
X1649486Y2214908D01*
X1649460Y2214896D01*
X1649436Y2214878D01*
X1649415Y2214854D01*
X1649397Y2214824D01*
X1649385Y2214790D01*
X1649377Y2214753D01*
X1649374Y2214714D01*
G01X1649513Y2211762D02*
X1649486Y2211758D01*
X1649460Y2211747D01*
X1649436Y2211729D01*
X1649415Y2211704D01*
X1649397Y2211674D01*
X1649385Y2211641D01*
X1649377Y2211604D01*
X1649374Y2211565D01*
G01X1649513Y2208612D02*
X1649486Y2208608D01*
X1649460Y2208597D01*
X1649436Y2208579D01*
X1649415Y2208554D01*
X1649397Y2208525D01*
X1649385Y2208491D01*
X1649377Y2208454D01*
X1649374Y2208415D01*
G01X1649513Y2205463D02*
X1649486Y2205459D01*
X1649460Y2205448D01*
X1649436Y2205430D01*
X1649415Y2205405D01*
X1649397Y2205375D01*
X1649385Y2205341D01*
X1649377Y2205305D01*
X1649374Y2205266D01*
G01X1649513Y2202313D02*
X1649486Y2202309D01*
X1649460Y2202298D01*
X1649436Y2202280D01*
X1649415Y2202255D01*
X1649397Y2202226D01*
X1649385Y2202192D01*
X1649377Y2202155D01*
X1649374Y2202116D01*
G01X1649513Y2199163D02*
X1649486Y2199160D01*
X1649460Y2199148D01*
X1649436Y2199130D01*
X1649415Y2199106D01*
X1649397Y2199076D01*
X1649385Y2199042D01*
X1649377Y2199005D01*
X1649374Y2198966D01*
G01X1649513Y2196014D02*
X1649486Y2196010D01*
X1649460Y2195999D01*
X1649436Y2195981D01*
X1649415Y2195956D01*
X1649397Y2195926D01*
X1649385Y2195892D01*
X1649377Y2195856D01*
X1649374Y2195817D01*
G01X1649513Y2192864D02*
X1649486Y2192860D01*
X1649460Y2192849D01*
X1649436Y2192831D01*
X1649415Y2192806D01*
X1649397Y2192777D01*
X1649385Y2192743D01*
X1649377Y2192706D01*
X1649374Y2192667D01*
G01X1649513Y2189714D02*
X1649486Y2189711D01*
X1649460Y2189700D01*
X1649436Y2189682D01*
X1649415Y2189657D01*
X1649397Y2189627D01*
X1649385Y2189593D01*
X1649377Y2189557D01*
X1649374Y2189518D01*
G01X1649513Y2186565D02*
X1649486Y2186561D01*
X1649460Y2186550D01*
X1649436Y2186532D01*
X1649415Y2186507D01*
X1649397Y2186478D01*
X1649385Y2186444D01*
X1649377Y2186407D01*
X1649374Y2186368D01*
G01X1649513Y2183415D02*
X1649486Y2183412D01*
X1649460Y2183400D01*
X1649436Y2183382D01*
X1649415Y2183358D01*
X1649397Y2183328D01*
X1649385Y2183294D01*
X1649377Y2183257D01*
X1649374Y2183218D01*
G01X1649513Y2180266D02*
X1649486Y2180262D01*
X1649460Y2180251D01*
X1649436Y2180233D01*
X1649415Y2180208D01*
X1649397Y2180178D01*
X1649385Y2180144D01*
X1649377Y2180108D01*
X1649374Y2180069D01*
G01X1649513Y2177116D02*
X1649486Y2177112D01*
X1649460Y2177101D01*
X1649436Y2177083D01*
X1649415Y2177058D01*
X1649397Y2177029D01*
X1649385Y2176995D01*
X1649377Y2176958D01*
X1649374Y2176919D01*
G01X1649513Y2173966D02*
X1649486Y2173963D01*
X1649460Y2173952D01*
X1649436Y2173934D01*
X1649415Y2173909D01*
X1649397Y2173879D01*
X1649385Y2173845D01*
X1649377Y2173809D01*
X1649374Y2173770D01*
G01X1649513Y2170817D02*
X1649486Y2170813D01*
X1649460Y2170802D01*
X1649436Y2170784D01*
X1649415Y2170759D01*
X1649397Y2170729D01*
X1649385Y2170696D01*
X1649377Y2170659D01*
X1649374Y2170620D01*
G01X1649513Y2167667D02*
X1649486Y2167663D01*
X1649460Y2167652D01*
X1649436Y2167634D01*
X1649415Y2167610D01*
X1649397Y2167580D01*
X1649385Y2167546D01*
X1649377Y2167509D01*
X1649374Y2167470D01*
G01X1649513Y2164518D02*
X1649486Y2164514D01*
X1649460Y2164503D01*
X1649436Y2164485D01*
X1649415Y2164460D01*
X1649397Y2164430D01*
X1649385Y2164396D01*
X1649377Y2164360D01*
X1649374Y2164321D01*
G01X1654561Y2223573D02*
X1654689Y2223600D01*
X1654777Y2223673D01*
X1654809Y2223770D01*
G01X1654561Y2220423D02*
X1654689Y2220451D01*
X1654777Y2220524D01*
X1654809Y2220620D01*
G01X1654561Y2217274D02*
X1654689Y2217301D01*
X1654777Y2217374D01*
X1654809Y2217470D01*
G01X1654561Y2214124D02*
X1654689Y2214152D01*
X1654777Y2214225D01*
X1654809Y2214321D01*
G01X1654561Y2207825D02*
X1654689Y2207852D01*
X1654777Y2207925D01*
X1654809Y2208022D01*
G01X1654561Y2204675D02*
X1654689Y2204703D01*
X1654777Y2204776D01*
X1654809Y2204872D01*
G01X1654561Y2201525D02*
X1654689Y2201553D01*
X1654777Y2201626D01*
X1654809Y2201722D01*
G01X1654561Y2198376D02*
X1654689Y2198404D01*
X1654777Y2198477D01*
X1654809Y2198573D01*
G01X1654561Y2195226D02*
X1654689Y2195254D01*
X1654777Y2195327D01*
X1654809Y2195423D01*
G01X1654561Y2192077D02*
X1654689Y2192104D01*
X1654777Y2192177D01*
X1654809Y2192274D01*
G01X1654561Y2188927D02*
X1654689Y2188955D01*
X1654777Y2189028D01*
X1654809Y2189124D01*
G01X1654561Y2185777D02*
X1654689Y2185805D01*
X1654777Y2185878D01*
X1654809Y2185974D01*
G01X1654561Y2179478D02*
X1654689Y2179506D01*
X1654777Y2179579D01*
X1654809Y2179675D01*
G01X1654561Y2176329D02*
X1654689Y2176356D01*
X1654777Y2176429D01*
X1654809Y2176525D01*
G01X1654561Y2173179D02*
X1654689Y2173207D01*
X1654777Y2173280D01*
X1654809Y2173376D01*
G01X1654561Y2170029D02*
X1654689Y2170057D01*
X1654777Y2170130D01*
X1654809Y2170226D01*
G01X1654561Y2166880D02*
X1654689Y2166908D01*
X1654777Y2166980D01*
X1654809Y2167077D01*
G01X1654561Y2163730D02*
X1654689Y2163758D01*
X1654777Y2163831D01*
X1654809Y2163927D01*
G01X1654561Y2211762D02*
X1654688Y2211734D01*
X1654777Y2211662D01*
X1654809Y2211565D01*
G01X1654561Y2196014D02*
X1648477D01*
G01X1648197Y2195817D02*
X1654809D01*
G01Y2195423D02*
X1648197D01*
G01X1654531Y2195364D02*
X1648786D01*
G01X1654561Y2195226D02*
X1648477D01*
G01X1648359Y2194774D02*
X1654945D01*
G01X1648359Y2194380D02*
X1654945D01*
G01X1654531Y2193789D02*
X1648786D01*
G01X1654561Y2192864D02*
X1648477D01*
G01X1648197Y2192667D02*
X1654809D01*
G01Y2192274D02*
X1648197D01*
G01X1654561Y2192077D02*
X1648477D01*
G01X1654531Y2190364D02*
X1648786D01*
G01X1648359Y2189774D02*
X1654945D01*
G01X1654561Y2189714D02*
X1648477D01*
G01X1648197Y2189518D02*
X1654809D01*
G01X1648359Y2189380D02*
X1654945D01*
G01X1654809Y2189124D02*
X1648197D01*
G01X1654561Y2188927D02*
X1648477D01*
G01X1654531Y2188789D02*
X1648786D01*
G01X1654561Y2186565D02*
X1648477D01*
G01X1648197Y2186368D02*
X1654809D01*
G01Y2185974D02*
X1648197D01*
G01X1654561Y2185777D02*
X1648477D01*
G01X1654531Y2185364D02*
X1648786D01*
G01X1648359Y2184774D02*
X1654945D01*
G01X1648359Y2184380D02*
X1654945D01*
G01X1654531Y2183789D02*
X1648786D01*
G01X1654561Y2183415D02*
X1648477D01*
G01X1648197Y2183218D02*
X1654809D01*
G01Y2182825D02*
X1648197D01*
G01X1654561Y2182628D02*
X1648477D01*
G01X1654531Y2180364D02*
X1648786D01*
G01X1654561Y2180266D02*
X1648477D01*
G01X1648197Y2180069D02*
X1654809D01*
G01X1648359Y2179774D02*
X1654945D01*
G01X1654809Y2179675D02*
X1648197D01*
G01X1654561Y2179478D02*
X1648477D01*
G01X1648359Y2179380D02*
X1654945D01*
G01X1654531Y2178789D02*
X1648786D01*
G01X1654561Y2177116D02*
X1648477D01*
G01X1648197Y2176919D02*
X1654809D01*
G01Y2176525D02*
X1648197D01*
G01X1654561Y2176329D02*
X1648477D01*
G01X1654531Y2175364D02*
X1648786D01*
G01X1648359Y2174774D02*
X1654945D01*
G01X1648359Y2174380D02*
X1654945D01*
G01X1654561Y2173966D02*
X1648477D01*
G01X1654531Y2173789D02*
X1648786D01*
G01X1648197Y2173770D02*
X1654809D01*
G01Y2173376D02*
X1648197D01*
G01X1654561Y2173179D02*
X1648477D01*
G01X1654561Y2170817D02*
X1648477D01*
G01X1648197Y2170620D02*
X1654809D01*
G01X1656500Y2170364D02*
X1650754D01*
G01X1654809Y2170226D02*
X1648197D01*
G01X1654561Y2170029D02*
X1648477D01*
G01X1650328Y2169774D02*
X1656914D01*
G01X1650328Y2169380D02*
X1656914D01*
G01X1656500Y2168789D02*
X1650754D01*
G01X1654561Y2167667D02*
X1648477D01*
G01X1648197Y2167470D02*
X1654809D01*
G01Y2167077D02*
X1648197D01*
G01X1654561Y2166880D02*
X1648477D01*
G01X1654531Y2165364D02*
X1648786D01*
G01X1648359Y2164774D02*
X1654945D01*
G01X1654561Y2164518D02*
X1648477D01*
G01X1648359Y2164380D02*
X1654945D01*
G01X1648197Y2164321D02*
X1654809D01*
G01Y2163927D02*
X1648197D01*
G01X1654531Y2163789D02*
X1648786D01*
G01X1654561Y2163730D02*
X1648477D01*
G01X1654561Y2183415D02*
X1654688Y2183388D01*
X1654777Y2183315D01*
X1654809Y2183218D01*
G01X1649964Y2223573D02*
X1649925Y2223599D01*
X1649897Y2223671D01*
X1649887Y2223770D01*
G01X1649964Y2220423D02*
X1649925Y2220450D01*
X1649897Y2220522D01*
X1649887Y2220620D01*
G01X1649964Y2217274D02*
X1649925Y2217300D01*
X1649897Y2217372D01*
X1649887Y2217470D01*
G01X1649964Y2214124D02*
X1649925Y2214150D01*
X1649897Y2214222D01*
X1649887Y2214321D01*
G01X1649964Y2210974D02*
X1649925Y2211001D01*
X1649897Y2211073D01*
X1649887Y2211171D01*
G01X1649964Y2207825D02*
X1649925Y2207851D01*
X1649897Y2207923D01*
X1649887Y2208022D01*
G01X1649964Y2204675D02*
X1649925Y2204702D01*
X1649897Y2204774D01*
X1649887Y2204872D01*
G01X1649964Y2201525D02*
X1649925Y2201552D01*
X1649897Y2201624D01*
X1649887Y2201722D01*
G01X1649964Y2198376D02*
X1649925Y2198402D01*
X1649897Y2198474D01*
X1649887Y2198573D01*
G01X1649964Y2195226D02*
X1649925Y2195253D01*
X1649897Y2195325D01*
X1649887Y2195423D01*
G01X1649964Y2192077D02*
X1649925Y2192103D01*
X1649897Y2192175D01*
X1649887Y2192274D01*
G01X1649964Y2188927D02*
X1649925Y2188953D01*
X1649897Y2189026D01*
X1649887Y2189124D01*
G01X1649964Y2185777D02*
X1649925Y2185804D01*
X1649897Y2185876D01*
X1649887Y2185974D01*
G01X1649964Y2182628D02*
X1649925Y2182654D01*
X1649897Y2182726D01*
X1649887Y2182825D01*
G01X1649964Y2179478D02*
X1649925Y2179505D01*
X1649897Y2179577D01*
X1649887Y2179675D01*
G01X1649964Y2176329D02*
X1649925Y2176355D01*
X1649897Y2176427D01*
X1649887Y2176525D01*
G01X1649964Y2173179D02*
X1649925Y2173205D01*
X1649897Y2173278D01*
X1649887Y2173376D01*
G01X1649964Y2170029D02*
X1649925Y2170056D01*
X1649897Y2170128D01*
X1649887Y2170226D01*
G01X1649964Y2166880D02*
X1649925Y2166906D01*
X1649897Y2166978D01*
X1649887Y2167077D01*
G01X1649964Y2163730D02*
X1649925Y2163757D01*
X1649897Y2163829D01*
X1649887Y2163927D01*
G01X1654945Y2224774D02*
X1654808Y2224971D01*
X1654670Y2225168D01*
X1654531Y2225364D01*
G01X1654945Y2219774D02*
X1654808Y2219971D01*
X1654670Y2220168D01*
X1654531Y2220364D01*
G01X1654945Y2214774D02*
X1654808Y2214971D01*
X1654670Y2215168D01*
X1654531Y2215364D01*
G01X1656914Y2209774D02*
X1656777Y2209971D01*
X1656639Y2210168D01*
X1656500Y2210364D01*
G01X1654945Y2204774D02*
X1654808Y2204971D01*
X1654670Y2205168D01*
X1654531Y2205364D01*
G01X1654945Y2199774D02*
X1654808Y2199971D01*
X1654670Y2200168D01*
X1654531Y2200364D01*
G01X1654945Y2194774D02*
X1654808Y2194971D01*
X1654670Y2195168D01*
X1654531Y2195364D01*
G01X1654945Y2189774D02*
X1654808Y2189971D01*
X1654670Y2190168D01*
X1654531Y2190364D01*
G01X1654945Y2184774D02*
X1654808Y2184971D01*
X1654670Y2185168D01*
X1654531Y2185364D01*
G01X1654945Y2179774D02*
X1654808Y2179971D01*
X1654670Y2180168D01*
X1654531Y2180364D01*
G01X1654945Y2174774D02*
X1654808Y2174971D01*
X1654670Y2175168D01*
X1654531Y2175364D01*
G01X1656914Y2169774D02*
X1656777Y2169971D01*
X1656639Y2170168D01*
X1656500Y2170364D01*
G01X1654945Y2164774D02*
X1654808Y2164971D01*
X1654670Y2165168D01*
X1654531Y2165364D01*
G01X1648786Y2223789D02*
X1648359Y2224380D01*
G01X1648786Y2218789D02*
X1648359Y2219380D01*
G01X1648786Y2213789D02*
X1648359Y2214380D01*
G01X1650754Y2208789D02*
X1650328Y2209380D01*
G01X1648786Y2203789D02*
X1648359Y2204380D01*
G01X1648786Y2198789D02*
X1648359Y2199380D01*
G01X1648786Y2193789D02*
X1648359Y2194380D01*
G01X1648786Y2188789D02*
X1648359Y2189380D01*
G01X1648786Y2183789D02*
X1648359Y2184380D01*
G01X1648786Y2178789D02*
X1648359Y2179380D01*
G01X1648786Y2173789D02*
X1648359Y2174380D01*
G01X1650754Y2168789D02*
X1650328Y2169380D01*
G01X1648786Y2163789D02*
X1648359Y2164380D01*
G01X1649476Y2223789D02*
X1649203Y2224380D01*
G01X1649476Y2218789D02*
X1649203Y2219380D01*
G01X1649476Y2213789D02*
X1649203Y2214380D01*
G01X1651444Y2208789D02*
X1651172Y2209380D01*
G01X1649476Y2203789D02*
X1649203Y2204380D01*
G01X1649476Y2198789D02*
X1649203Y2199380D01*
G01X1649476Y2193789D02*
X1649203Y2194380D01*
G01X1649476Y2188789D02*
X1649203Y2189380D01*
G01X1649476Y2183789D02*
X1649203Y2184380D01*
G01X1649476Y2178789D02*
X1649203Y2179380D01*
G01X1649476Y2173789D02*
X1649203Y2174380D01*
G01X1651444Y2168789D02*
X1651172Y2169380D01*
G01X1649476Y2163789D02*
X1649203Y2164380D01*
G01X1654809Y2224163D02*
X1654777Y2224260D01*
X1654689Y2224332D01*
X1654561Y2224360D01*
G01X1654809Y2221014D02*
X1654777Y2221111D01*
X1654689Y2221183D01*
X1654561Y2221211D01*
G01X1654809Y2217864D02*
X1654777Y2217961D01*
X1654689Y2218033D01*
X1654561Y2218061D01*
G01X1654809Y2214714D02*
X1654777Y2214811D01*
X1654689Y2214884D01*
X1654561Y2214911D01*
G01X1654809Y2208415D02*
X1654777Y2208512D01*
X1654689Y2208584D01*
X1654561Y2208612D01*
G01X1654809Y2205266D02*
X1654777Y2205363D01*
X1654689Y2205435D01*
X1654561Y2205463D01*
G01X1654809Y2202116D02*
X1654777Y2202213D01*
X1654689Y2202285D01*
X1654561Y2202313D01*
G01X1654809Y2198966D02*
X1654777Y2199063D01*
X1654689Y2199136D01*
X1654561Y2199163D01*
G01X1654809Y2195817D02*
X1654777Y2195914D01*
X1654689Y2195986D01*
X1654561Y2196014D01*
G01X1654809Y2192667D02*
X1654777Y2192764D01*
X1654689Y2192836D01*
X1654561Y2192864D01*
G01X1654809Y2189518D02*
X1654777Y2189615D01*
X1654689Y2189687D01*
X1654561Y2189714D01*
G01X1654809Y2186368D02*
X1654777Y2186465D01*
X1654689Y2186537D01*
X1654561Y2186565D01*
G01X1654809Y2180069D02*
X1654777Y2180166D01*
X1654689Y2180238D01*
X1654561Y2180266D01*
G01X1654809Y2176919D02*
X1654777Y2177016D01*
X1654689Y2177088D01*
X1654561Y2177116D01*
G01X1654809Y2173770D02*
X1654777Y2173867D01*
X1654689Y2173939D01*
X1654561Y2173966D01*
G01X1654809Y2170620D02*
X1654777Y2170717D01*
X1654689Y2170789D01*
X1654561Y2170817D01*
G01X1654809Y2167470D02*
X1654777Y2167567D01*
X1654689Y2167640D01*
X1654561Y2167667D01*
G01X1654809Y2164321D02*
X1654777Y2164418D01*
X1654689Y2164490D01*
X1654561Y2164518D01*
G01X1650328Y2224380D02*
X1650405Y2223789D01*
G01X1652296Y2209380D02*
X1652374Y2208789D01*
G01X1650405Y2218789D02*
X1650328Y2219380D01*
G01Y2214380D02*
X1650405Y2213789D01*
G01X1650328Y2204380D02*
X1650405Y2203789D01*
G01X1650328Y2199380D02*
X1650405Y2198789D01*
G01X1650328Y2194380D02*
X1650405Y2193789D01*
G01X1650328Y2189380D02*
X1650405Y2188789D01*
G01X1650328Y2184380D02*
X1650405Y2183789D01*
G01X1652296Y2169380D02*
X1652374Y2168789D01*
G01X1650328Y2179380D02*
X1650405Y2178789D01*
G01X1650328Y2174380D02*
X1650405Y2173789D01*
G01X1650328Y2164380D02*
X1650405Y2163789D01*
G01X1649374Y2223770D02*
X1649377Y2223731D01*
X1649385Y2223695D01*
X1649397Y2223661D01*
X1649415Y2223630D01*
X1649436Y2223606D01*
X1649459Y2223588D01*
X1649485Y2223577D01*
X1649513Y2223573D01*
G01X1649374Y2220620D02*
X1649377Y2220582D01*
X1649385Y2220545D01*
X1649397Y2220511D01*
X1649415Y2220481D01*
X1649436Y2220456D01*
X1649459Y2220438D01*
X1649485Y2220427D01*
X1649513Y2220423D01*
G01X1649374Y2217470D02*
X1649377Y2217432D01*
X1649385Y2217395D01*
X1649397Y2217361D01*
X1649415Y2217331D01*
X1649436Y2217307D01*
X1649459Y2217289D01*
X1649485Y2217277D01*
X1649513Y2217274D01*
G01X1649374Y2214321D02*
X1649377Y2214283D01*
X1649385Y2214246D01*
X1649397Y2214212D01*
X1649415Y2214182D01*
X1649436Y2214157D01*
X1649459Y2214139D01*
X1649485Y2214128D01*
X1649513Y2214124D01*
G01X1649374Y2211171D02*
X1649377Y2211133D01*
X1649385Y2211096D01*
X1649397Y2211062D01*
X1649415Y2211032D01*
X1649436Y2211008D01*
X1649459Y2210989D01*
X1649485Y2210978D01*
X1649513Y2210974D01*
G01X1649374Y2208022D02*
X1649377Y2207983D01*
X1649385Y2207947D01*
X1649397Y2207913D01*
X1649415Y2207882D01*
X1649436Y2207858D01*
X1649459Y2207840D01*
X1649485Y2207829D01*
X1649513Y2207825D01*
G01X1649374Y2204872D02*
X1649377Y2204834D01*
X1649385Y2204797D01*
X1649397Y2204763D01*
X1649415Y2204733D01*
X1649436Y2204708D01*
X1649459Y2204690D01*
X1649485Y2204679D01*
X1649513Y2204675D01*
G01X1649374Y2201722D02*
X1649377Y2201684D01*
X1649385Y2201647D01*
X1649397Y2201613D01*
X1649415Y2201583D01*
X1649436Y2201559D01*
X1649459Y2201541D01*
X1649485Y2201529D01*
X1649513Y2201525D01*
G01X1649374Y2198573D02*
X1649377Y2198535D01*
X1649385Y2198498D01*
X1649397Y2198464D01*
X1649415Y2198434D01*
X1649436Y2198409D01*
X1649459Y2198391D01*
X1649485Y2198380D01*
X1649513Y2198376D01*
G01X1649374Y2195423D02*
X1649377Y2195385D01*
X1649385Y2195348D01*
X1649397Y2195314D01*
X1649415Y2195284D01*
X1649436Y2195260D01*
X1649459Y2195241D01*
X1649485Y2195230D01*
X1649513Y2195226D01*
G01X1649374Y2192274D02*
X1649377Y2192235D01*
X1649385Y2192199D01*
X1649397Y2192165D01*
X1649415Y2192134D01*
X1649436Y2192110D01*
X1649459Y2192092D01*
X1649485Y2192081D01*
X1649513Y2192077D01*
G01X1649374Y2189124D02*
X1649377Y2189086D01*
X1649385Y2189049D01*
X1649397Y2189015D01*
X1649415Y2188985D01*
X1649436Y2188960D01*
X1649459Y2188942D01*
X1649485Y2188931D01*
X1649513Y2188927D01*
G01X1649374Y2185974D02*
X1649377Y2185936D01*
X1649385Y2185899D01*
X1649397Y2185865D01*
X1649415Y2185835D01*
X1649436Y2185811D01*
X1649459Y2185793D01*
X1649485Y2185781D01*
X1649513Y2185777D01*
G01X1649374Y2182825D02*
X1649377Y2182786D01*
X1649385Y2182750D01*
X1649397Y2182716D01*
X1649415Y2182686D01*
X1649436Y2182661D01*
X1649459Y2182643D01*
X1649485Y2182632D01*
X1649513Y2182628D01*
G01X1649374Y2179675D02*
X1649377Y2179637D01*
X1649385Y2179600D01*
X1649397Y2179566D01*
X1649415Y2179536D01*
X1649436Y2179512D01*
X1649459Y2179493D01*
X1649485Y2179482D01*
X1649513Y2179478D01*
G01X1649374Y2176525D02*
X1649377Y2176487D01*
X1649385Y2176450D01*
X1649397Y2176417D01*
X1649415Y2176386D01*
X1649436Y2176362D01*
X1649459Y2176344D01*
X1649485Y2176333D01*
X1649513Y2176329D01*
G01X1649374Y2173376D02*
X1649377Y2173338D01*
X1649385Y2173301D01*
X1649397Y2173267D01*
X1649415Y2173237D01*
X1649436Y2173212D01*
X1649459Y2173194D01*
X1649485Y2173183D01*
X1649513Y2173179D01*
G01X1649374Y2170226D02*
X1649377Y2170188D01*
X1649385Y2170151D01*
X1649397Y2170117D01*
X1649415Y2170087D01*
X1649436Y2170063D01*
X1649459Y2170045D01*
X1649485Y2170033D01*
X1649513Y2170029D01*
G01X1649374Y2167077D02*
X1649377Y2167038D01*
X1649385Y2167002D01*
X1649397Y2166968D01*
X1649415Y2166937D01*
X1649436Y2166913D01*
X1649459Y2166895D01*
X1649485Y2166884D01*
X1649513Y2166880D01*
G01X1649374Y2163927D02*
X1649377Y2163889D01*
X1649385Y2163852D01*
X1649397Y2163818D01*
X1649415Y2163788D01*
X1649436Y2163763D01*
X1649459Y2163745D01*
X1649485Y2163734D01*
X1649513Y2163730D01*
G01X1656914Y2169774D02*
Y2169380D01*
G01Y2209774D02*
Y2209380D01*
G01X1654945Y2164774D02*
Y2164380D01*
G01Y2174774D02*
Y2174380D01*
G01Y2179774D02*
Y2179380D01*
G01Y2184774D02*
Y2184380D01*
G01Y2189774D02*
Y2189380D01*
G01Y2194774D02*
Y2194380D01*
G01Y2199774D02*
Y2199380D01*
G01Y2204774D02*
Y2204380D01*
G01Y2214774D02*
Y2214380D01*
G01Y2219774D02*
Y2219380D01*
G01Y2224774D02*
Y2224380D01*
G01X1654809Y2223770D02*
Y2224163D01*
G01Y2220620D02*
Y2221014D01*
G01Y2217470D02*
Y2217864D01*
G01Y2214321D02*
Y2214714D01*
G01Y2208022D02*
Y2208415D01*
G01Y2211171D02*
Y2211565D01*
G01Y2204872D02*
Y2205266D01*
G01Y2201722D02*
Y2202116D01*
G01Y2198573D02*
Y2198966D01*
G01Y2195423D02*
Y2195817D01*
G01Y2192274D02*
Y2192667D01*
G01Y2189124D02*
Y2189518D01*
G01Y2185974D02*
Y2186368D01*
G01Y2182825D02*
Y2183218D01*
G01Y2176525D02*
Y2176919D01*
G01Y2179675D02*
Y2180069D01*
G01Y2173376D02*
Y2173770D01*
G01Y2170226D02*
Y2170620D01*
G01Y2167077D02*
Y2167470D01*
G01Y2163927D02*
Y2164321D01*
G01X1652296Y2169774D02*
Y2169380D01*
G01Y2209774D02*
Y2209380D01*
G01X1651172D02*
Y2209774D01*
G01Y2169380D02*
Y2169774D01*
G01X1650328Y2209380D02*
Y2209774D01*
G01Y2169380D02*
Y2169774D01*
G01Y2219380D02*
Y2219774D01*
G01Y2164774D02*
Y2164380D01*
G01Y2174774D02*
Y2174380D01*
G01Y2179774D02*
Y2179380D01*
G01Y2184774D02*
Y2184380D01*
G01Y2189774D02*
Y2189380D01*
G01Y2194774D02*
Y2194380D01*
G01Y2199774D02*
Y2199380D01*
G01Y2204774D02*
Y2204380D01*
G01Y2214774D02*
Y2214380D01*
G01Y2224774D02*
Y2224380D01*
G01X1649887Y2223770D02*
Y2224163D01*
G01Y2220620D02*
Y2221014D01*
G01Y2217470D02*
Y2217864D01*
G01Y2214321D02*
Y2214714D01*
G01Y2208022D02*
Y2208415D01*
G01Y2211171D02*
Y2211565D01*
G01Y2204872D02*
Y2205266D01*
G01Y2201722D02*
Y2202116D01*
G01Y2198573D02*
Y2198966D01*
G01Y2195423D02*
Y2195817D01*
G01Y2192274D02*
Y2192667D01*
G01Y2189124D02*
Y2189518D01*
G01Y2185974D02*
Y2186368D01*
G01Y2182825D02*
Y2183218D01*
G01Y2176525D02*
Y2176919D01*
G01Y2179675D02*
Y2180069D01*
G01Y2173376D02*
Y2173770D01*
G01Y2170226D02*
Y2170620D01*
G01Y2167077D02*
Y2167470D01*
G01Y2163927D02*
Y2164321D01*
G01X1649374D02*
Y2163927D01*
G01Y2170620D02*
Y2170226D01*
G01Y2167470D02*
Y2167077D01*
G01Y2173770D02*
Y2173376D01*
G01Y2176919D02*
Y2176525D01*
G01Y2180069D02*
Y2179675D01*
G01Y2183218D02*
Y2182825D01*
G01Y2189518D02*
Y2189124D01*
G01Y2186368D02*
Y2185974D01*
G01Y2192667D02*
Y2192274D01*
G01Y2195817D02*
Y2195423D01*
G01Y2202116D02*
Y2201722D01*
G01Y2198966D02*
Y2198573D01*
G01Y2205266D02*
Y2204872D01*
G01Y2208415D02*
Y2208022D01*
G01Y2211565D02*
Y2211171D01*
G01Y2214714D02*
Y2214321D01*
G01Y2221014D02*
Y2220620D01*
G01Y2217864D02*
Y2217470D01*
G01Y2224163D02*
Y2223770D01*
G01X1649203Y2224380D02*
Y2224774D01*
G01Y2219380D02*
Y2219774D01*
G01Y2214380D02*
Y2214774D01*
G01Y2204380D02*
Y2204774D01*
G01Y2199380D02*
Y2199774D01*
G01Y2194380D02*
Y2194774D01*
G01Y2189380D02*
Y2189774D01*
G01Y2184380D02*
Y2184774D01*
G01Y2179380D02*
Y2179774D01*
G01Y2174380D02*
Y2174774D01*
G01Y2164380D02*
Y2164774D01*
G01X1648359Y2224380D02*
Y2224774D01*
G01Y2219380D02*
Y2219774D01*
G01Y2214380D02*
Y2214774D01*
G01Y2204380D02*
Y2204774D01*
G01Y2199380D02*
Y2199774D01*
G01Y2194380D02*
Y2194774D01*
G01Y2189380D02*
Y2189774D01*
G01Y2184380D02*
Y2184774D01*
G01Y2179380D02*
Y2179774D01*
G01Y2174380D02*
Y2174774D01*
G01Y2164380D02*
Y2164774D01*
G01X1648197Y2164321D02*
Y2163927D01*
G01Y2170620D02*
Y2170226D01*
G01Y2167470D02*
Y2167077D01*
G01Y2173770D02*
Y2173376D01*
G01Y2176919D02*
Y2176525D01*
G01Y2180069D02*
Y2179675D01*
G01Y2183218D02*
Y2182825D01*
G01Y2189518D02*
Y2189124D01*
G01Y2186368D02*
Y2185974D01*
G01Y2192667D02*
Y2192274D01*
G01Y2195817D02*
Y2195423D01*
G01Y2202116D02*
Y2201722D01*
G01Y2198966D02*
Y2198573D01*
G01Y2205266D02*
Y2204872D01*
G01Y2208415D02*
Y2208022D01*
G01Y2211565D02*
Y2211171D01*
G01Y2214714D02*
Y2214321D01*
G01Y2221014D02*
Y2220620D01*
G01Y2217864D02*
Y2217470D01*
G01Y2224163D02*
Y2223770D01*
G01X1652296Y2169774D02*
X1652374Y2170364D01*
G01X1650328Y2164774D02*
X1650405Y2165364D01*
G01X1650328Y2174774D02*
X1650405Y2175364D01*
G01X1650328Y2179774D02*
X1650405Y2180364D01*
G01X1650328Y2184774D02*
X1650405Y2185364D01*
G01X1650328Y2189774D02*
X1650405Y2190364D01*
G01X1650328Y2194774D02*
X1650405Y2195364D01*
G01X1652296Y2209774D02*
X1652374Y2210364D01*
G01X1650328Y2199774D02*
X1650405Y2200364D01*
G01X1650328Y2204774D02*
X1650405Y2205364D01*
G01X1650328Y2214774D02*
X1650405Y2215364D01*
G01Y2220364D02*
X1650328Y2219774D01*
G01Y2224774D02*
X1650405Y2225364D01*
G01X1649887Y2164321D02*
X1649897Y2164419D01*
X1649925Y2164491D01*
X1649964Y2164518D01*
G01X1649887Y2167470D02*
X1649897Y2167569D01*
X1649925Y2167641D01*
X1649964Y2167667D01*
G01X1649887Y2170620D02*
X1649897Y2170718D01*
X1649925Y2170790D01*
X1649964Y2170817D01*
G01X1649887Y2173770D02*
X1649897Y2173868D01*
X1649925Y2173940D01*
X1649964Y2173966D01*
G01X1649887Y2176919D02*
X1649897Y2177018D01*
X1649925Y2177090D01*
X1649964Y2177116D01*
G01X1649887Y2180069D02*
X1649897Y2180167D01*
X1649925Y2180239D01*
X1649964Y2180266D01*
G01X1649887Y2183218D02*
X1649897Y2183317D01*
X1649925Y2183389D01*
X1649964Y2183415D01*
G01X1649887Y2186368D02*
X1649897Y2186466D01*
X1649925Y2186538D01*
X1649964Y2186565D01*
G01X1649887Y2189518D02*
X1649897Y2189616D01*
X1649925Y2189688D01*
X1649964Y2189714D01*
G01X1649887Y2192667D02*
X1649897Y2192766D01*
X1649925Y2192838D01*
X1649964Y2192864D01*
G01X1649887Y2195817D02*
X1649897Y2195915D01*
X1649925Y2195987D01*
X1649964Y2196014D01*
G01X1649887Y2198966D02*
X1649897Y2199065D01*
X1649925Y2199137D01*
X1649964Y2199163D01*
G01X1649887Y2202116D02*
X1649897Y2202214D01*
X1649925Y2202286D01*
X1649964Y2202313D01*
G01X1649887Y2205266D02*
X1649897Y2205364D01*
X1649925Y2205436D01*
X1649964Y2205463D01*
G01X1649887Y2208415D02*
X1649897Y2208514D01*
X1649925Y2208586D01*
X1649964Y2208612D01*
G01X1649887Y2211565D02*
X1649897Y2211663D01*
X1649925Y2211735D01*
X1649964Y2211762D01*
G01X1649887Y2214714D02*
X1649897Y2214813D01*
X1649925Y2214885D01*
X1649964Y2214911D01*
G01X1649887Y2217864D02*
X1649897Y2217962D01*
X1649925Y2218035D01*
X1649964Y2218061D01*
G01X1649887Y2221014D02*
X1649897Y2221112D01*
X1649925Y2221184D01*
X1649964Y2221211D01*
G01X1649887Y2224163D02*
X1649897Y2224262D01*
X1649925Y2224334D01*
X1649964Y2224360D01*
G01X1654809Y2182825D02*
X1654775Y2182726D01*
X1654687Y2182655D01*
X1654561Y2182628D01*
G01X1654809Y2211171D02*
X1654775Y2211072D01*
X1654687Y2211001D01*
X1654561Y2210974D01*
G01X1649203Y2164774D02*
X1649476Y2165364D01*
G01X1651172Y2169774D02*
X1651444Y2170364D01*
G01X1649203Y2174774D02*
X1649476Y2175364D01*
G01X1649203Y2179774D02*
X1649476Y2180364D01*
G01X1649203Y2184774D02*
X1649476Y2185364D01*
G01X1649203Y2189774D02*
X1649476Y2190364D01*
G01X1649203Y2194774D02*
X1649476Y2195364D01*
G01X1649203Y2199774D02*
X1649476Y2200364D01*
G01X1649203Y2204774D02*
X1649476Y2205364D01*
G01X1651172Y2209774D02*
X1651444Y2210364D01*
G01X1649203Y2214774D02*
X1649476Y2215364D01*
G01X1649203Y2219774D02*
X1649476Y2220364D01*
G01X1649203Y2224774D02*
X1649476Y2225364D01*
G01X1648786Y2165364D02*
X1648359Y2164774D01*
G01X1650754Y2170364D02*
X1650328Y2169774D01*
G01X1648786Y2175364D02*
X1648359Y2174774D01*
G01X1648786Y2180364D02*
X1648359Y2179774D01*
G01X1648786Y2185364D02*
X1648359Y2184774D01*
G01X1648786Y2190364D02*
X1648359Y2189774D01*
G01X1648786Y2195364D02*
X1648359Y2194774D01*
G01X1648786Y2200364D02*
X1648359Y2199774D01*
G01X1648786Y2205364D02*
X1648359Y2204774D01*
G01X1650754Y2210364D02*
X1650328Y2209774D01*
G01X1648786Y2215364D02*
X1648359Y2214774D01*
G01X1648786Y2220364D02*
X1648359Y2219774D01*
G01X1648786Y2225364D02*
X1648359Y2224774D01*
G01X1654531Y2163789D02*
X1654670Y2163985D01*
X1654808Y2164182D01*
X1654945Y2164380D01*
G01X1656500Y2168789D02*
X1656639Y2168985D01*
X1656777Y2169182D01*
X1656914Y2169380D01*
G01X1654531Y2173789D02*
X1654670Y2173985D01*
X1654808Y2174182D01*
X1654945Y2174380D01*
G01X1654531Y2178789D02*
X1654670Y2178985D01*
X1654808Y2179182D01*
X1654945Y2179380D01*
G01X1654531Y2183789D02*
X1654670Y2183985D01*
X1654808Y2184182D01*
X1654945Y2184380D01*
G01X1654531Y2188789D02*
X1654670Y2188985D01*
X1654808Y2189182D01*
X1654945Y2189380D01*
G01X1654531Y2193789D02*
X1654670Y2193985D01*
X1654808Y2194182D01*
X1654945Y2194380D01*
G01X1654531Y2198789D02*
X1654670Y2198985D01*
X1654808Y2199182D01*
X1654945Y2199380D01*
G01X1654531Y2203789D02*
X1654670Y2203985D01*
X1654808Y2204182D01*
X1654945Y2204380D01*
G01X1656500Y2208789D02*
X1656639Y2208985D01*
X1656777Y2209182D01*
X1656914Y2209380D01*
G01X1654531Y2213789D02*
X1654670Y2213985D01*
X1654808Y2214182D01*
X1654945Y2214380D01*
G01X1654531Y2218789D02*
X1654670Y2218985D01*
X1654808Y2219182D01*
X1654945Y2219380D01*
G01X1654531Y2223789D02*
X1654670Y2223985D01*
X1654808Y2224182D01*
X1654945Y2224380D01*
G01X1656827Y2228396D02*
X1658795Y2230364D01*
G01X1662079Y2233317D02*
X1658795D01*
G01X1656827D02*
X1658795Y2231348D01*
G01X1660764Y2233317D02*
Y2240482D01*
G01X1662079Y2233317D02*
X1665488Y2235285D01*
G01Y2237018D02*
X1660764Y2241663D01*
G01X1660768Y2240556D02*
X1665488Y2235914D01*
G01X1660795Y2241632D02*
X1660853Y2241492D01*
X1660858Y2241252D01*
G01X1665488Y2235285D02*
Y2237018D01*
G01X1660822Y2240933D02*
X1660768Y2240556D01*
G01X1660821Y2240931D02*
X1660858Y2241255D01*
X1660852Y2241496D01*
X1660795Y2241632D01*
G01X1713999Y-172119D02*
Y-191056D01*
G01X1777830Y-172119D02*
X2167593D01*
G01X1724871Y178095D02*
X1730646Y181019D01*
G01X1721984Y173711D02*
Y170787D01*
X1725593Y170300D01*
X1724871Y171275D01*
Y172249D01*
X1725593Y173223D01*
X1726315Y173711D01*
X1727758Y174198D01*
X1729202Y173711D01*
X1729924Y173223D01*
X1730646Y172249D01*
Y171275D01*
X1729924Y170300D01*
X1729202Y169813D01*
G01X1730646Y178095D02*
X1724871Y181019D01*
G01X1730646Y187352D02*
X1727037Y187839D01*
X1724871Y188327D01*
X1723428Y188814D01*
X1721984Y189301D01*
Y185403D01*
G01X1732811Y537392D02*
Y226762D01*
G01X1730646Y195148D02*
X1729924Y194173D01*
X1729202Y193686D01*
X1727758Y193199D01*
X1724871D01*
X1723428Y193686D01*
X1722706Y194173D01*
X1721984Y195148D01*
X1722706Y196122D01*
X1723428Y196609D01*
X1724871Y197096D01*
X1727758D01*
X1729202Y196609D01*
X1729924Y196122D01*
X1730646Y195148D01*
G01Y210738D02*
X1729924Y209764D01*
X1729202Y209276D01*
X1727758Y208789D01*
X1724871D01*
X1723428Y209276D01*
X1722706Y209764D01*
X1721984Y210738D01*
X1722706Y211713D01*
X1723428Y212200D01*
X1724871Y212687D01*
X1727758D01*
X1729202Y212200D01*
X1729924Y211713D01*
X1730646Y210738D01*
G01Y218533D02*
X1729924Y217559D01*
X1729202Y217072D01*
X1727758Y216585D01*
X1724871D01*
X1723428Y217072D01*
X1722706Y217559D01*
X1721984Y218533D01*
X1722706Y219508D01*
X1723428Y219995D01*
X1724871Y220482D01*
X1727758D01*
X1729202Y219995D01*
X1729924Y219508D01*
X1730646Y218533D01*
G01Y202943D02*
Y202456D01*
X1729924D01*
X1730646Y202943D01*
G01X1738716Y553140D02*
G03X1726905I-5906J0D01*
G01X1738716D02*
G03X1726905I-5906J0D01*
G01X1740685D02*
G03X1724937I-7874J0D01*
G01X1746590D02*
G03X1719031I-13780J0D01*
G01X1748559D02*
G03X1717063I-15748J0D01*
G01X1748559D02*
G03X1717063I-15748J0D01*
G01X1725781Y546248D02*
G03X1739841I7030J-6888D01*
G01X1717063Y539360D02*
G03X1748559I15748J0D01*
G01X1717063D02*
G03X1748559I15748J0D01*
G01X1723756Y553140D02*
G03I-984J0D01*
G01X1725781Y546248D02*
G03X1726905Y549004I-2813J2754D01*
G01Y550777D02*
Y553140D01*
G01D02*
Y549004D01*
G01X1724937Y553140D02*
Y550777D01*
G01X1719031Y553140D02*
Y550777D01*
G01X1717063Y539360D02*
Y553140D01*
G01Y539360D02*
Y553140D01*
G01X1719031Y550777D02*
X1726905D01*
G01X1743835Y553140D02*
G03I-985J0D01*
G01X1738716Y549004D02*
G03X1739841Y546248I3937J0D01*
G01X1748559Y539360D02*
Y553140D01*
G01Y539360D02*
Y553140D01*
G01X1746590Y550777D02*
Y553140D01*
G01X1740685Y550777D02*
Y553140D01*
G01X1738716Y549004D02*
Y553140D01*
G01D02*
Y550777D01*
G01D02*
X1746590D01*
G01X1736748Y541329D02*
X1787526D01*
G01X1725101Y558159D02*
G03I-984J0D01*
G01X1728775Y561834D02*
G03I-984J0D01*
G01X1742490Y558159D02*
G03I-985J0D01*
G01X1738815Y561834D02*
G03I-984J0D01*
G01X1738714Y958642D02*
G03X1726908I-5903J0D01*
G01X1738716D02*
G03X1726905I-5906J0D01*
G01X1740685D02*
G03X1724937I-7874J0D01*
G01X1746590D02*
G03X1719031I-13780J0D01*
G01X1748559D02*
G03X1717063I-15748J0D01*
G01X1748559D02*
G03X1717063I-15748J0D01*
G01X1748559D02*
G03X1717063I-15748J0D01*
G01X1725782Y951752D02*
G03X1739840I7029J-6890D01*
G01X1717063Y944862D02*
G03X1748559I15748J0D01*
G01X1717063D02*
G03X1748559I15748J0D01*
G01X1717063D02*
G03X1748559I15748J0D01*
G01X1723756Y958642D02*
G03I-984J0D01*
G01X1728775Y967336D02*
G03I-984J0D01*
G01X1725101Y963661D02*
G03I-984J0D01*
G01X1725782Y951752D02*
G03X1726908Y954508I-2811J2757D01*
G01Y958642D02*
Y954508D01*
G01X1726905Y956280D02*
Y958642D01*
G01X1724937D02*
Y956280D01*
G01X1719031Y958642D02*
Y956280D01*
G01X1717063Y944862D02*
Y958642D01*
G01Y944862D02*
Y958642D01*
G01Y944862D02*
Y958642D01*
G01X1719031Y956280D02*
X1726905D01*
G01X1742490Y963661D02*
G03I-985J0D01*
G01X1738815Y967336D02*
G03I-984J0D01*
G01X1743835Y958642D02*
G03I-985J0D01*
G01X1738714Y954508D02*
G03X1739840Y951752I3937J1D01*
G01X1784011Y955689D02*
Y947028D01*
G01X1748559Y944862D02*
Y958642D01*
G01Y944862D02*
Y958642D01*
G01Y944862D02*
Y958642D01*
G01X1746590Y956280D02*
Y958642D01*
G01X1740685Y956280D02*
Y958642D01*
G01X1738716D02*
Y956280D01*
G01X1738714Y954508D02*
Y958642D01*
G01X1738716Y956280D02*
X1746590D01*
G01X1736748Y944862D02*
X1775782D01*
G01X1725782Y1355295D02*
G03X1739840I7029J-6890D01*
G01X1717063Y1348406D02*
G03X1748559I15748J0D01*
G01X1717063D02*
G03X1748559I15748J0D01*
G01X1717063D02*
G03X1748559I15748J0D01*
G01X1725782Y1355295D02*
G03X1726908Y1358051I-2811J2757D01*
G01X1717063Y1348406D02*
Y1362185D01*
G01Y1348406D02*
Y1362185D01*
G01Y1348406D02*
Y1362185D01*
G01X1738714Y1358051D02*
G03X1739840Y1355295I3937J1D01*
G01X1748559Y1348406D02*
Y1362185D01*
G01Y1348406D02*
Y1362185D01*
G01Y1348406D02*
Y1362185D01*
G01X1736748Y1348406D02*
X1789611D01*
G01X1726908Y1362185D02*
Y1358051D01*
G01X1738714Y1362185D02*
G03X1726908I-5903J0D01*
G01X1738716D02*
G03X1726905I-5906J0D01*
G01X1740685D02*
G03X1724937I-7874J0D01*
G01X1746590D02*
G03X1719031I-13780J0D01*
G01X1748559D02*
G03X1717063I-15748J0D01*
G01X1748559D02*
G03X1717063I-15748J0D01*
G01X1748559D02*
G03X1717063I-15748J0D01*
G01X1723756D02*
G03I-984J0D01*
G01X1728775Y1370879D02*
G03I-984J0D01*
G01X1725101Y1367205D02*
G03I-984J0D01*
G01X1719031Y1359823D02*
X1726905D01*
G01D02*
Y1362185D01*
G01X1724937D02*
Y1359823D01*
G01X1719031Y1362185D02*
Y1359823D01*
G01X1738714Y1358051D02*
Y1362185D01*
G01X1742490Y1367205D02*
G03I-985J0D01*
G01X1738815Y1370879D02*
G03I-984J0D01*
G01X1743835Y1362185D02*
G03I-985J0D01*
G01X1738716Y1359823D02*
X1746590D01*
G01D02*
Y1362185D01*
G01X1740685Y1359823D02*
Y1362185D01*
G01X1738716D02*
Y1359823D01*
G01X1729199Y1495991D02*
X1734071D01*
G01X1714583Y1488052D02*
X1713608Y1489495D01*
X1713121Y1491660D01*
X1713608Y1493826D01*
X1714096Y1494548D01*
X1714583Y1495269D01*
X1715557Y1495991D01*
X1716532D01*
X1717506Y1495269D01*
X1718480Y1493826D01*
G01D02*
X1718968Y1491660D01*
X1718480Y1489495D01*
X1717993Y1488773D01*
G01X1731635Y1495991D02*
Y1487330D01*
G01X1717993Y1488773D02*
X1717506Y1488052D01*
X1716532Y1487330D01*
X1715557D01*
X1714583Y1488052D01*
G01X1783766Y1495991D02*
X1788638D01*
G01X1760867Y1491660D02*
X1763303D01*
G01X1776945Y1490217D02*
X1779868D01*
G01X1745764D02*
X1748687D01*
G01X1764765Y1487330D02*
X1760867D01*
Y1495991D01*
X1764765D01*
G01X1753559Y1488052D02*
X1752585Y1489495D01*
X1752097Y1491660D01*
X1752585Y1493826D01*
X1753072Y1494548D01*
X1753559Y1495269D01*
X1754534Y1495991D01*
X1755508D01*
X1756482Y1495269D01*
X1756970Y1494548D01*
G01X1739917Y1491660D02*
X1741379Y1487330D01*
G01X1775971D02*
X1778407Y1495991D01*
X1780843Y1487330D01*
G01X1744789D02*
X1747225Y1495991D01*
X1749661Y1487330D01*
G01X1737481D02*
Y1495991D01*
X1739917D01*
X1740892Y1495269D01*
X1741379Y1494548D01*
Y1493104D01*
X1740892Y1492382D01*
X1739917Y1491660D01*
X1737481D01*
G01X1756970Y1488773D02*
X1756482Y1488052D01*
X1755508Y1487330D01*
X1754534D01*
X1753559Y1488052D01*
G01X1733894Y1763770D02*
G03I-6989J0D01*
G01X1730842D02*
X1752239D01*
G01X1726905Y1767707D02*
Y1807338D01*
G01X1759980Y1770987D02*
X1760955D01*
G01X1783853Y1765935D02*
X1783366D01*
Y1766657D01*
X1783853Y1765935D01*
G01X1775571Y1770987D02*
X1774597Y1771709D01*
X1774109Y1772431D01*
Y1773153D01*
X1774597Y1773875D01*
X1775571Y1774596D01*
X1776545D01*
X1777520Y1773875D01*
X1778007Y1773153D01*
Y1772431D01*
X1777520Y1771709D01*
X1776545Y1770987D01*
G01X1775571Y1765935D02*
X1774597Y1766657D01*
X1773622Y1768100D01*
G01X1778494Y1768822D02*
Y1768100D01*
X1777520Y1766657D01*
G01X1773622Y1768100D02*
Y1768822D01*
X1774597Y1770266D01*
G01X1762904Y1768822D02*
Y1768100D01*
X1761929Y1766657D01*
G01X1768263Y1765935D02*
X1768750Y1769544D01*
X1769237Y1771709D01*
X1769725Y1773153D01*
X1770212Y1774596D01*
X1766314D01*
G01X1774597Y1770266D02*
X1775571Y1770987D01*
X1776545D01*
X1777520Y1770266D01*
X1778494Y1768822D01*
G01X1761929Y1766657D02*
X1760955Y1765935D01*
X1759980D01*
X1759006Y1766657D01*
X1758519Y1767379D01*
G01X1777520Y1766657D02*
X1776545Y1765935D01*
X1775571D01*
G01X1759006Y1773875D02*
X1759980Y1774596D01*
X1760955D01*
X1761929Y1773875D01*
X1762416Y1773153D01*
Y1772431D01*
X1761929Y1771709D01*
X1760955Y1770987D01*
X1761929Y1770266D01*
X1762904Y1768822D01*
G01X1721853Y1825798D02*
X1722575D01*
X1724018Y1824823D01*
G01X1722575Y1820926D02*
X1721853D01*
X1720409Y1821900D01*
G01X1721853Y1813618D02*
X1720409Y1814105D01*
X1719688Y1815567D01*
X1720409Y1817028D01*
X1721853Y1817515D01*
X1723296Y1817028D01*
X1724018Y1816541D01*
X1724740Y1815567D01*
X1724018Y1814592D01*
X1723296Y1814105D01*
X1721853Y1813618D01*
X1718966D01*
X1717522Y1814105D01*
X1716800Y1814592D01*
X1716079Y1815567D01*
X1716800Y1816541D01*
X1717522Y1817028D01*
G01X1724018Y1824823D02*
X1724740Y1823849D01*
Y1822874D01*
G01X1720409Y1821900D02*
X1719688Y1822874D01*
Y1823849D01*
X1720409Y1824823D01*
X1721853Y1825798D01*
G01X1724740Y1831157D02*
Y1830670D01*
X1724018D01*
X1724740Y1831157D01*
G01X1716079Y1840901D02*
Y1837978D01*
X1719688Y1837491D01*
X1718966Y1838465D01*
Y1839439D01*
X1719688Y1840414D01*
X1720409Y1840901D01*
X1721853Y1841388D01*
X1723296Y1840901D01*
X1724018Y1840414D01*
X1724740Y1839439D01*
Y1838465D01*
X1724018Y1837491D01*
X1723296Y1837003D01*
G01X1724740Y1822874D02*
X1724018Y1821900D01*
X1722575Y1820926D01*
G01X1719688Y1822874D02*
X1718966Y1821900D01*
X1718244Y1821413D01*
X1717522D01*
X1716800Y1821900D01*
X1716079Y1822874D01*
Y1823849D01*
X1716800Y1824823D01*
X1717522Y1825310D01*
X1718244D01*
X1718966Y1824823D01*
X1719688Y1823849D01*
G01X1724740Y1846748D02*
X1724018Y1845773D01*
X1723296Y1845286D01*
X1721853Y1844799D01*
X1718966D01*
X1717522Y1845286D01*
X1716800Y1845773D01*
X1716079Y1846748D01*
X1716800Y1847722D01*
X1717522Y1848209D01*
X1718966Y1848697D01*
X1721853D01*
X1723296Y1848209D01*
X1724018Y1847722D01*
X1724740Y1846748D01*
G01X1725782Y2170256D02*
G03X1739840I7029J-6890D01*
G01X1717063Y2163366D02*
G03X1748559I15748J0D01*
G01X1717063D02*
G03X1748559I15748J0D01*
G01X1717063D02*
G03X1748559I15748J0D01*
G01X1738714Y2177146D02*
G03X1726908I-5903J0D01*
G01X1738716D02*
G03X1726905I-5906J0D01*
G01X1740685D02*
G03X1724937I-7874J0D01*
G01X1746590D02*
G03X1719031I-13780J0D01*
G01X1748559D02*
G03X1717063I-15748J0D01*
G01X1748559D02*
G03X1717063I-15748J0D01*
G01X1748559D02*
G03X1717063I-15748J0D01*
G01X1723756D02*
G03I-984J0D01*
G01X1728775Y2185840D02*
G03I-984J0D01*
G01X1725101Y2182165D02*
G03I-984J0D01*
G01X1725782Y2170256D02*
G03X1726908Y2173012I-2811J2757D01*
G01X1719031Y2174783D02*
X1726905D01*
G01X1726908Y2177146D02*
Y2173012D01*
G01X1726905Y2174783D02*
Y2177146D01*
G01X1724937D02*
Y2174783D01*
G01X1719031Y2177146D02*
Y2174783D01*
G01X1717063Y2163366D02*
Y2177146D01*
G01Y2163366D02*
Y2177146D01*
G01Y2163366D02*
Y2177146D01*
G01X1742490Y2182165D02*
G03I-985J0D01*
G01X1738815Y2185840D02*
G03I-984J0D01*
G01X1743835Y2177146D02*
G03I-985J0D01*
G01X1738714Y2173012D02*
G03X1739840Y2170256I3937J1D01*
G01X1738716Y2174783D02*
X1746590D01*
G01X1748559Y2163366D02*
Y2177146D01*
G01Y2163366D02*
Y2177146D01*
G01Y2163366D02*
Y2177146D01*
G01X1746590Y2174783D02*
Y2177146D01*
G01X1740685Y2174783D02*
Y2177146D01*
G01X1738716D02*
Y2174783D01*
G01X1738714Y2173012D02*
Y2177146D01*
G01X1736748Y2163376D02*
X1778758D01*
G01X1713999Y2437400D02*
Y2418463D01*
G01X1856086Y82367D02*
X1857061Y83088D01*
X1858035D01*
X1859009Y82367D01*
X1859497Y81645D01*
G01Y75871D02*
X1859009Y75149D01*
X1858035Y74427D01*
X1857061D01*
X1856086Y75149D01*
X1855112Y76592D01*
G01D02*
X1854625Y78758D01*
X1855112Y80923D01*
X1856086Y82367D01*
G01X1801113Y546381D02*
X1802088Y547825D01*
X1803062Y548546D01*
X1804037D01*
X1805011Y547825D01*
G01X1793805Y546381D02*
X1794293Y547825D01*
X1795754Y548546D01*
X1797216Y547825D01*
X1797703Y546381D01*
X1797216Y544938D01*
X1796729Y544216D01*
X1795754Y543494D01*
X1794780Y544216D01*
X1794293Y544938D01*
X1793805Y546381D01*
Y549268D01*
X1794293Y550712D01*
X1794780Y551434D01*
X1795754Y552155D01*
X1796729Y551434D01*
X1797216Y550712D01*
G01X1805011Y547825D02*
X1805985Y546381D01*
Y545659D01*
X1805498Y544938D01*
X1805011Y544216D01*
X1804037Y543494D01*
X1803062D01*
G01X1802088Y544216D02*
X1801113Y545659D01*
Y546381D01*
G01X1803062Y548546D02*
X1802088Y549268D01*
X1801601Y549990D01*
Y550712D01*
X1802088Y551434D01*
X1803062Y552155D01*
X1804037D01*
X1805011Y551434D01*
X1805498Y550712D01*
Y549990D01*
X1805011Y549268D01*
X1804037Y548546D01*
G01X1803062Y543494D02*
X1802088Y544216D01*
G01X1826935Y543494D02*
X1825961Y544216D01*
X1825474Y544938D01*
X1824986Y546381D01*
Y549268D01*
X1825474Y550712D01*
X1825961Y551434D01*
X1826935Y552155D01*
X1827910Y551434D01*
X1828397Y550712D01*
X1828884Y549268D01*
Y546381D01*
X1828397Y544938D01*
X1827910Y544216D01*
X1826935Y543494D01*
G01X1819140D02*
X1818166Y544216D01*
X1817678Y544938D01*
X1817191Y546381D01*
Y549268D01*
X1817678Y550712D01*
X1818166Y551434D01*
X1819140Y552155D01*
X1820114Y551434D01*
X1820602Y550712D01*
X1821089Y549268D01*
Y546381D01*
X1820602Y544938D01*
X1820114Y544216D01*
X1819140Y543494D01*
G01X1811345D02*
X1810857D01*
Y544216D01*
X1811345Y543494D01*
G01X1792780Y952802D02*
X1793755Y955689D01*
X1789857D01*
G01X1791806Y947028D02*
X1792293Y950637D01*
X1792780Y952802D01*
G01X1799601Y947028D02*
X1798627Y947749D01*
X1798140Y948471D01*
X1797652Y949915D01*
Y952802D01*
X1798140Y954245D01*
X1798627Y954967D01*
X1799601Y955689D01*
X1800576Y954967D01*
X1801063Y954245D01*
X1801550Y952802D01*
Y949915D01*
X1801063Y948471D01*
X1800576Y947749D01*
X1799601Y947028D01*
G01X1822987D02*
X1822013Y947749D01*
X1821525Y948471D01*
X1821038Y949915D01*
Y952802D01*
X1821525Y954245D01*
X1822013Y954967D01*
X1822987Y955689D01*
X1823961Y954967D01*
X1824449Y954245D01*
X1824936Y952802D01*
Y949915D01*
X1824449Y948471D01*
X1823961Y947749D01*
X1822987Y947028D01*
G01X1817141Y955689D02*
X1814217D01*
X1813730Y952080D01*
X1814705Y952802D01*
X1815679D01*
X1816653Y952080D01*
X1817141Y951358D01*
X1817628Y949915D01*
X1817141Y948471D01*
X1816653Y947749D01*
X1815679Y947028D01*
X1814705D01*
X1813730Y947749D01*
X1813243Y948471D01*
G01X1807397Y947028D02*
X1806909D01*
Y947749D01*
X1807397Y947028D01*
G01X1797352Y1354180D02*
X1796378Y1352736D01*
X1795890Y1350571D01*
X1799788D01*
G01X1795890Y1357789D02*
X1796378Y1358510D01*
X1797352Y1359232D01*
X1798326D01*
X1799301Y1358510D01*
X1799788Y1357789D01*
Y1356345D01*
X1799301Y1355623D01*
X1797352Y1354180D01*
G01X1806609Y1356345D02*
X1807583Y1359232D01*
X1803686D01*
G01X1805634Y1350571D02*
X1806122Y1354180D01*
X1806609Y1356345D01*
G01X1812942Y1355623D02*
X1813917D01*
G01X1821225Y1350571D02*
X1820738D01*
Y1351293D01*
X1821225Y1350571D01*
G01X1836816D02*
X1835841Y1351293D01*
X1835354Y1352015D01*
X1834867Y1353458D01*
Y1356345D01*
X1835354Y1357789D01*
X1835841Y1358510D01*
X1836816Y1359232D01*
X1837790Y1358510D01*
X1838277Y1357789D01*
X1838764Y1356345D01*
Y1353458D01*
X1838277Y1352015D01*
X1837790Y1351293D01*
X1836816Y1350571D01*
G01X1829020D02*
X1828046Y1351293D01*
X1827559Y1352015D01*
X1827071Y1353458D01*
Y1356345D01*
X1827559Y1357789D01*
X1828046Y1358510D01*
X1829020Y1359232D01*
X1829995Y1358510D01*
X1830482Y1357789D01*
X1830969Y1356345D01*
Y1353458D01*
X1830482Y1352015D01*
X1829995Y1351293D01*
X1829020Y1350571D01*
G01X1814891Y1351293D02*
X1813917Y1350571D01*
X1812942D01*
X1811968Y1351293D01*
X1811481Y1352015D01*
G01X1811968Y1358510D02*
X1812942Y1359232D01*
X1813917D01*
X1814891Y1358510D01*
X1815379Y1357789D01*
Y1357067D01*
X1814891Y1356345D01*
X1813917Y1355623D01*
X1814891Y1354902D01*
X1815866Y1353458D01*
G01D02*
Y1352736D01*
X1814891Y1351293D01*
G01X1792535Y1490217D02*
X1795459D01*
G01X1799844Y1495991D02*
Y1487330D01*
X1803741D01*
G01X1786202Y1495991D02*
Y1487330D01*
G01X1791561D02*
X1793997Y1495991D01*
X1796433Y1487330D01*
G01X1846615Y1491660D02*
X1849051D01*
G01X1831512Y1490217D02*
X1834435D01*
G01X1850513Y1487330D02*
X1846615D01*
Y1495991D01*
X1850513D01*
G01X1856847Y1491660D02*
X1858308Y1487330D01*
G01X1838820Y1495991D02*
X1840769Y1491660D01*
Y1487330D01*
G01X1854411D02*
Y1495991D01*
X1856847D01*
X1857821Y1495269D01*
X1858308Y1494548D01*
Y1493104D01*
X1857821Y1492382D01*
X1856847Y1491660D01*
X1854411D01*
G01X1840769D02*
X1842718Y1495991D01*
G01X1830537Y1487330D02*
X1832974Y1495991D01*
X1835409Y1487330D01*
G01X1823229Y1495991D02*
Y1487330D01*
X1827127D01*
G01X1807639Y1495991D02*
Y1487330D01*
X1811536D01*
G01X1793598Y1774596D02*
X1790674D01*
X1790187Y1770987D01*
X1791162Y1771709D01*
X1792136D01*
X1793110Y1770987D01*
X1793598Y1770266D01*
X1794085Y1768822D01*
X1793598Y1767379D01*
X1793110Y1766657D01*
X1792136Y1765935D01*
X1791162D01*
X1790187Y1766657D01*
X1789700Y1767379D01*
G01X1799444Y1765935D02*
X1798470Y1766657D01*
X1797982Y1767379D01*
X1797495Y1768822D01*
Y1771709D01*
X1797982Y1773153D01*
X1798470Y1773875D01*
X1799444Y1774596D01*
X1800418Y1773875D01*
X1800906Y1773153D01*
X1801393Y1771709D01*
Y1768822D01*
X1800906Y1767379D01*
X1800418Y1766657D01*
X1799444Y1765935D01*
G01X1802577Y2165541D02*
X1801603Y2166263D01*
X1801116Y2166985D01*
X1800629Y2168428D01*
Y2171315D01*
X1801116Y2172759D01*
X1801603Y2173481D01*
X1802577Y2174203D01*
X1803552Y2173481D01*
X1804039Y2172759D01*
X1804526Y2171315D01*
Y2168428D01*
X1804039Y2166985D01*
X1803552Y2166263D01*
X1802577Y2165541D01*
G01X1794295Y2170594D02*
X1793321Y2171315D01*
X1792833Y2172037D01*
Y2172759D01*
X1793321Y2173481D01*
X1794295Y2174203D01*
X1795269D01*
X1796244Y2173481D01*
X1796731Y2172759D01*
Y2172037D01*
X1796244Y2171315D01*
X1795269Y2170594D01*
G01X1794295Y2165541D02*
X1793321Y2166263D01*
X1792346Y2167707D01*
G01X1797218Y2168428D02*
Y2167707D01*
X1796244Y2166263D01*
G01X1792346Y2167707D02*
Y2168428D01*
X1793321Y2169872D01*
G01X1788448Y2165541D02*
Y2174203D01*
X1785038Y2167707D01*
X1789423D01*
G01X1796244Y2166263D02*
X1795269Y2165541D01*
X1794295D01*
G01X1793321Y2169872D02*
X1794295Y2170594D01*
X1795269D01*
X1796244Y2169872D01*
X1797218Y2168428D01*
G01X1810373Y2165541D02*
X1809885D01*
Y2166263D01*
X1810373Y2165541D01*
G01X1825963D02*
X1824989Y2166263D01*
X1824502Y2166985D01*
X1824014Y2168428D01*
Y2171315D01*
X1824502Y2172759D01*
X1824989Y2173481D01*
X1825963Y2174203D01*
X1826938Y2173481D01*
X1827425Y2172759D01*
X1827912Y2171315D01*
Y2168428D01*
X1827425Y2166985D01*
X1826938Y2166263D01*
X1825963Y2165541D01*
G01X1818168D02*
X1817194Y2166263D01*
X1816706Y2166985D01*
X1816219Y2168428D01*
Y2171315D01*
X1816706Y2172759D01*
X1817194Y2173481D01*
X1818168Y2174203D01*
X1819142Y2173481D01*
X1819629Y2172759D01*
X1820117Y2171315D01*
Y2168428D01*
X1819629Y2166985D01*
X1819142Y2166263D01*
X1818168Y2165541D01*
G01X1873139Y78758D02*
X1874113Y80201D01*
X1875087D01*
X1876062Y78758D01*
Y74427D01*
G01X1870215Y78758D02*
X1871190Y80201D01*
X1872164D01*
X1873139Y78758D01*
Y74427D01*
G01X1867292Y76592D02*
X1866318Y75149D01*
X1865343Y74427D01*
X1864369Y75149D01*
X1863394Y76592D01*
Y78036D01*
X1864369Y79479D01*
X1865343Y80201D01*
X1866318Y79479D01*
X1867292Y78036D01*
Y76592D01*
G01X1870215Y80201D02*
Y74427D01*
G01X1905781Y75871D02*
X1905294Y75149D01*
X1904320Y74427D01*
X1903345Y75149D01*
X1902371Y76592D01*
Y78036D01*
X1903345Y79479D01*
X1904320Y80201D01*
X1905294Y79479D01*
X1905781Y78036D01*
X1902371D01*
G01X1910653Y78758D02*
X1911628Y80201D01*
X1912602D01*
X1913576Y78758D01*
Y74427D01*
G01X1895063Y78758D02*
X1896037Y80201D01*
X1897011D01*
X1897986Y78758D01*
Y74427D01*
G01X1890678Y76592D02*
X1889703Y75149D01*
X1888729Y74427D01*
X1887755Y75149D01*
X1886780Y76592D01*
Y78036D01*
X1887755Y79479D01*
X1888729Y80201D01*
X1889703Y79479D01*
X1890678Y78036D01*
Y76592D01*
G01X1878985Y78036D02*
X1879959Y79479D01*
X1880934Y80201D01*
X1881908Y79479D01*
X1882883Y78036D01*
Y76592D01*
X1881908Y75149D01*
X1880934Y74427D01*
X1879959D01*
X1878985Y76592D01*
G01X1918449Y79479D02*
X1921372D01*
G01X1919910Y74427D02*
Y83088D01*
G01X1910653Y74427D02*
Y80201D01*
G01X1895063Y74427D02*
Y80201D01*
G01X1878985D02*
Y71540D01*
G01X1904071Y910423D02*
Y916575D01*
G01D02*
X1934227D01*
G01Y910423D02*
X1904071D01*
G01Y985472D02*
Y991624D01*
G01Y965787D02*
Y971939D01*
G01Y949793D02*
Y955945D01*
G01Y930108D02*
Y936260D01*
G01Y991624D02*
X1934227D01*
G01Y985472D02*
X1904071D01*
G01Y971939D02*
X1934227D01*
G01Y965787D02*
X1904071D01*
G01Y955945D02*
X1944279D01*
G01X1935483Y949793D02*
X1904071D01*
G01Y936260D02*
X1934227D01*
G01Y930108D02*
X1904071D01*
G01X1921662Y1064213D02*
X1917892Y1062982D01*
G01D02*
X1912866Y1060522D01*
G01X1921662Y1058061D02*
X1914123Y1053140D01*
G01X1912866Y1060522D02*
X1909097Y1056831D01*
G01D02*
X1905327Y1050679D01*
G01X1939253Y1065443D02*
X1927944D01*
G01X1937996Y1059291D02*
X1929201D01*
G01D02*
X1921662Y1058061D01*
G01X1927944Y1065443D02*
X1921662Y1064213D01*
G01X1914123Y1053140D02*
X1911610Y1049449D01*
G01D02*
X1910353Y1043297D01*
G01X1905327Y1050679D02*
X1904071Y1043297D01*
G01Y1005157D02*
Y1011309D01*
G01Y1043297D02*
X1905327Y1035915D01*
G01X1910353Y1043297D02*
X1911610Y1037146D01*
G01X1905327Y1035915D02*
X1909097Y1029764D01*
G01X1911610Y1037146D02*
X1914123Y1033455D01*
G01X1909097Y1029764D02*
X1912866Y1026073D01*
G01X1914123Y1033455D02*
X1921662Y1028533D01*
G01X1912866Y1026073D02*
X1917892Y1023612D01*
G01D02*
X1921662Y1022382D01*
G01D02*
X1927944Y1021151D01*
G01X1921662Y1028533D02*
X1929201Y1027303D01*
G01D02*
X1937996D01*
G01X1927944Y1021151D02*
X1939253D01*
G01X1904071Y1011309D02*
X1944279D01*
G01X1935483Y1005157D02*
X1904071D01*
G01X1910353Y1081437D02*
Y1075285D01*
G01Y1125728D02*
Y1091279D01*
G01X1904071D02*
Y1135571D01*
G01Y1075285D02*
Y1081437D01*
G01X1937996Y1094970D02*
X1910353Y1125728D01*
G01Y1135571D02*
X1941766Y1101122D01*
G01X1904071Y1135571D02*
X1910353D01*
G01Y1091279D02*
X1904071D01*
G01Y1081437D02*
X1910353D01*
G01Y1075285D02*
X1904071D01*
G01X1921662Y1147874D02*
X1934227Y1171250D01*
G01Y1162638D02*
X1925431Y1145413D01*
G01X1904071Y1181092D02*
Y1188474D01*
G01X1925431Y1145413D02*
X1921662Y1147874D01*
G01X1904071Y1188474D02*
X1931714D01*
G01X1963126Y1181092D02*
X1904071D01*
G01Y1230305D02*
X1963126D01*
G01X1931714Y1222923D02*
X1904071D01*
G01D02*
Y1230305D01*
G01X1871463Y1495991D02*
X1872437Y1494548D01*
X1872924Y1492382D01*
Y1490939D01*
X1872437Y1488773D01*
X1871463Y1487330D01*
G01X1862693Y1488052D02*
X1861719Y1489495D01*
G01X1866103Y1494548D02*
X1865616Y1495269D01*
X1864642Y1495991D01*
X1863667D01*
X1862693Y1495269D01*
X1862206Y1494548D01*
Y1493826D01*
X1862693Y1493104D01*
X1863667Y1492382D01*
X1864642Y1491660D01*
X1865616Y1490939D01*
X1866103Y1490217D01*
Y1488773D01*
X1865616Y1488052D01*
X1864642Y1487330D01*
X1863667D01*
X1862693Y1488052D01*
G01X1933668Y-172119D02*
Y-191056D01*
G01X1953040Y76592D02*
X1952066Y75149D01*
X1951091Y74427D01*
X1950117Y75149D01*
X1949142Y76592D01*
Y78036D01*
X1950117Y79479D01*
X1951091Y80201D01*
X1952066Y79479D01*
X1953040Y78036D01*
G01X1943296Y80201D02*
Y74427D01*
G01Y83088D02*
Y82367D01*
G01X1937450Y81645D02*
X1936962Y82367D01*
X1935988Y83088D01*
X1935013D01*
X1934039Y82367D01*
X1933552Y81645D01*
Y80923D01*
X1934039Y80201D01*
X1935013Y79479D01*
X1935988Y78758D01*
X1936962Y78036D01*
X1937450Y77314D01*
Y75871D01*
X1936962Y75149D01*
X1935988Y74427D01*
X1935013D01*
X1934039Y75149D01*
X1933065Y76592D01*
G01X1960348Y75871D02*
X1959861Y75149D01*
X1958886Y74427D01*
X1957912Y75149D01*
X1956938Y76592D01*
Y78036D01*
X1957912Y79479D01*
X1958886Y80201D01*
X1959861Y79479D01*
X1960348Y78036D01*
X1956938D01*
G01X1953040Y83088D02*
Y74427D01*
G01X1940509Y912884D02*
X1934227Y910423D01*
G01Y916575D02*
X1936740Y917805D01*
G01X1943022Y915344D02*
X1940509Y912884D01*
G01X1936740Y917805D02*
X1937996Y919035D01*
G01D02*
X1939253Y921496D01*
G01X1944279Y919035D02*
X1943022Y915344D01*
G01X1944279Y923957D02*
Y919035D01*
G01X1939253Y921496D02*
Y925187D01*
G01X1940509Y968248D02*
X1934227Y965787D01*
G01Y936260D02*
X1936740Y937490D01*
G01X1934227Y971939D02*
X1936740Y973169D01*
G01X1934227Y991624D02*
X1936740Y992854D01*
G01X1943022Y935029D02*
X1939253Y931338D01*
G01X1936740Y937490D02*
X1937996Y938720D01*
G01X1943022Y970709D02*
X1940509Y968248D01*
G01X1936740Y973169D02*
X1937996Y974399D01*
G01X1943022Y990394D02*
X1939253Y986703D01*
G01X1936740Y992854D02*
X1937996Y994085D01*
G01Y938720D02*
X1939253Y941181D01*
G01X1937996Y974399D02*
X1939253Y976860D01*
G01X1944279Y938720D02*
X1943022Y935029D01*
G01X1944279Y974399D02*
X1943022Y970709D01*
G01X1944279Y994085D02*
X1943022Y990394D01*
G01X1944279Y943642D02*
Y938720D01*
G01Y955945D02*
Y949793D01*
G01Y979321D02*
Y974399D01*
G01X1939253Y976860D02*
Y980551D01*
G01Y941181D02*
Y943642D01*
G01X1943022Y983012D02*
X1944279Y979321D01*
G01X1943022Y947333D02*
X1944279Y943642D01*
G01X1939253D02*
X1937996Y947333D01*
G01X1943022Y927648D02*
X1944279Y923957D01*
G01X1939253Y980551D02*
X1937996Y983012D01*
G01X1939253Y925187D02*
X1937996Y927648D01*
G01X1939253Y986703D02*
X1943022Y983012D01*
G01X1937996D02*
X1936740Y984242D01*
G01X1940509Y949793D02*
X1943022Y947333D01*
G01X1937996D02*
X1935483Y949793D01*
G01X1939253Y931338D02*
X1943022Y927648D01*
G01X1937996D02*
X1936740Y928878D01*
G01Y984242D02*
X1934227Y985472D01*
G01X1936740Y928878D02*
X1934227Y930108D01*
G01X1944279Y949793D02*
X1940509D01*
G01X1953074Y1053140D02*
X1945535Y1058061D01*
G01X1954330Y1060522D02*
X1949304Y1062982D01*
G01D02*
X1945535Y1064213D01*
G01D02*
X1939253Y1065443D01*
G01X1945535Y1058061D02*
X1937996Y1059291D01*
G01X1961869Y1050679D02*
X1958100Y1056831D01*
G01D02*
X1954330Y1060522D01*
G01X1937996Y994085D02*
X1939253Y996545D01*
G01X1944279Y999006D02*
Y994085D01*
G01X1945535Y1022382D02*
X1949304Y1023612D01*
G01D02*
X1954330Y1026073D01*
G01X1945535Y1028533D02*
X1953074Y1033455D01*
G01X1944279Y1011309D02*
Y1005157D01*
G01X1939253Y996545D02*
Y999006D01*
G01X1943022Y1002697D02*
X1944279Y999006D01*
G01X1939253D02*
X1937996Y1002697D01*
G01X1940509Y1005157D02*
X1943022Y1002697D01*
G01X1937996D02*
X1935483Y1005157D01*
G01X1944279D02*
X1940509D01*
G01X1937996Y1027303D02*
X1945535Y1028533D01*
G01X1939253Y1021151D02*
X1945535Y1022382D01*
G01X1954330Y1026073D02*
X1958100Y1029764D01*
G01X1953074Y1033455D02*
X1955587Y1037146D01*
G01X1958100Y1029764D02*
X1961869Y1035915D01*
G01X1955587Y1037146D02*
X1956843Y1043297D01*
G01X1961869Y1035915D02*
X1963126Y1043297D01*
G01D02*
X1961869Y1050679D01*
G01X1956843Y1043297D02*
X1955587Y1049449D01*
G01D02*
X1953074Y1053140D01*
G01X1949304Y1098661D02*
X1953074Y1101122D01*
G01X1949304Y1128189D02*
Y1134340D01*
G01X1953074Y1125728D02*
X1949304Y1128189D01*
G01Y1134340D02*
X1954330Y1133110D01*
G01X1941766Y1092510D02*
X1937996Y1094970D01*
G01X1941766Y1101122D02*
X1946791Y1098661D01*
G01Y1091279D02*
X1941766Y1092510D01*
G01X1946791Y1098661D02*
X1949304D01*
G01Y1091279D02*
X1946791D01*
G01X1954330Y1092510D02*
X1949304Y1091279D01*
G01X1959356Y1097431D02*
X1954330Y1092510D01*
G01X1953074Y1101122D02*
X1955587Y1104813D01*
G01X1961869Y1102352D02*
X1959356Y1097431D01*
G01X1955587Y1104813D02*
X1956843Y1110964D01*
G01X1963126Y1109734D02*
X1961869Y1102352D01*
G01Y1123268D02*
X1963126Y1114655D01*
G01X1956843Y1115886D02*
X1955587Y1122037D01*
G01X1963126Y1114655D02*
Y1109734D01*
G01X1956843Y1110964D02*
Y1115886D01*
G01X1959356Y1128189D02*
X1961869Y1123268D01*
G01X1955587Y1122037D02*
X1953074Y1125728D01*
G01X1954330Y1133110D02*
X1959356Y1128189D01*
G01X1946791Y1147874D02*
X1943022Y1145413D01*
G01X1939253Y1222923D02*
Y1188474D01*
G01X1931714D02*
Y1222923D01*
G01X1943022Y1145413D02*
X1934227Y1162638D01*
G01Y1171250D02*
X1946791Y1147874D01*
G01X1939253Y1188474D02*
X1963126D01*
G01D02*
Y1181092D01*
G01Y1222923D02*
X1939253D01*
G01X1963126Y1230305D02*
Y1222923D01*
G01X1933668Y2437400D02*
Y2418463D01*
G01X1979444D02*
X2487318D01*
G01X2152391Y-172119D02*
Y-191056D01*
G01X2167593Y-172119D02*
X2818027D01*
G01X2153337Y2437400D02*
Y2418463D01*
G01X2276402Y177608D02*
X2275680Y178095D01*
X2274958Y179070D01*
Y180044D01*
X2275680Y181019D01*
X2276402Y181506D01*
X2277845D01*
X2278567Y181019D01*
X2279289Y180044D01*
X2280010Y179070D01*
X2281454Y178095D01*
X2283619Y177608D01*
Y181506D01*
G01X2274958Y187352D02*
X2283619D01*
G01Y195148D02*
X2282898Y194173D01*
X2282176Y193686D01*
X2280732Y193199D01*
X2277845D01*
X2276402Y193686D01*
X2275680Y194173D01*
X2274958Y195148D01*
X2275680Y196122D01*
X2276402Y196609D01*
X2277845Y197096D01*
X2280732D01*
X2282176Y196609D01*
X2282898Y196122D01*
X2283619Y195148D01*
G01Y202943D02*
Y202456D01*
X2282898D01*
X2283619Y202943D01*
G01X2280732Y216585D02*
X2279289Y217072D01*
X2278567Y218533D01*
X2279289Y219995D01*
X2280732Y220482D01*
X2282176Y219995D01*
X2282898Y219508D01*
X2283619Y218533D01*
X2282898Y217559D01*
X2282176Y217072D01*
X2280732Y216585D01*
X2277845D01*
X2276402Y217072D01*
X2275680Y217559D01*
X2274958Y218533D01*
X2275680Y219508D01*
X2276402Y219995D01*
G01X2283619Y212200D02*
X2274958D01*
X2281454Y208789D01*
Y213174D01*
G01X2285785Y303809D02*
Y226762D01*
G01Y307746D02*
Y538061D01*
G01X2363355Y307746D02*
X2285785D01*
G01X2282614Y470463D02*
G03I-590J0D01*
G01X2275818Y470650D02*
X2275724Y470539D01*
G01Y470666D02*
X2275818Y470777D01*
G01X2293424Y463179D02*
Y462195D01*
G01Y465738D02*
Y464754D01*
G01Y468297D02*
Y467313D01*
G01Y470856D02*
Y469872D01*
G01X2293342Y463179D02*
Y462195D01*
G01Y465738D02*
Y464754D01*
G01Y468297D02*
Y467313D01*
G01Y470856D02*
Y469872D01*
G01X2291948Y463179D02*
Y462195D01*
G01Y465738D02*
Y464754D01*
G01Y468297D02*
Y467313D01*
G01Y470856D02*
Y469872D01*
G01X2291866Y463179D02*
Y462195D01*
G01Y465738D02*
Y464754D01*
G01Y468297D02*
Y467313D01*
G01Y470856D02*
Y469872D01*
G01X2291669Y460423D02*
Y472628D01*
G01X2280252D02*
Y460423D01*
G01X2280055Y463179D02*
Y462195D01*
G01Y465738D02*
Y464754D01*
G01Y468297D02*
Y467313D01*
G01Y470856D02*
Y469872D01*
G01X2279973Y463179D02*
Y462195D01*
G01Y465738D02*
Y464754D01*
G01Y468297D02*
Y467313D01*
G01Y470856D02*
Y469872D01*
G01X2278579Y463179D02*
Y462195D01*
G01Y465738D02*
Y464754D01*
G01Y468297D02*
Y467313D01*
G01Y470856D02*
Y469872D01*
G01X2278497Y463179D02*
Y462195D01*
G01Y465738D02*
Y464754D01*
G01Y468297D02*
Y467313D01*
G01Y470856D02*
Y469872D01*
G01X2276610Y463179D02*
Y462195D01*
G01Y465738D02*
Y464754D01*
G01Y468297D02*
Y467313D01*
G01Y470856D02*
Y469872D01*
G01X2275911Y470777D02*
Y470029D01*
G01X2275818D02*
Y470650D01*
G01X2275724Y470539D02*
Y470666D01*
G01X2272673Y476565D02*
Y456486D01*
G01X2299248Y476565D02*
X2272673D01*
G01X2291669Y472628D02*
X2280252D01*
G01Y470856D02*
X2276610D01*
G01X2295311D02*
X2291669D01*
G01X2275818Y470777D02*
X2275911D01*
G01Y470029D02*
X2275818D01*
G01X2280252Y469872D02*
X2276610D01*
G01X2295311D02*
X2291669D01*
G01X2280252Y468297D02*
X2276610D01*
G01X2295311D02*
X2291669D01*
G01X2280252Y467313D02*
X2276610D01*
G01X2295311D02*
X2291669D01*
G01X2280252Y465738D02*
X2276610D01*
G01X2295311D02*
X2291669D01*
G01X2280252Y464754D02*
X2276610D01*
G01X2295311D02*
X2291669D01*
G01X2280252Y463179D02*
X2276610D01*
G01X2295311D02*
X2291669D01*
G01X2280252Y462195D02*
X2276610D01*
G01X2295311D02*
X2291669D01*
G01X2280252Y460423D02*
X2291669D01*
G01X2272673Y456486D02*
X2299248D01*
G01X2285785Y538061D02*
X2325312D01*
G01X2288218Y1932347D02*
X2289661Y1931860D01*
X2290383Y1930398D01*
X2289661Y1928936D01*
X2288218Y1928449D01*
X2286774Y1928936D01*
X2286052Y1929424D01*
X2285331Y1930398D01*
X2286052Y1931372D01*
X2286774Y1931860D01*
X2288218Y1932347D01*
X2291105D01*
X2292548Y1931860D01*
X2293270Y1931372D01*
X2293992Y1930398D01*
X2293270Y1929424D01*
X2292548Y1928936D01*
G01X2286052Y1905550D02*
X2285331Y1906525D01*
Y1907499D01*
X2286052Y1908474D01*
X2286774Y1908961D01*
X2287496D01*
X2288218Y1908474D01*
X2288939Y1907499D01*
X2289661Y1908474D01*
G01X2288939Y1892883D02*
X2290383Y1890934D01*
X2291827Y1889960D01*
X2293992Y1889473D01*
Y1893370D01*
G01X2286774Y1889473D02*
X2286052Y1889960D01*
X2285331Y1890934D01*
Y1891909D01*
X2286052Y1892883D01*
X2286774Y1893370D01*
X2288218D01*
X2288939Y1892883D01*
G01X2285331Y1899217D02*
X2293992D01*
G01Y1914807D02*
Y1914320D01*
X2293270D01*
X2293992Y1914807D01*
G01X2288939Y1906525D02*
Y1907499D01*
G01X2293992Y1922602D02*
X2293270Y1921628D01*
X2292548Y1921141D01*
X2291105Y1920654D01*
X2288218D01*
X2286774Y1921141D01*
X2286052Y1921628D01*
X2285331Y1922602D01*
X2286052Y1923577D01*
X2286774Y1924064D01*
X2288218Y1924551D01*
X2291105D01*
X2292548Y1924064D01*
X2293270Y1923577D01*
X2293992Y1922602D01*
G01X2289661Y1908474D02*
X2291105Y1909448D01*
X2291827D01*
X2292548Y1908961D01*
X2293270Y1908474D01*
X2293992Y1907499D01*
Y1906525D01*
X2293270Y1905550D01*
X2292548Y1905063D01*
G01X2282614Y2084636D02*
G03I-590J0D01*
G01X2275911Y2084203D02*
X2275818D01*
G01X2280252Y2084045D02*
X2276610D01*
G01X2295311D02*
X2291669D01*
G01X2280252Y2082470D02*
X2276610D01*
G01X2295311D02*
X2291669D01*
G01X2280252Y2081486D02*
X2276610D01*
G01X2295311D02*
X2291669D01*
G01X2280252Y2079911D02*
X2276610D01*
G01X2295311D02*
X2291669D01*
G01X2280252Y2078927D02*
X2276610D01*
G01X2295311D02*
X2291669D01*
G01X2280252Y2077352D02*
X2276610D01*
G01X2295311D02*
X2291669D01*
G01X2280252Y2076368D02*
X2276610D01*
G01X2295311D02*
X2291669D01*
G01X2280252Y2074596D02*
X2291669D01*
G01X2272673Y2070659D02*
X2299248D01*
G01X2293424Y2077352D02*
Y2076368D01*
G01Y2079911D02*
Y2078927D01*
G01Y2082470D02*
Y2081486D01*
G01Y2085029D02*
Y2084045D01*
G01X2293342Y2077352D02*
Y2076368D01*
G01Y2079911D02*
Y2078927D01*
G01Y2082470D02*
Y2081486D01*
G01Y2085029D02*
Y2084045D01*
G01X2291948Y2077352D02*
Y2076368D01*
G01Y2079911D02*
Y2078927D01*
G01Y2082470D02*
Y2081486D01*
G01Y2085029D02*
Y2084045D01*
G01X2291866Y2077352D02*
Y2076368D01*
G01Y2079911D02*
Y2078927D01*
G01Y2082470D02*
Y2081486D01*
G01Y2085029D02*
Y2084045D01*
G01X2291669Y2074596D02*
Y2086801D01*
G01X2280252D02*
Y2074596D01*
G01X2280055Y2077352D02*
Y2076368D01*
G01Y2079911D02*
Y2078927D01*
G01Y2082470D02*
Y2081486D01*
G01Y2085029D02*
Y2084045D01*
G01X2279973Y2077352D02*
Y2076368D01*
G01Y2079911D02*
Y2078927D01*
G01Y2082470D02*
Y2081486D01*
G01Y2085029D02*
Y2084045D01*
G01X2278579Y2077352D02*
Y2076368D01*
G01Y2079911D02*
Y2078927D01*
G01Y2082470D02*
Y2081486D01*
G01Y2085029D02*
Y2084045D01*
G01X2278497Y2077352D02*
Y2076368D01*
G01Y2079911D02*
Y2078927D01*
G01Y2082470D02*
Y2081486D01*
G01Y2085029D02*
Y2084045D01*
G01X2276610Y2077352D02*
Y2076368D01*
G01Y2079911D02*
Y2078927D01*
G01Y2082470D02*
Y2081486D01*
G01Y2085029D02*
Y2084045D01*
G01X2275911Y2084951D02*
Y2084203D01*
G01X2275818D02*
Y2084823D01*
G01X2275724Y2084712D02*
Y2084839D01*
G01X2272673Y2090738D02*
Y2070659D01*
G01X2275818Y2084823D02*
X2275724Y2084712D01*
G01Y2084839D02*
X2275818Y2084951D01*
G01X2291669Y2086801D02*
X2280252D01*
G01Y2085029D02*
X2276610D01*
G01X2295311D02*
X2291669D01*
G01X2275818Y2084951D02*
X2275911D01*
G01X2299248Y2090738D02*
X2272673D01*
G01X2315929Y185403D02*
X2315207Y185891D01*
X2314486Y186865D01*
Y187839D01*
X2315207Y188814D01*
X2315929Y189301D01*
X2317373D01*
X2318095Y188814D01*
X2319538Y186865D01*
G01X2315929Y177608D02*
X2315207Y178095D01*
X2314486Y179070D01*
Y180044D01*
X2315207Y181019D01*
X2315929Y181506D01*
X2317373D01*
X2318095Y181019D01*
X2319538Y179070D01*
G01X2356137Y186865D02*
Y187839D01*
G01X2353250Y185891D02*
X2352528Y186865D01*
Y187839D01*
X2353250Y188814D01*
X2353972Y189301D01*
X2354694D01*
X2355415Y188814D01*
X2356137Y187839D01*
X2356859Y188814D01*
X2358303Y189788D01*
G01X2357581Y179070D02*
X2359024Y178095D01*
X2361190Y177608D01*
Y181506D01*
G01X2353972Y177608D02*
X2353250Y178095D01*
X2352528Y179070D01*
Y180044D01*
X2353250Y181019D01*
X2353972Y181506D01*
X2355415D01*
X2356137Y181019D01*
X2357581Y179070D01*
G01X2319538Y186865D02*
X2320982Y185891D01*
X2323147Y185403D01*
Y189301D01*
G01X2319538Y179070D02*
X2320982Y178095D01*
X2323147Y177608D01*
Y181506D01*
G01X2358303Y189788D02*
X2359024D01*
X2359746Y189301D01*
X2360468Y188814D01*
X2361190Y187839D01*
Y186865D01*
X2360468Y185891D01*
X2359746Y185403D01*
G01X2323147Y195148D02*
X2322425Y194173D01*
X2321703Y193686D01*
X2320260Y193199D01*
X2317373D01*
X2315929Y193686D01*
X2315207Y194173D01*
X2314486Y195148D01*
X2315207Y196122D01*
X2315929Y196609D01*
X2317373Y197096D01*
X2320260D01*
X2321703Y196609D01*
X2322425Y196122D01*
X2323147Y195148D01*
G01Y218533D02*
X2322425Y217559D01*
X2321703Y217072D01*
X2320260Y216585D01*
X2317373D01*
X2315929Y217072D01*
X2315207Y217559D01*
X2314486Y218533D01*
X2315207Y219508D01*
X2315929Y219995D01*
X2317373Y220482D01*
X2320260D01*
X2321703Y219995D01*
X2322425Y219508D01*
X2323147Y218533D01*
G01X2314486Y212687D02*
Y209764D01*
X2318095Y209276D01*
X2317373Y210251D01*
Y211225D01*
X2318095Y212200D01*
X2318816Y212687D01*
X2320260Y213174D01*
X2321703Y212687D01*
X2322425Y212200D01*
X2323147Y211225D01*
Y210251D01*
X2322425Y209276D01*
X2321703Y208789D01*
G01X2361190Y195148D02*
X2360468Y194173D01*
X2359746Y193686D01*
X2358303Y193199D01*
X2355415D01*
X2353972Y193686D01*
X2353250Y194173D01*
X2352528Y195148D01*
X2353250Y196122D01*
X2353972Y196609D01*
X2355415Y197096D01*
X2358303D01*
X2359746Y196609D01*
X2360468Y196122D01*
X2361190Y195148D01*
G01Y202943D02*
Y202456D01*
X2360468D01*
X2361190Y202943D01*
G01X2323147D02*
Y202456D01*
X2322425D01*
X2323147Y202943D01*
G01X2358303Y216585D02*
X2356859Y217072D01*
X2356137Y218533D01*
X2356859Y219995D01*
X2358303Y220482D01*
X2359746Y219995D01*
X2360468Y219508D01*
X2361190Y218533D01*
X2360468Y217559D01*
X2359746Y217072D01*
X2358303Y216585D01*
X2355415D01*
X2353972Y217072D01*
X2353250Y217559D01*
X2352528Y218533D01*
X2353250Y219508D01*
X2353972Y219995D01*
G01X2352528Y210738D02*
X2361190D01*
G01X2325312Y434242D02*
Y226762D01*
G01X2363355Y303809D02*
Y226762D01*
G01Y438179D02*
Y307746D01*
G01X2308017Y386998D02*
X2306341Y386342D01*
G01Y387982D02*
X2307012Y388310D01*
G01X2304666Y403074D02*
X2303661Y402746D01*
G01X2303996Y401106D02*
X2305671Y401762D01*
G01X2306341Y393232D02*
X2307012Y393560D01*
G01X2300980Y410292D02*
X2302321Y410948D01*
G01X2305671Y403730D02*
X2304666Y403074D01*
G01X2305671Y401762D02*
X2307012Y402746D01*
G01X2300980Y412260D02*
X2299640Y411276D01*
G01X2308687Y387654D02*
X2308017Y386998D01*
G01X2307012Y388310D02*
X2307347Y388638D01*
G01X2308687Y392903D02*
X2307682Y391919D01*
G01X2307012Y393560D02*
X2307347Y393888D01*
G01X2306341Y404714D02*
X2305671Y403730D01*
G01X2300310Y409308D02*
X2300980Y410292D01*
G01X2307012Y402746D02*
X2308017Y404386D01*
G01X2299640Y411276D02*
X2298635Y409636D01*
G01X2307347Y388638D02*
X2307682Y389295D01*
G01X2307347Y393888D02*
X2307682Y394544D01*
G01X2309022Y388638D02*
X2308687Y387654D01*
G01X2309022Y393888D02*
X2308687Y392903D01*
G01X2306676Y406027D02*
X2306341Y404714D01*
G01X2299975Y407995D02*
X2300310Y409308D01*
G01X2308017Y404386D02*
X2308352Y406027D01*
G01X2298635Y409636D02*
X2298300Y407995D01*
G01X2314048Y401762D02*
Y412917D01*
G01X2312373Y411276D02*
Y401762D01*
G01X2309022Y389951D02*
Y388638D01*
G01Y395200D02*
Y393888D01*
G01Y398481D02*
Y396840D01*
G01X2308352Y406027D02*
Y407995D01*
G01X2307682Y394544D02*
Y395200D01*
G01Y389295D02*
Y390279D01*
G01X2306676Y407995D02*
Y406027D01*
G01X2305336Y412917D02*
Y410620D01*
G01X2302321Y410948D02*
Y412917D01*
G01X2299975Y406027D02*
Y407995D01*
G01X2298300Y396840D02*
Y398481D01*
G01Y391591D02*
Y393232D01*
G01Y386342D02*
Y387982D01*
G01Y407995D02*
Y406027D01*
G01X2308352Y407995D02*
X2308017Y409636D01*
G01X2298300Y406027D02*
X2298635Y404386D01*
G01X2306341Y409308D02*
X2306676Y407995D01*
G01X2300310Y404714D02*
X2299975Y406027D01*
G01X2308687Y396184D02*
X2309022Y395200D01*
G01X2307682D02*
X2307347Y396184D01*
G01X2308687Y390935D02*
X2309022Y389951D01*
G01X2307682Y390279D02*
X2307347Y390935D01*
G01X2308017Y409636D02*
X2307012Y411276D01*
G01X2298635Y404386D02*
X2299640Y402746D01*
G01X2300980Y403730D02*
X2300310Y404714D01*
G01X2305336Y410620D02*
X2306341Y409308D01*
G01X2308017Y396840D02*
X2308687Y396184D01*
G01X2307347D02*
X2306676Y396840D01*
G01X2307682Y391919D02*
X2308687Y390935D01*
G01X2307347D02*
X2307012Y391263D01*
G01X2299640Y402746D02*
X2300980Y401762D01*
G01X2301986Y403074D02*
X2300980Y403730D01*
G01X2307012Y391263D02*
X2306341Y391591D01*
G01X2300980Y401762D02*
X2302656Y401106D01*
G01X2302991Y402746D02*
X2301986Y403074D01*
G01X2307012Y411276D02*
X2312373D01*
G01X2303661Y402746D02*
X2302991D01*
G01X2312373Y401762D02*
X2314048D01*
G01X2302656Y401106D02*
X2303996D01*
G01X2298300Y398481D02*
X2309022D01*
G01X2306676Y396840D02*
X2298300D01*
G01X2309022D02*
X2308017D01*
G01X2298300Y393232D02*
X2306341D01*
G01Y391591D02*
X2298300D01*
G01Y387982D02*
X2306341D01*
G01Y386342D02*
X2298300D01*
G01X2354937Y483317D02*
G03X2355331Y483711I0J394D01*
G01Y481348D02*
G03X2354937Y481742I-394J0D01*
G01X2366669Y606348D02*
Y473711D01*
G01X2360449Y490325D02*
Y473907D01*
G01X2358480D02*
Y606151D01*
G01X2356433Y608966D02*
Y471092D01*
G01X2355331Y471545D02*
Y608514D01*
G01X2354491Y481840D02*
Y482628D01*
G01X2354464Y481840D02*
Y482628D01*
G01X2354088Y481840D02*
Y482628D01*
G01X2353874Y483317D02*
Y481742D01*
G01X2352890Y484104D02*
Y480955D01*
G01X2351905Y484104D02*
Y480955D01*
G01X2351315Y471545D02*
Y608514D01*
G01X2350921Y483317D02*
Y481742D01*
G01X2350860Y474124D02*
Y605738D01*
G01X2350726Y482628D02*
Y481840D01*
G01X2348743Y482628D02*
Y481840D01*
G01X2347772Y483317D02*
Y481742D01*
G01X2347091Y481840D02*
Y482628D01*
G01X2345363Y481840D02*
Y479478D01*
G01Y484990D02*
Y482628D01*
G01X2344424Y481840D02*
Y482628D01*
G01X2344277Y481840D02*
Y482628D01*
G01X2342685Y481840D02*
Y482628D01*
G01X2342330Y608514D02*
Y471545D01*
G01X2341743Y482628D02*
Y481840D01*
G01X2338907Y482628D02*
Y481840D01*
G01X2338718D02*
Y482628D01*
G01X2336945Y481840D02*
Y482628D01*
G01X2325312Y538061D02*
Y438179D01*
G01X2352890Y484104D02*
X2351905D01*
G01X2352890Y483907D02*
X2351905D01*
G01X2352890Y483514D02*
X2351905D01*
G01X2347772Y483317D02*
X2354937D01*
G01X2344277Y482628D02*
X2336945D01*
G01X2356433D02*
X2344424D01*
G01Y481840D02*
X2356433D01*
G01X2336945D02*
X2344277D01*
G01X2347772Y481742D02*
X2354937D01*
G01X2352890Y481545D02*
X2351905D01*
G01X2302321Y412917D02*
X2300980Y412260D01*
G01X2309692Y416197D02*
X2308687Y415541D01*
G01X2302991Y416197D02*
X2306341Y422431D01*
G01Y420134D02*
X2303996Y415541D01*
G01X2314048Y427024D02*
Y425056D01*
G01Y438179D02*
Y436211D01*
G01X2307682D02*
Y427024D01*
G01X2305671D02*
Y436211D01*
G01X2299248Y476565D02*
Y456486D01*
G01X2298300Y436211D02*
Y438179D01*
G01Y425056D02*
Y427024D01*
G01X2295311Y463179D02*
Y462195D01*
G01Y465738D02*
Y464754D01*
G01Y468297D02*
Y467313D01*
G01Y470856D02*
Y469872D01*
G01X2308687Y415541D02*
X2306341Y420134D01*
G01Y422431D02*
X2309692Y416197D01*
G01X2303996Y415541D02*
X2302991Y416197D01*
G01X2298300Y438179D02*
X2314048D01*
G01X2305671Y436211D02*
X2298300D01*
G01X2314048D02*
X2307682D01*
G01Y427024D02*
X2314048D01*
G01X2298300D02*
X2305671D01*
G01X2314048Y425056D02*
X2298300D01*
G01X2314048Y412917D02*
X2305336D01*
G01X2359976Y434636D02*
G03Y433455I0J-590D01*
G01Y437392D02*
G03Y436211I0J-590D01*
G01X2358992Y451840D02*
G03Y454990I0J1575D01*
G01X2360210Y466831D02*
G03X2357996Y461663I6938J-6030D01*
G01X2361096Y466905D02*
G03X2358881Y461663I7142J-6107D01*
G01X2354937Y478317D02*
G03X2355331Y478711I0J394D01*
G01Y476348D02*
G03X2354937Y476742I-394J0D01*
G01X2353677Y433455D02*
G03Y434636I0J591D01*
G01Y436211D02*
G03Y437392I0J591D01*
G01X2354661Y454990D02*
G03Y451840I0J-1575D01*
G01X2353739Y463385D02*
G03X2353197Y462401I1276J-1344D01*
G01X2349740Y465226D02*
G03I-2165J0D01*
G01X2350921D02*
G03I-3346J0D01*
G01X2351079D02*
G03I-3504J0D01*
G01X2353234Y463929D02*
G03X2352164Y462106I2809J-2874D01*
G01X2352102Y465226D02*
G03I-4527J0D01*
G01X2339762Y466831D02*
G03X2337548Y461663I6938J-6031D01*
G01X2340648Y466905D02*
G03X2338433Y461663I7142J-6107D01*
G01X2360621Y475627D02*
X2360359Y475541D01*
G01X2358879Y475882D02*
X2358617Y475797D01*
G01X2358356Y477930D02*
X2358094Y477844D01*
G01X2360098Y478186D02*
X2359750Y478015D01*
G01X2358182Y477333D02*
X2358356Y477418D01*
G01X2360708Y475115D02*
X2361144Y475371D01*
G01X2353528Y466590D02*
X2353815Y466768D01*
X2354169Y466831D01*
G01X2349338Y465272D02*
X2349621Y465449D01*
X2349808Y465715D01*
X2349875Y466016D01*
X2349811Y466317D01*
X2349625Y466584D01*
X2349340Y466765D01*
X2348990Y466831D01*
G01X2348641Y466766D02*
X2348358Y466588D01*
X2348171Y466323D01*
X2348104Y466021D01*
X2348168Y465720D01*
X2348354Y465454D01*
X2348639Y465272D01*
X2348990Y465207D01*
G01X2344171Y465272D02*
X2344454Y465449D01*
X2344641Y465715D01*
X2344708Y466016D01*
X2344644Y466317D01*
X2344458Y466584D01*
X2344173Y466765D01*
X2343822Y466831D01*
G01X2343473Y466766D02*
X2343191Y466588D01*
X2343004Y466323D01*
X2342937Y466021D01*
X2343001Y465720D01*
X2343186Y465454D01*
X2343472Y465272D01*
X2343822Y465207D01*
G01X2359924Y477503D02*
X2360185Y477674D01*
G01X2349413Y462479D02*
X2349773Y462715D01*
X2350011Y463065D01*
X2350097Y463469D01*
X2350014Y463871D01*
X2349778Y464224D01*
X2349414Y464464D01*
X2348990Y464548D01*
G01X2348567Y464464D02*
X2348206Y464228D01*
X2347968Y463878D01*
X2347882Y463475D01*
X2347965Y463072D01*
X2348201Y462720D01*
X2348565Y462480D01*
X2348990Y462395D01*
G01X2344245Y462479D02*
X2344606Y462715D01*
X2344844Y463065D01*
X2344929Y463469D01*
X2344847Y463871D01*
X2344610Y464224D01*
X2344247Y464464D01*
X2343822Y464548D01*
G01X2343399Y464464D02*
X2343039Y464228D01*
X2342800Y463878D01*
X2342715Y463475D01*
X2342798Y463072D01*
X2343034Y462720D01*
X2343397Y462480D01*
X2343822Y462395D01*
G01X2358094Y477844D02*
X2357746Y477588D01*
G01X2355368Y464932D02*
X2353739Y463385D01*
G01X2347792Y464920D02*
X2347340Y464480D01*
X2347070Y463944D01*
X2347000Y463374D01*
X2347141Y462809D01*
X2347488Y462285D01*
X2348015Y461891D01*
X2348658Y461688D01*
X2349337Y461691D01*
X2349977Y461898D01*
X2350500Y462295D01*
X2350842Y462818D01*
X2350980Y463379D01*
X2350908Y463947D01*
X2350638Y464481D01*
G01X2342624Y464920D02*
X2342173Y464480D01*
X2341903Y463944D01*
X2341832Y463374D01*
X2341974Y462809D01*
X2342321Y462285D01*
X2342848Y461891D01*
X2343491Y461688D01*
X2344170Y461691D01*
X2344810Y461898D01*
X2345333Y462295D01*
X2345674Y462818D01*
X2345812Y463379D01*
X2345741Y463947D01*
X2345470Y464481D01*
G01X2354796Y465457D02*
X2353234Y463929D01*
G01X2360882Y475882D02*
X2360621Y475627D01*
G01X2359053Y475371D02*
X2359401Y475712D01*
G01X2359750Y478015D02*
X2359401Y477674D01*
G01X2358007Y477162D02*
X2358182Y477333D01*
G01X2353688Y434256D02*
X2353594Y434145D01*
G01Y434272D02*
X2353688Y434384D01*
G01X2350187Y464920D02*
X2350510Y465339D01*
X2350673Y465823D01*
X2350651Y466327D01*
X2350448Y466804D01*
X2350081Y467208D01*
X2349575Y467475D01*
X2348984Y467569D01*
X2348395Y467472D01*
X2347892Y467203D01*
X2347528Y466799D01*
X2347327Y466321D01*
X2347308Y465816D01*
X2347471Y465335D01*
X2347792Y464920D01*
G01X2345020D02*
X2345343Y465339D01*
X2345505Y465823D01*
X2345484Y466327D01*
X2345281Y466804D01*
X2344914Y467208D01*
X2344408Y467475D01*
X2343816Y467569D01*
X2343227Y467472D01*
X2342725Y467203D01*
X2342361Y466799D01*
X2342159Y466321D01*
X2342140Y465816D01*
X2342304Y465335D01*
X2342624Y464920D01*
G01X2357746Y477588D02*
X2357485Y477247D01*
G01X2355368Y464932D02*
X2355705Y465393D01*
X2355850Y465912D01*
X2355790Y466430D01*
X2355539Y466913D01*
X2355102Y467308D01*
X2354529Y467531D01*
X2353895Y467550D01*
X2353310Y467364D01*
X2352855Y467011D01*
X2352563Y466540D01*
X2352459Y466019D01*
G01X2353528Y466590D02*
X2353338Y466323D01*
G01X2354796Y465457D02*
X2354979Y465722D01*
X2355043Y466020D01*
X2354978Y466317D01*
G01X2359053Y476138D02*
X2358879Y475882D01*
G01X2359750Y477247D02*
X2359924Y477503D01*
G01X2361144Y475371D02*
X2361405Y475797D01*
G01X2359401Y475712D02*
X2359575Y476053D01*
G01X2359401Y477674D02*
X2359227Y477333D01*
G01X2359140Y476394D02*
X2359053Y476138D01*
G01X2357920Y476906D02*
X2358007Y477162D01*
G01X2360969Y476224D02*
X2360882Y475882D01*
G01X2359575Y476053D02*
X2359663Y476394D01*
G01Y476906D02*
X2359750Y477247D01*
G01X2353338Y466323D02*
X2353271Y466019D01*
G01X2361405Y475797D02*
X2361492Y476224D01*
G01X2359227Y477333D02*
X2359140Y476906D01*
G01X2357485Y477247D02*
X2357398Y476821D01*
G01X2352459Y466019D02*
X2352546Y466495D01*
X2352793Y466938D01*
X2353182Y467290D01*
X2353688Y467509D01*
X2354266Y467566D01*
X2354829Y467444D01*
X2355305Y467161D01*
X2355644Y466757D01*
X2355824Y466300D01*
X2355839Y465819D01*
X2355682Y465349D01*
X2355368Y464932D01*
G01X2365016Y447510D02*
Y473907D01*
G01X2364701Y474498D02*
Y472726D01*
G01X2362732Y460443D02*
Y468789D01*
G01X2361551Y433159D02*
Y435128D01*
G01Y437687D02*
Y435718D01*
G01X2361492Y476224D02*
Y476906D01*
G01Y479892D02*
Y479380D01*
G01X2361096Y466904D02*
Y467569D01*
G01X2360969Y476906D02*
Y476224D01*
G01X2360359Y475541D02*
Y475029D01*
G01X2359976Y434636D02*
Y436211D01*
G01Y437392D02*
Y437982D01*
G01Y432864D02*
Y433455D01*
G01X2359663Y476394D02*
Y476906D01*
G01X2359617Y452628D02*
Y454203D01*
G01X2359583D02*
Y452628D01*
G01X2359558Y454203D02*
Y452628D01*
G01X2359140Y476906D02*
Y476394D01*
G01X2358992Y432864D02*
Y437982D01*
G01X2358795D02*
Y432864D01*
G01Y466191D02*
Y462411D01*
G01Y470600D02*
Y468159D01*
G01X2358401Y435718D02*
Y437687D01*
G01Y435128D02*
Y433159D01*
G01X2358356Y477418D02*
Y477930D01*
G01X2358235Y452628D02*
Y454203D01*
G01X2357920Y476394D02*
Y476906D01*
G01X2357865Y454203D02*
Y452628D01*
G01X2357398Y479380D02*
Y479892D01*
G01Y476821D02*
Y476394D01*
G01X2357257Y467569D02*
Y466831D01*
G01X2356076Y461663D02*
Y462401D01*
G01X2355788Y452628D02*
Y454203D01*
G01X2355418D02*
Y452628D01*
G01X2355252Y435718D02*
Y437687D01*
G01Y435128D02*
Y433159D01*
G01X2354878Y476565D02*
Y478533D01*
G01X2354858Y437982D02*
Y432864D01*
G01X2354661D02*
Y437982D01*
G01X2354491Y478691D02*
Y479478D01*
G01X2354464Y478691D02*
Y479478D01*
G01X2354095Y452628D02*
Y454203D01*
G01X2354088Y478691D02*
Y479478D01*
G01X2354071Y452628D02*
Y454203D01*
G01X2354036D02*
Y452628D01*
G01X2353874Y478317D02*
Y476742D01*
G01X2353781Y434384D02*
Y433636D01*
G01X2353688D02*
Y434256D01*
G01X2353677Y433455D02*
Y432864D01*
G01Y436211D02*
Y434636D01*
G01Y437982D02*
Y437392D01*
G01X2353594Y434145D02*
Y434272D01*
G01X2353271Y465871D02*
Y466019D01*
G01X2352890Y471092D02*
Y468789D01*
G01Y479104D02*
Y475955D01*
G01X2352459Y466019D02*
Y465871D01*
G01X2352164Y462106D02*
Y461663D01*
G01X2352102Y433159D02*
Y435128D01*
G01Y437687D02*
Y435718D01*
G01X2351905Y479104D02*
Y475955D01*
G01X2350921Y478317D02*
Y476742D01*
G01X2350726Y479478D02*
Y478691D01*
G01X2350333Y471151D02*
Y471092D01*
G01X2349694Y468789D02*
Y471545D01*
G01X2348743Y479478D02*
Y478691D01*
G01X2348638Y460443D02*
Y447510D01*
G01X2347772Y478317D02*
Y476742D01*
G01X2347091Y478691D02*
Y479478D01*
G01X2346807Y478533D02*
Y476565D01*
G01X2345363Y478691D02*
Y476112D01*
G01X2344424Y478691D02*
Y479478D01*
G01X2344277Y478691D02*
Y479478D01*
G01X2342685Y478691D02*
Y479478D01*
G01X2341820Y468789D02*
Y471545D01*
G01X2341743Y479478D02*
Y478691D01*
G01X2340648Y466904D02*
Y467569D01*
G01X2338907Y479478D02*
Y478691D01*
G01X2338718D02*
Y479478D01*
G01X2336945Y478691D02*
Y479478D01*
G01X2336809Y467569D02*
Y466831D01*
G01X2335966Y474124D02*
Y471545D01*
G01X2335491Y474124D02*
Y468789D01*
G01X2335173Y474124D02*
Y460443D01*
G01X2361492Y476906D02*
X2361405Y477333D01*
G01X2360882Y477247D02*
X2360969Y476906D01*
G01X2357398Y476394D02*
X2357485Y476053D01*
G01X2358007Y476138D02*
X2357920Y476394D01*
G01X2361405Y477333D02*
X2361231Y477674D01*
G01X2357485Y476053D02*
X2357659Y475712D01*
G01X2350078Y471545D02*
X2350333Y471151D01*
G01X2360708Y477503D02*
X2360882Y477247D01*
G01X2358182Y475882D02*
X2358007Y476138D01*
G01X2354796Y466581D02*
X2354978Y466316D01*
X2355043Y466017D01*
X2354978Y465721D01*
G01X2347792Y464920D02*
X2347469Y465339D01*
X2347307Y465823D01*
X2347328Y466327D01*
X2347531Y466804D01*
X2347898Y467208D01*
X2348404Y467475D01*
X2348995Y467569D01*
X2349585Y467472D01*
X2350087Y467203D01*
X2350451Y466799D01*
X2350652Y466321D01*
X2350672Y465816D01*
X2350508Y465335D01*
X2350187Y464920D01*
G01X2342624D02*
X2342302Y465339D01*
X2342139Y465823D01*
X2342161Y466327D01*
X2342364Y466804D01*
X2342731Y467208D01*
X2343237Y467475D01*
X2343828Y467569D01*
X2344417Y467472D01*
X2344920Y467203D01*
X2345284Y466799D01*
X2345485Y466321D01*
X2345504Y465816D01*
X2345340Y465335D01*
X2345020Y464920D01*
G01X2361231Y477674D02*
X2360882Y478015D01*
G01X2357659Y475712D02*
X2358007Y475371D01*
G01X2350187Y464920D02*
X2350639Y464480D01*
X2350909Y463944D01*
X2350979Y463374D01*
X2350838Y462809D01*
X2350491Y462285D01*
X2349964Y461891D01*
X2349321Y461688D01*
X2348642Y461691D01*
X2348002Y461898D01*
X2347479Y462295D01*
X2347137Y462818D01*
X2346999Y463379D01*
X2347071Y463947D01*
X2347341Y464481D01*
G01X2345020Y464920D02*
X2345472Y464480D01*
X2345742Y463944D01*
X2345812Y463374D01*
X2345670Y462809D01*
X2345324Y462285D01*
X2344796Y461891D01*
X2344154Y461688D01*
X2343474Y461691D01*
X2342834Y461898D01*
X2342312Y462295D01*
X2341970Y462818D01*
X2341832Y463379D01*
X2341904Y463947D01*
X2342174Y464481D01*
G01X2358094Y479380D02*
X2358704Y478868D01*
G01X2358007D02*
X2357398Y479380D01*
G01X2360447Y477674D02*
X2360708Y477503D01*
G01X2349413Y464464D02*
X2349773Y464228D01*
X2350011Y463878D01*
X2350097Y463475D01*
X2350014Y463072D01*
X2349778Y462720D01*
X2349414Y462480D01*
X2348990Y462395D01*
G01X2348567Y462479D02*
X2348206Y462715D01*
X2347968Y463065D01*
X2347882Y463469D01*
X2347965Y463871D01*
X2348201Y464224D01*
X2348565Y464464D01*
X2348990Y464548D01*
G01X2344245Y464464D02*
X2344606Y464228D01*
X2344844Y463878D01*
X2344929Y463475D01*
X2344847Y463072D01*
X2344610Y462720D01*
X2344247Y462480D01*
X2343822Y462395D01*
G01X2343399Y462479D02*
X2343039Y462715D01*
X2342800Y463065D01*
X2342715Y463469D01*
X2342798Y463871D01*
X2343034Y464224D01*
X2343397Y464464D01*
X2343822Y464548D01*
G01X2354516Y466762D02*
X2354796Y466581D01*
G01X2349338Y466766D02*
X2349621Y466588D01*
X2349808Y466323D01*
X2349875Y466021D01*
X2349811Y465720D01*
X2349625Y465454D01*
X2349340Y465272D01*
X2348990Y465207D01*
G01X2348641Y465272D02*
X2348358Y465449D01*
X2348171Y465715D01*
X2348104Y466016D01*
X2348168Y466317D01*
X2348354Y466584D01*
X2348639Y466765D01*
X2348990Y466831D01*
G01X2344171Y466766D02*
X2344454Y466588D01*
X2344641Y466323D01*
X2344708Y466021D01*
X2344644Y465720D01*
X2344458Y465454D01*
X2344173Y465272D01*
X2343822Y465207D01*
G01X2343473Y465272D02*
X2343191Y465449D01*
X2343004Y465715D01*
X2342937Y466016D01*
X2343001Y466317D01*
X2343186Y466584D01*
X2343472Y466765D01*
X2343822Y466831D01*
G01X2360882Y478015D02*
X2360534Y478186D01*
G01X2358443Y475797D02*
X2358182Y475882D01*
G01X2358007Y475371D02*
X2358356Y475285D01*
G01X2354169Y466831D02*
X2354517Y466761D01*
G01X2352890Y481151D02*
X2351905D01*
G01X2352890Y480955D02*
X2351905D01*
G01X2357398Y479892D02*
X2361492D01*
G01X2344277Y479478D02*
X2336945D01*
G01X2356433D02*
X2344424D01*
G01X2361492Y479380D02*
X2358094D01*
G01X2352890Y479104D02*
X2351905D01*
G01X2352890Y478907D02*
X2351905D01*
G01X2358704Y478868D02*
X2358007D01*
G01X2344424Y478691D02*
X2356433D01*
G01X2336945D02*
X2344277D01*
G01X2354878Y478533D02*
X2346807D01*
G01X2352890Y478514D02*
X2351905D01*
G01X2347772Y478317D02*
X2354937D01*
G01X2360534Y478186D02*
X2360098D01*
G01X2360185Y477674D02*
X2360447D01*
G01X2347772Y476742D02*
X2354937D01*
G01X2346807Y476565D02*
X2354878D01*
G01X2352890Y476545D02*
X2351905D01*
G01X2352890Y476151D02*
X2351905D01*
G01X2351315Y476112D02*
X2342330D01*
G01X2352890Y475955D02*
X2351905D01*
G01X2358617Y475797D02*
X2358443D01*
G01X2358356Y475285D02*
X2358704D01*
G01X2355331Y474498D02*
X2364701D01*
G01X2355331Y474124D02*
X2335173D01*
G01X2365016Y473907D02*
X2358480D01*
G01X2385173Y473711D02*
X2366669D01*
G01X2356433Y473317D02*
X2387142D01*
G01X2355331Y472726D02*
X2364701D01*
G01X2335966Y471545D02*
X2356433D01*
G01X2350333Y471151D02*
X2356433D01*
G01Y471092D02*
X2350333D01*
G01X2358795Y470600D02*
X2335173D01*
G01X2385173Y468789D02*
X2335173D01*
G01Y468159D02*
X2358795D01*
G01X2340648Y467569D02*
X2336809D01*
G01X2361096D02*
X2357257D01*
G01Y466831D02*
X2360210D01*
G01X2336809D02*
X2339762D01*
G01X2358795Y466191D02*
X2335173D01*
G01X2352459Y465871D02*
X2353271D01*
G01X2358795Y462411D02*
X2335173D01*
G01X2356076Y462401D02*
X2353197D01*
G01X2357995Y461663D02*
X2358881D01*
G01X2352164D02*
X2356076D01*
G01X2337548D02*
X2338433D01*
G01X2362732Y461624D02*
X2389110D01*
G01Y460443D02*
X2335173D01*
G01X2365016Y457687D02*
X2348638D01*
G01X2354661Y454990D02*
X2358992D01*
G01X2354036Y454203D02*
X2359617D01*
G01Y452628D02*
X2354036D01*
G01X2358992Y451840D02*
X2354661D01*
G01X2365016Y447510D02*
X2348638D01*
G01X2325312Y438179D02*
X2363355D01*
G01X2359976Y437982D02*
X2353677D01*
G01X2358401Y437687D02*
X2361551D01*
G01X2355252D02*
X2352102D01*
G01Y435718D02*
X2355252D01*
G01X2361551D02*
X2358401D01*
G01X2352102Y435128D02*
X2355252D01*
G01X2361551D02*
X2358401D01*
G01X2353688Y434384D02*
X2353781D01*
G01Y433636D02*
X2353688D01*
G01X2358401Y433159D02*
X2361551D01*
G01X2355252D02*
X2352102D01*
G01X2353677Y432864D02*
X2359976D01*
G01X2358704Y475285D02*
X2359053Y475371D01*
G01X2360359Y475029D02*
X2360708Y475115D01*
G01X2354491Y484990D02*
Y485777D01*
G01X2354464Y484990D02*
Y485777D01*
G01X2354088Y484990D02*
Y485777D01*
G01X2350726D02*
Y484990D01*
G01X2348743Y485777D02*
Y484990D01*
G01X2347091D02*
Y485777D01*
G01X2344424Y484990D02*
Y485777D01*
G01X2344277Y484990D02*
Y485777D01*
G01X2342685Y484990D02*
Y485777D01*
G01X2341743D02*
Y484990D01*
G01X2338907Y485777D02*
Y484990D01*
G01X2338718D02*
Y485777D01*
G01X2336945Y484990D02*
Y485777D01*
G01X2344424Y484990D02*
X2356433D01*
G01X2336945D02*
X2344277D01*
G01X2354937Y553317D02*
G03X2355331Y553711I0J394D01*
G01Y551348D02*
G03X2354937Y551742I-394J0D01*
G01Y538317D02*
G03X2355331Y538711I0J394D01*
G01Y536348D02*
G03X2354937Y536742I-394J0D01*
G01Y543317D02*
G03X2355331Y543711I0J394D01*
G01Y541348D02*
G03X2354937Y541742I-394J0D01*
G01X2355331Y556348D02*
G03X2354937Y556742I-394J0D01*
G01Y533317D02*
G03X2355331Y533711I0J394D01*
G01Y531348D02*
G03X2354937Y531742I-394J0D01*
G01Y508317D02*
G03X2355331Y508711I0J394D01*
G01Y506348D02*
G03X2354937Y506742I-394J0D01*
G01Y503317D02*
G03X2355331Y503711I0J394D01*
G01Y501348D02*
G03X2354937Y501742I-394J0D01*
G01Y498317D02*
G03X2355331Y498711I0J394D01*
G01Y496348D02*
G03X2354937Y496742I-394J0D01*
G01Y488317D02*
G03X2355331Y488711I0J394D01*
G01Y486348D02*
G03X2354937Y486742I-394J0D01*
G01Y493317D02*
G03X2355331Y493711I0J394D01*
G01Y491348D02*
G03X2354937Y491742I-394J0D01*
G01X2360449Y550837D02*
Y567372D01*
G01Y532136D02*
Y548474D01*
G01Y507923D02*
Y492687D01*
G01Y529774D02*
Y510285D01*
G01X2355252Y529675D02*
Y510384D01*
G01X2354937D02*
Y529675D01*
G01X2354858Y549104D02*
Y545955D01*
G01X2354491Y551132D02*
Y551919D01*
G01Y554281D02*
Y555069D01*
G01Y547982D02*
Y548770D01*
G01Y541683D02*
Y542470D01*
G01Y544833D02*
Y545620D01*
G01Y538533D02*
Y539321D01*
G01Y532234D02*
Y533022D01*
G01Y535384D02*
Y536171D01*
G01Y529085D02*
Y529872D01*
G01Y522785D02*
Y523573D01*
G01Y525935D02*
Y526722D01*
G01Y519636D02*
Y520423D01*
G01Y513337D02*
Y514124D01*
G01Y516486D02*
Y517274D01*
G01Y510187D02*
Y510974D01*
G01Y503888D02*
Y504675D01*
G01Y507037D02*
Y507825D01*
G01Y500738D02*
Y501525D01*
G01Y494439D02*
Y495226D01*
G01Y497588D02*
Y498376D01*
G01Y491289D02*
Y492077D01*
G01Y488140D02*
Y488927D01*
G01X2354464Y551132D02*
Y551919D01*
G01Y554281D02*
Y555069D01*
G01Y547982D02*
Y548770D01*
G01Y541683D02*
Y542470D01*
G01Y544833D02*
Y545620D01*
G01Y538533D02*
Y539321D01*
G01Y532234D02*
Y533022D01*
G01Y535384D02*
Y536171D01*
G01Y529085D02*
Y529872D01*
G01Y522785D02*
Y523573D01*
G01Y525935D02*
Y526722D01*
G01Y519636D02*
Y520423D01*
G01Y513337D02*
Y514124D01*
G01Y516486D02*
Y517274D01*
G01Y510187D02*
Y510974D01*
G01Y503888D02*
Y504675D01*
G01Y507037D02*
Y507825D01*
G01Y500738D02*
Y501525D01*
G01Y494439D02*
Y495226D01*
G01Y497588D02*
Y498376D01*
G01Y491289D02*
Y492077D01*
G01Y488140D02*
Y488927D01*
G01X2354424Y513337D02*
Y510974D01*
G01Y516486D02*
Y514124D01*
G01Y519636D02*
Y517274D01*
G01Y522785D02*
Y520423D01*
G01Y525935D02*
Y523573D01*
G01Y529085D02*
Y526722D01*
G01X2354149Y529675D02*
Y510384D01*
G01X2354088Y551132D02*
Y551919D01*
G01Y554281D02*
Y555069D01*
G01Y547982D02*
Y548770D01*
G01Y541683D02*
Y542470D01*
G01Y544833D02*
Y545620D01*
G01Y538533D02*
Y539321D01*
G01Y532234D02*
Y533022D01*
G01Y535384D02*
Y536171D01*
G01Y529085D02*
Y529872D01*
G01Y522785D02*
Y523573D01*
G01Y525935D02*
Y526722D01*
G01Y519636D02*
Y520423D01*
G01Y513337D02*
Y514124D01*
G01Y516486D02*
Y517274D01*
G01Y510187D02*
Y510974D01*
G01Y503888D02*
Y504675D01*
G01Y507037D02*
Y507825D01*
G01Y500738D02*
Y501525D01*
G01Y494439D02*
Y495226D01*
G01Y497588D02*
Y498376D01*
G01Y491289D02*
Y492077D01*
G01Y488140D02*
Y488927D01*
G01X2353874Y488317D02*
Y486742D01*
G01Y493317D02*
Y491742D01*
G01Y498317D02*
Y496742D01*
G01Y503317D02*
Y501742D01*
G01Y508317D02*
Y506742D01*
G01Y533317D02*
Y531742D01*
G01Y538317D02*
Y536742D01*
G01Y543317D02*
Y541742D01*
G01Y549104D02*
Y545955D01*
G01Y553317D02*
Y551742D01*
G01Y558317D02*
Y556742D01*
G01X2353649Y529675D02*
Y510384D01*
G01X2353439Y510876D02*
Y529183D01*
G01X2352890Y489104D02*
Y485955D01*
G01Y494104D02*
Y490955D01*
G01Y499104D02*
Y495955D01*
G01Y504104D02*
Y500955D01*
G01Y509104D02*
Y505955D01*
G01Y534104D02*
Y530955D01*
G01Y539104D02*
Y535955D01*
G01Y544104D02*
Y540955D01*
G01Y548317D02*
Y546742D01*
G01Y554104D02*
Y550955D01*
G01Y559104D02*
Y555955D01*
G01X2352732Y510384D02*
Y529675D01*
G01X2352455Y512746D02*
Y511565D01*
G01Y515896D02*
Y514714D01*
G01Y519045D02*
Y517864D01*
G01Y522195D02*
Y521014D01*
G01Y525344D02*
Y524163D01*
G01Y528494D02*
Y527313D01*
G01X2351905Y489104D02*
Y485955D01*
G01Y494104D02*
Y490955D01*
G01Y499104D02*
Y495955D01*
G01Y504104D02*
Y500955D01*
G01Y509104D02*
Y505955D01*
G01Y534104D02*
Y530955D01*
G01Y539104D02*
Y535955D01*
G01Y544104D02*
Y540955D01*
G01Y554104D02*
Y550955D01*
G01Y559104D02*
Y555955D01*
G01X2350921Y488317D02*
Y486742D01*
G01Y493317D02*
Y491742D01*
G01Y498317D02*
Y496742D01*
G01Y503317D02*
Y501742D01*
G01Y508317D02*
Y506742D01*
G01Y533317D02*
Y531742D01*
G01Y538317D02*
Y536742D01*
G01Y543317D02*
Y541742D01*
G01Y553317D02*
Y551742D01*
G01Y558317D02*
Y556742D01*
G01X2350726Y488927D02*
Y488140D01*
G01Y492077D02*
Y491289D01*
G01Y495226D02*
Y494439D01*
G01Y498376D02*
Y497588D01*
G01Y501525D02*
Y500738D01*
G01Y504675D02*
Y503888D01*
G01Y507825D02*
Y507037D01*
G01Y510974D02*
Y510187D01*
G01Y514124D02*
Y513337D01*
G01Y517274D02*
Y516486D01*
G01Y520423D02*
Y519636D01*
G01Y523573D02*
Y522785D01*
G01Y526722D02*
Y525935D01*
G01Y529872D02*
Y529085D01*
G01Y533022D02*
Y532234D01*
G01Y536171D02*
Y535384D01*
G01Y539321D02*
Y538533D01*
G01Y542470D02*
Y541683D01*
G01Y545620D02*
Y544833D01*
G01Y548770D02*
Y547982D01*
G01Y551919D02*
Y551132D01*
G01Y555069D02*
Y554281D01*
G01X2349740Y548317D02*
Y546742D01*
G01X2349376Y510384D02*
Y529675D01*
G01X2349324Y516407D02*
Y514203D01*
G01Y525856D02*
Y523651D01*
G01X2349305Y512746D02*
Y511565D01*
G01Y515896D02*
Y514714D01*
G01Y519045D02*
Y517864D01*
G01Y522195D02*
Y521014D01*
G01Y525344D02*
Y524163D01*
G01Y528494D02*
Y527313D01*
G01X2348898Y525856D02*
Y529675D01*
G01Y516407D02*
Y523651D01*
G01Y510384D02*
Y514203D01*
G01X2348743Y488927D02*
Y488140D01*
G01Y492077D02*
Y491289D01*
G01Y495226D02*
Y494439D01*
G01Y498376D02*
Y497588D01*
G01Y501525D02*
Y500738D01*
G01Y504675D02*
Y503888D01*
G01Y507825D02*
Y507037D01*
G01Y510974D02*
Y510187D01*
G01Y514124D02*
Y513337D01*
G01Y517274D02*
Y516486D01*
G01Y520423D02*
Y519636D01*
G01Y523573D02*
Y522785D01*
G01Y526722D02*
Y525935D01*
G01Y529872D02*
Y529085D01*
G01Y533022D02*
Y532234D01*
G01Y536171D02*
Y535384D01*
G01Y539321D02*
Y538533D01*
G01Y542470D02*
Y541683D01*
G01Y545620D02*
Y544833D01*
G01Y548770D02*
Y547982D01*
G01Y551919D02*
Y551132D01*
G01Y555069D02*
Y554281D01*
G01X2347772Y488317D02*
Y486742D01*
G01Y493317D02*
Y491742D01*
G01Y498317D02*
Y496742D01*
G01Y503317D02*
Y501742D01*
G01Y508317D02*
Y506742D01*
G01Y533317D02*
Y531742D01*
G01Y538317D02*
Y536742D01*
G01Y543317D02*
Y541742D01*
G01Y553317D02*
Y551742D01*
G01Y558317D02*
Y556742D01*
G01X2347441Y523651D02*
Y525856D01*
G01Y514203D02*
Y516407D01*
G01X2347091Y551132D02*
Y551919D01*
G01Y554281D02*
Y555069D01*
G01Y547982D02*
Y548770D01*
G01Y541683D02*
Y542470D01*
G01Y544833D02*
Y545620D01*
G01Y538533D02*
Y539321D01*
G01Y532234D02*
Y533022D01*
G01Y535384D02*
Y536171D01*
G01Y529085D02*
Y529872D01*
G01Y522785D02*
Y523573D01*
G01Y525935D02*
Y526722D01*
G01Y519636D02*
Y520423D01*
G01Y513337D02*
Y514124D01*
G01Y516486D02*
Y517274D01*
G01Y510187D02*
Y510974D01*
G01Y503888D02*
Y504675D01*
G01Y507037D02*
Y507825D01*
G01Y500738D02*
Y501525D01*
G01Y494439D02*
Y495226D01*
G01Y497588D02*
Y498376D01*
G01Y491289D02*
Y492077D01*
G01Y488140D02*
Y488927D01*
G01X2345363Y488140D02*
Y485777D01*
G01Y491289D02*
Y488927D01*
G01Y494439D02*
Y492077D01*
G01Y497588D02*
Y495226D01*
G01Y500738D02*
Y498376D01*
G01Y503888D02*
Y501525D01*
G01Y507037D02*
Y504675D01*
G01Y510187D02*
Y507825D01*
G01Y513337D02*
Y510974D01*
G01Y516486D02*
Y514124D01*
G01Y519636D02*
Y517274D01*
G01Y522785D02*
Y520423D01*
G01Y525935D02*
Y523573D01*
G01Y529085D02*
Y526722D01*
G01Y532234D02*
Y529872D01*
G01Y535384D02*
Y533022D01*
G01Y538533D02*
Y536171D01*
G01Y541683D02*
Y539321D01*
G01Y544833D02*
Y542470D01*
G01Y547982D02*
Y545620D01*
G01Y551132D02*
Y548770D01*
G01Y554281D02*
Y551919D01*
G01Y557431D02*
Y555069D01*
G01X2344424Y551132D02*
Y551919D01*
G01Y554281D02*
Y555069D01*
G01Y547982D02*
Y548770D01*
G01Y541683D02*
Y542470D01*
G01Y544833D02*
Y545620D01*
G01Y538533D02*
Y539321D01*
G01Y532234D02*
Y533022D01*
G01Y535384D02*
Y536171D01*
G01Y529085D02*
Y529872D01*
G01Y522785D02*
Y523573D01*
G01Y525935D02*
Y526722D01*
G01Y519636D02*
Y520423D01*
G01Y513337D02*
Y514124D01*
G01Y516486D02*
Y517274D01*
G01Y510187D02*
Y510974D01*
G01Y503888D02*
Y504675D01*
G01Y507037D02*
Y507825D01*
G01Y500738D02*
Y501525D01*
G01Y494439D02*
Y495226D01*
G01Y497588D02*
Y498376D01*
G01Y491289D02*
Y492077D01*
G01Y488140D02*
Y488927D01*
G01X2344277Y551132D02*
Y551919D01*
G01Y554281D02*
Y555069D01*
G01Y547982D02*
Y548770D01*
G01Y541683D02*
Y542470D01*
G01Y544833D02*
Y545620D01*
G01Y538533D02*
Y539321D01*
G01Y532234D02*
Y533022D01*
G01Y535384D02*
Y536171D01*
G01Y529085D02*
Y529872D01*
G01Y522785D02*
Y523573D01*
G01Y525935D02*
Y526722D01*
G01Y519636D02*
Y520423D01*
G01Y513337D02*
Y514124D01*
G01Y516486D02*
Y517274D01*
G01Y510187D02*
Y510974D01*
G01Y503888D02*
Y504675D01*
G01Y507037D02*
Y507825D01*
G01Y500738D02*
Y501525D01*
G01Y494439D02*
Y495226D01*
G01Y497588D02*
Y498376D01*
G01Y491289D02*
Y492077D01*
G01Y488140D02*
Y488927D01*
G01X2342685Y551132D02*
Y551919D01*
G01Y554281D02*
Y555069D01*
G01Y547982D02*
Y548770D01*
G01Y541683D02*
Y542470D01*
G01Y544833D02*
Y545620D01*
G01Y538533D02*
Y539321D01*
G01Y532234D02*
Y533022D01*
G01Y535384D02*
Y536171D01*
G01Y529085D02*
Y529872D01*
G01Y522785D02*
Y523573D01*
G01Y525935D02*
Y526722D01*
G01Y519636D02*
Y520423D01*
G01Y513337D02*
Y514124D01*
G01Y516486D02*
Y517274D01*
G01Y510187D02*
Y510974D01*
G01Y503888D02*
Y504675D01*
G01Y507037D02*
Y507825D01*
G01Y500738D02*
Y501525D01*
G01Y494439D02*
Y495226D01*
G01Y497588D02*
Y498376D01*
G01Y491289D02*
Y492077D01*
G01Y488140D02*
Y488927D01*
G01X2341743D02*
Y488140D01*
G01Y492077D02*
Y491289D01*
G01Y495226D02*
Y494439D01*
G01Y498376D02*
Y497588D01*
G01Y501525D02*
Y500738D01*
G01Y504675D02*
Y503888D01*
G01Y507825D02*
Y507037D01*
G01Y510974D02*
Y510187D01*
G01Y514124D02*
Y513337D01*
G01Y517274D02*
Y516486D01*
G01Y520423D02*
Y519636D01*
G01Y523573D02*
Y522785D01*
G01Y526722D02*
Y525935D01*
G01Y529872D02*
Y529085D01*
G01Y533022D02*
Y532234D01*
G01Y536171D02*
Y535384D01*
G01Y539321D02*
Y538533D01*
G01Y542470D02*
Y541683D01*
G01Y545620D02*
Y544833D01*
G01Y548770D02*
Y547982D01*
G01Y551919D02*
Y551132D01*
G01Y555069D02*
Y554281D01*
G01X2338907Y488927D02*
Y488140D01*
G01Y492077D02*
Y491289D01*
G01Y495226D02*
Y494439D01*
G01Y498376D02*
Y497588D01*
G01Y501525D02*
Y500738D01*
G01Y504675D02*
Y503888D01*
G01Y507825D02*
Y507037D01*
G01Y510974D02*
Y510187D01*
G01Y514124D02*
Y513337D01*
G01Y517274D02*
Y516486D01*
G01Y520423D02*
Y519636D01*
G01Y523573D02*
Y522785D01*
G01Y526722D02*
Y525935D01*
G01Y529872D02*
Y529085D01*
G01Y533022D02*
Y532234D01*
G01Y536171D02*
Y535384D01*
G01Y539321D02*
Y538533D01*
G01Y542470D02*
Y541683D01*
G01Y545620D02*
Y544833D01*
G01Y548770D02*
Y547982D01*
G01Y551919D02*
Y551132D01*
G01Y555069D02*
Y554281D01*
G01X2338718Y551132D02*
Y551919D01*
G01Y554281D02*
Y555069D01*
G01Y547982D02*
Y548770D01*
G01Y541683D02*
Y542470D01*
G01Y544833D02*
Y545620D01*
G01Y538533D02*
Y539321D01*
G01Y532234D02*
Y533022D01*
G01Y535384D02*
Y536171D01*
G01Y529085D02*
Y529872D01*
G01Y522785D02*
Y523573D01*
G01Y525935D02*
Y526722D01*
G01Y519636D02*
Y520423D01*
G01Y513337D02*
Y514124D01*
G01Y516486D02*
Y517274D01*
G01Y510187D02*
Y510974D01*
G01Y503888D02*
Y504675D01*
G01Y507037D02*
Y507825D01*
G01Y500738D02*
Y501525D01*
G01Y494439D02*
Y495226D01*
G01Y497588D02*
Y498376D01*
G01Y491289D02*
Y492077D01*
G01Y488140D02*
Y488927D01*
G01X2336945Y551132D02*
Y551919D01*
G01Y554281D02*
Y555069D01*
G01Y547982D02*
Y548770D01*
G01Y541683D02*
Y542470D01*
G01Y544833D02*
Y545620D01*
G01Y538533D02*
Y539321D01*
G01Y532234D02*
Y533022D01*
G01Y535384D02*
Y536171D01*
G01Y529085D02*
Y529872D01*
G01Y522785D02*
Y523573D01*
G01Y525935D02*
Y526722D01*
G01Y519636D02*
Y520423D01*
G01Y513337D02*
Y514124D01*
G01Y516486D02*
Y517274D01*
G01Y510187D02*
Y510974D01*
G01Y503888D02*
Y504675D01*
G01Y507037D02*
Y507825D01*
G01Y500738D02*
Y501525D01*
G01Y494439D02*
Y495226D01*
G01Y497588D02*
Y498376D01*
G01Y491289D02*
Y492077D01*
G01Y488140D02*
Y488927D01*
G01X2347772Y556742D02*
X2354937D01*
G01X2352890Y556545D02*
X2351905D01*
G01X2352890Y556151D02*
X2351905D01*
G01X2352890Y555955D02*
X2351905D01*
G01X2344277Y555069D02*
X2336945D01*
G01X2356433D02*
X2344424D01*
G01Y554281D02*
X2356433D01*
G01X2336945D02*
X2344277D01*
G01X2352890Y554104D02*
X2351905D01*
G01X2352890Y553907D02*
X2351905D01*
G01X2352890Y553514D02*
X2351905D01*
G01X2347772Y553317D02*
X2354937D01*
G01X2344277Y551919D02*
X2336945D01*
G01X2356433D02*
X2344424D01*
G01X2347772Y551742D02*
X2354937D01*
G01X2352890Y551545D02*
X2351905D01*
G01X2352890Y551151D02*
X2351905D01*
G01X2344424Y551132D02*
X2356433D01*
G01X2336945D02*
X2344277D01*
G01X2352890Y550955D02*
X2351905D01*
G01X2385173Y550837D02*
X2358480D01*
G01X2355331Y549734D02*
X2356433D01*
G01X2354858Y549104D02*
X2353874D01*
G01X2354858Y548907D02*
X2353874D01*
G01X2344277Y548770D02*
X2336945D01*
G01X2356433D02*
X2344424D01*
G01X2354858Y548514D02*
X2353874D01*
G01X2385173Y548474D02*
X2358480D01*
G01X2355331Y548317D02*
X2349740D01*
G01X2344424Y547982D02*
X2356433D01*
G01X2336945D02*
X2344277D01*
G01X2355331Y546742D02*
X2349740D01*
G01X2354858Y546545D02*
X2353874D01*
G01X2354858Y546151D02*
X2353874D01*
G01X2354858Y545955D02*
X2353874D01*
G01X2344277Y545620D02*
X2336945D01*
G01X2356433D02*
X2344424D01*
G01X2356433Y545325D02*
X2355331D01*
G01X2344424Y544833D02*
X2356433D01*
G01X2336945D02*
X2344277D01*
G01X2352890Y544104D02*
X2351905D01*
G01X2352890Y543907D02*
X2351905D01*
G01X2352890Y543514D02*
X2351905D01*
G01X2347772Y543317D02*
X2354937D01*
G01X2344277Y542470D02*
X2336945D01*
G01X2356433D02*
X2344424D01*
G01X2347772Y541742D02*
X2354937D01*
G01X2344424Y541683D02*
X2356433D01*
G01X2336945D02*
X2344277D01*
G01X2352890Y541545D02*
X2351905D01*
G01X2352890Y541151D02*
X2351905D01*
G01X2352890Y540955D02*
X2351905D01*
G01X2344277Y539321D02*
X2336945D01*
G01X2356433D02*
X2344424D01*
G01X2352890Y539104D02*
X2351905D01*
G01X2352890Y538907D02*
X2351905D01*
G01X2344424Y538533D02*
X2356433D01*
G01X2336945D02*
X2344277D01*
G01X2352890Y538514D02*
X2351905D01*
G01X2347772Y538317D02*
X2354937D01*
G01X2347772Y536742D02*
X2354937D01*
G01X2352890Y536545D02*
X2351905D01*
G01X2386130Y536230D02*
X2366669D01*
G01X2344277Y536171D02*
X2336945D01*
G01X2356433D02*
X2344424D01*
G01X2352890Y536151D02*
X2351905D01*
G01X2352890Y535955D02*
X2351905D01*
G01X2344424Y535384D02*
X2356433D01*
G01X2336945D02*
X2344277D01*
G01X2352890Y534104D02*
X2351905D01*
G01X2352890Y533907D02*
X2351905D01*
G01X2352890Y533514D02*
X2351905D01*
G01X2347772Y533317D02*
X2354937D01*
G01X2344277Y533022D02*
X2336945D01*
G01X2356433D02*
X2344424D01*
G01Y532234D02*
X2356433D01*
G01X2336945D02*
X2344277D01*
G01X2385173Y532136D02*
X2358480D01*
G01X2347772Y531742D02*
X2354937D01*
G01X2352890Y531545D02*
X2351905D01*
G01X2352890Y531151D02*
X2351905D01*
G01X2352890Y530955D02*
X2351905D01*
G01X2344277Y529872D02*
X2336945D01*
G01X2356433D02*
X2344424D01*
G01X2366669Y529793D02*
X2385173D01*
G01X2356433D02*
X2355331D01*
G01X2380673Y529774D02*
X2358480D01*
G01X2356433Y529675D02*
X2348898D01*
G01X2353439Y529183D02*
X2351315D01*
G01X2344424Y529085D02*
X2356433D01*
G01X2336945D02*
X2344277D01*
G01X2354424Y528888D02*
X2353439D01*
G01X2354424Y528691D02*
X2353439D01*
G01X2355331Y528494D02*
X2349305D01*
G01X2355331Y527313D02*
X2349305D01*
G01X2354424Y527116D02*
X2353439D01*
G01X2354424Y526919D02*
X2353439D01*
G01X2344277Y526722D02*
X2336945D01*
G01X2356433D02*
X2344424D01*
G01Y525935D02*
X2356433D01*
G01X2336945D02*
X2344277D01*
G01X2349324Y525856D02*
X2347441D01*
G01X2354424Y525738D02*
X2353439D01*
G01X2354424Y525541D02*
X2353439D01*
G01X2355331Y525344D02*
X2349305D01*
G01X2355331Y524163D02*
X2349305D01*
G01X2354424Y523966D02*
X2353439D01*
G01X2354424Y523770D02*
X2353439D01*
G01X2347441Y523651D02*
X2349324D01*
G01X2344277Y523573D02*
X2336945D01*
G01X2356433D02*
X2344424D01*
G01Y522785D02*
X2356433D01*
G01X2336945D02*
X2344277D01*
G01X2354424Y522588D02*
X2353439D01*
G01X2354424Y522392D02*
X2353439D01*
G01X2355331Y522195D02*
X2349305D01*
G01X2355331Y521014D02*
X2349305D01*
G01X2354424Y520817D02*
X2353439D01*
G01X2354424Y520620D02*
X2353439D01*
G01X2344277Y520423D02*
X2336945D01*
G01X2356433D02*
X2344424D01*
G01Y519636D02*
X2356433D01*
G01X2336945D02*
X2344277D01*
G01X2354424Y519439D02*
X2353439D01*
G01X2354424Y519242D02*
X2353439D01*
G01X2355331Y519045D02*
X2349305D01*
G01X2355331Y517864D02*
X2349305D01*
G01X2354424Y517667D02*
X2353439D01*
G01X2354424Y517470D02*
X2353439D01*
G01X2344277Y517274D02*
X2336945D01*
G01X2356433D02*
X2344424D01*
G01Y516486D02*
X2356433D01*
G01X2336945D02*
X2344277D01*
G01X2349324Y516407D02*
X2347441D01*
G01X2354424Y516289D02*
X2353439D01*
G01X2354424Y516092D02*
X2353439D01*
G01X2355331Y515896D02*
X2349305D01*
G01X2355331Y514714D02*
X2349305D01*
G01X2354424Y514518D02*
X2353439D01*
G01X2354424Y514321D02*
X2353439D01*
G01X2347441Y514203D02*
X2349324D01*
G01X2344277Y514124D02*
X2336945D01*
G01X2356433D02*
X2344424D01*
G01Y513337D02*
X2356433D01*
G01X2336945D02*
X2344277D01*
G01X2354424Y513140D02*
X2353439D01*
G01X2354424Y512943D02*
X2353439D01*
G01X2355331Y512746D02*
X2349305D01*
G01X2355331Y511565D02*
X2349305D01*
G01X2354424Y511368D02*
X2353439D01*
G01X2354424Y511171D02*
X2353439D01*
G01X2344277Y510974D02*
X2336945D01*
G01X2356433D02*
X2344424D01*
G01X2353439Y510876D02*
X2351315D01*
G01X2348898Y510384D02*
X2356433D01*
G01X2380673Y510285D02*
X2358480D01*
G01X2356433Y510266D02*
X2355331D01*
G01X2385173D02*
X2366669D01*
G01X2344424Y510187D02*
X2356433D01*
G01X2336945D02*
X2344277D01*
G01X2352890Y509104D02*
X2351905D01*
G01X2352890Y508907D02*
X2351905D01*
G01X2352890Y508514D02*
X2351905D01*
G01X2347772Y508317D02*
X2354937D01*
G01X2385173Y507923D02*
X2358480D01*
G01X2344277Y507825D02*
X2336945D01*
G01X2356433D02*
X2344424D01*
G01Y507037D02*
X2356433D01*
G01X2336945D02*
X2344277D01*
G01X2347772Y506742D02*
X2354937D01*
G01X2352890Y506545D02*
X2351905D01*
G01X2352890Y506151D02*
X2351905D01*
G01X2352890Y505955D02*
X2351905D01*
G01X2344277Y504675D02*
X2336945D01*
G01X2356433D02*
X2344424D01*
G01X2352890Y504104D02*
X2351905D01*
G01X2386130Y503927D02*
X2366669D01*
G01X2352890Y503907D02*
X2351905D01*
G01X2344424Y503888D02*
X2356433D01*
G01X2336945D02*
X2344277D01*
G01X2352890Y503514D02*
X2351905D01*
G01X2347772Y503317D02*
X2354937D01*
G01X2347772Y501742D02*
X2354937D01*
G01X2352890Y501545D02*
X2351905D01*
G01X2344277Y501525D02*
X2336945D01*
G01X2356433D02*
X2344424D01*
G01X2352890Y501151D02*
X2351905D01*
G01X2352890Y500955D02*
X2351905D01*
G01X2344424Y500738D02*
X2356433D01*
G01X2336945D02*
X2344277D01*
G01X2352890Y499104D02*
X2351905D01*
G01X2352890Y498907D02*
X2351905D01*
G01X2352890Y498514D02*
X2351905D01*
G01X2344277Y498376D02*
X2336945D01*
G01X2356433D02*
X2344424D01*
G01X2347772Y498317D02*
X2354937D01*
G01X2344424Y497588D02*
X2356433D01*
G01X2336945D02*
X2344277D01*
G01X2347772Y496742D02*
X2354937D01*
G01X2352890Y496545D02*
X2351905D01*
G01X2352890Y496151D02*
X2351905D01*
G01X2352890Y495955D02*
X2351905D01*
G01X2344277Y495226D02*
X2336945D01*
G01X2356433D02*
X2344424D01*
G01Y494439D02*
X2356433D01*
G01X2336945D02*
X2344277D01*
G01X2352890Y494104D02*
X2351905D01*
G01X2352890Y493907D02*
X2351905D01*
G01X2352890Y493514D02*
X2351905D01*
G01X2347772Y493317D02*
X2354937D01*
G01X2385173Y492687D02*
X2358480D01*
G01X2344277Y492077D02*
X2336945D01*
G01X2356433D02*
X2344424D01*
G01X2347772Y491742D02*
X2354937D01*
G01X2352890Y491545D02*
X2351905D01*
G01X2344424Y491289D02*
X2356433D01*
G01X2336945D02*
X2344277D01*
G01X2352890Y491151D02*
X2351905D01*
G01X2352890Y490955D02*
X2351905D01*
G01X2385173Y490325D02*
X2358480D01*
G01X2352890Y489104D02*
X2351905D01*
G01X2344277Y488927D02*
X2336945D01*
G01X2356433D02*
X2344424D01*
G01X2352890Y488907D02*
X2351905D01*
G01X2352890Y488514D02*
X2351905D01*
G01X2347772Y488317D02*
X2354937D01*
G01X2344424Y488140D02*
X2356433D01*
G01X2336945D02*
X2344277D01*
G01X2347772Y486742D02*
X2354937D01*
G01X2352890Y486545D02*
X2351905D01*
G01X2352890Y486151D02*
X2351905D01*
G01X2352890Y485955D02*
X2351905D01*
G01X2344277Y485777D02*
X2336945D01*
G01X2356433D02*
X2344424D01*
G01X2329249Y538061D02*
X2575488D01*
G01X2354491Y557431D02*
Y558218D01*
G01X2354464Y557431D02*
Y558218D01*
G01X2354088Y557431D02*
Y558218D01*
G01X2350726D02*
Y557431D01*
G01X2348743Y558218D02*
Y557431D01*
G01X2347091D02*
Y558218D01*
G01X2344424Y557431D02*
Y558218D01*
G01X2344277Y557431D02*
Y558218D01*
G01X2342685Y557431D02*
Y558218D01*
G01X2341743D02*
Y557431D01*
G01X2338907Y558218D02*
Y557431D01*
G01X2338718D02*
Y558218D01*
G01X2336945Y557431D02*
Y558218D01*
G01X2344424Y557431D02*
X2356433D01*
G01X2336945D02*
X2344277D01*
G01X2358121Y615689D02*
G03X2359551I715J0D01*
G01X2355231D02*
G03X2356661I715J0D01*
G01X2358992Y625069D02*
G03Y628218I0J1575D01*
G01X2354132Y614614D02*
G03X2356768Y614759I1248J1352D01*
G01D02*
G03X2359549Y614764I1388J1207D01*
G01X2354937Y583317D02*
G03X2355331Y583711I0J394D01*
G01Y581348D02*
G03X2354937Y581742I-394J0D01*
G01Y603317D02*
G03X2355331Y603711I0J394D01*
G01Y601348D02*
G03X2354937Y601742I-394J0D01*
G01Y593317D02*
G03X2355331Y593711I0J394D01*
G01Y591348D02*
G03X2354937Y591742I-394J0D01*
G01Y598317D02*
G03X2355331Y598711I0J394D01*
G01Y596348D02*
G03X2354937Y596742I-394J0D01*
G01X2351632Y617105D02*
G03X2350159I-736J-277D01*
G01Y615421D02*
G03X2351632I737J277D01*
G01X2353838Y615285D02*
G03X2354132Y614614I914J0D01*
G01X2352904Y617440D02*
G03X2352383Y618005I-1351J-723D01*
G01X2352384Y614561D02*
G03X2352905Y615127I-831J1288D01*
G01X2354661Y628218D02*
G03Y625069I0J-1574D01*
G01X2350159Y617105D02*
G03Y615421I2236J-842D01*
G01X2352905Y615127D02*
G03X2352904Y617440I-2163J1156D01*
G01X2348816Y617438D02*
G03X2348817Y615126I2163J-1155D01*
G01X2352383Y618005D02*
G03X2349337Y618004I-1522J-2362D01*
G01X2349338Y614561D02*
G03X2352384I1523J2362D01*
G01X2354937Y563317D02*
G03X2355331Y563711I0J394D01*
G01Y561348D02*
G03X2354937Y561742I-394J0D01*
G01Y568317D02*
G03X2355331Y568711I0J394D01*
G01Y566348D02*
G03X2354937Y566742I-394J0D01*
G01Y578317D02*
G03X2355331Y578711I0J394D01*
G01Y576348D02*
G03X2354937Y576742I-394J0D01*
G01Y573317D02*
G03X2355331Y573711I0J394D01*
G01Y571348D02*
G03X2354937Y571742I-394J0D01*
G01Y558317D02*
G03X2355331Y558711I0J394D01*
G01X2349337Y618004D02*
G03X2348816Y617438I831J-1288D01*
G01X2348817Y615126D02*
G03X2349338Y614561I1351J723D01*
G01X2351632Y615421D02*
G03Y617105I-2237J842D01*
G01X2349740Y614833D02*
G03I-2165J0D01*
G01X2345620Y617549D02*
G03Y612116I1955J-2717D01*
G01X2349529D02*
G03Y617549I-1954J2717D01*
G01X2351079Y614833D02*
G03I-3504J0D01*
G01X2349878Y610935D02*
G03Y618730I-2304J3897D01*
G01X2345271D02*
G03Y610935I2304J-3898D01*
G01X2343658Y617423D02*
G03X2343068Y617058I-9J-645D01*
G01X2344432Y616615D02*
G03X2343658Y617423I-792J16D01*
G01X2342407Y618127D02*
G03X2341564Y617058I704J-1422D01*
G01X2341772Y615172D02*
G03X2343007Y614199I1735J931D01*
G01X2344649Y614242D02*
G03X2345814Y615381I-729J1911D01*
G01X2345727Y617397D02*
G03X2343989Y618414I-1806J-1094D01*
G01X2343007Y614199D02*
G03X2344649Y614242I757J2475D01*
G01X2345988Y616537D02*
G03X2345726Y617399I-2971J-432D01*
G01X2341433Y616615D02*
G03X2341772Y615172I3015J-53D01*
G01X2345988Y616041D02*
G03Y616538I-3524J249D01*
G01X2345814Y615381D02*
G03X2345988Y616041I-4018J1412D01*
G01X2343007Y615789D02*
G03X2344432I712J-82D01*
G01X2343992Y618414D02*
G03X2342407Y618127I-262J-3073D01*
G01X2338235Y616059D02*
X2336940Y614207D01*
G01X2339011Y615194D02*
X2338322Y614207D01*
G01X2341407Y618214D02*
X2339965Y616067D01*
G01X2350333Y608907D02*
X2350078Y608514D01*
G01X2339999Y618214D02*
X2339208Y616937D01*
G01X2345620Y612116D02*
X2345603Y612060D01*
X2345550Y611895D01*
X2345472Y611637D01*
X2345376Y611309D01*
X2345271Y610935D01*
G01X2349878Y618730D02*
X2349775Y618361D01*
X2349679Y618032D01*
X2349599Y617769D01*
X2349546Y617604D01*
X2349529Y617549D01*
G01X2365016Y606151D02*
Y632549D01*
G01X2364701Y607333D02*
Y605561D01*
G01X2362732Y619616D02*
Y611270D01*
G01X2360992Y618214D02*
Y614207D01*
G01X2360449Y588632D02*
Y606151D01*
G01Y569734D02*
Y586270D01*
G01X2359617Y625856D02*
Y627431D01*
G01X2359583D02*
Y625856D01*
G01X2359558Y627431D02*
Y625856D01*
G01X2359551Y615689D02*
Y618214D01*
G01X2359549Y614764D02*
Y614207D01*
G01X2358795Y611900D02*
Y609498D01*
G01Y617648D02*
Y613868D01*
G01X2358235Y625856D02*
Y627431D01*
G01X2358121Y618214D02*
Y615689D01*
G01X2357865Y627431D02*
Y625856D01*
G01X2356661Y615689D02*
Y618214D01*
G01X2355788Y625856D02*
Y627431D01*
G01X2355418D02*
Y625856D01*
G01X2355231Y618214D02*
Y615689D01*
G01X2354858Y589104D02*
Y585955D01*
G01X2354491Y598376D02*
Y599163D01*
G01Y601525D02*
Y602313D01*
G01Y595226D02*
Y596014D01*
G01Y588927D02*
Y589714D01*
G01Y592077D02*
Y592864D01*
G01Y585777D02*
Y586565D01*
G01Y579478D02*
Y580266D01*
G01Y582628D02*
Y583415D01*
G01Y576329D02*
Y577116D01*
G01Y570029D02*
Y570817D01*
G01Y573179D02*
Y573966D01*
G01Y566880D02*
Y567667D01*
G01Y560581D02*
Y561368D01*
G01Y563730D02*
Y564518D01*
G01X2354464Y598376D02*
Y599163D01*
G01Y601525D02*
Y602313D01*
G01Y595226D02*
Y596014D01*
G01Y588927D02*
Y589714D01*
G01Y592077D02*
Y592864D01*
G01Y585777D02*
Y586565D01*
G01Y579478D02*
Y580266D01*
G01Y582628D02*
Y583415D01*
G01Y576329D02*
Y577116D01*
G01Y570029D02*
Y570817D01*
G01Y573179D02*
Y573966D01*
G01Y566880D02*
Y567667D01*
G01Y560581D02*
Y561368D01*
G01Y563730D02*
Y564518D01*
G01X2354095Y625856D02*
Y627431D01*
G01X2354088Y598376D02*
Y599163D01*
G01Y601525D02*
Y602313D01*
G01Y595226D02*
Y596014D01*
G01Y588927D02*
Y589714D01*
G01Y592077D02*
Y592864D01*
G01Y585777D02*
Y586565D01*
G01Y579478D02*
Y580266D01*
G01Y582628D02*
Y583415D01*
G01Y576329D02*
Y577116D01*
G01Y570029D02*
Y570817D01*
G01Y573179D02*
Y573966D01*
G01Y566880D02*
Y567667D01*
G01Y560581D02*
Y561368D01*
G01Y563730D02*
Y564518D01*
G01X2354071Y625856D02*
Y627431D01*
G01X2354036D02*
Y625856D01*
G01X2353874Y563317D02*
Y561742D01*
G01Y568317D02*
Y566742D01*
G01Y573317D02*
Y571742D01*
G01Y578317D02*
Y576742D01*
G01Y583317D02*
Y581742D01*
G01Y589104D02*
Y585955D01*
G01Y593317D02*
Y591742D01*
G01Y598317D02*
Y596742D01*
G01Y603317D02*
Y601742D01*
G01X2353838Y618214D02*
Y615285D01*
G01X2352890Y564104D02*
Y560955D01*
G01Y569104D02*
Y565955D01*
G01Y574104D02*
Y570955D01*
G01Y579104D02*
Y575955D01*
G01Y584104D02*
Y580955D01*
G01Y588317D02*
Y586742D01*
G01Y594104D02*
Y590955D01*
G01Y599104D02*
Y595955D01*
G01Y604104D02*
Y600955D01*
G01Y611270D02*
Y608966D01*
G01X2351905Y564104D02*
Y560955D01*
G01Y569104D02*
Y565955D01*
G01Y574104D02*
Y570955D01*
G01Y579104D02*
Y575955D01*
G01Y584104D02*
Y580955D01*
G01Y594104D02*
Y590955D01*
G01Y599104D02*
Y595955D01*
G01Y604104D02*
Y600955D01*
G01X2350921Y563317D02*
Y561742D01*
G01Y568317D02*
Y566742D01*
G01Y573317D02*
Y571742D01*
G01Y578317D02*
Y576742D01*
G01Y583317D02*
Y581742D01*
G01Y593317D02*
Y591742D01*
G01Y598317D02*
Y596742D01*
G01Y603317D02*
Y601742D01*
G01X2350726Y561368D02*
Y560581D01*
G01Y564518D02*
Y563730D01*
G01Y567667D02*
Y566880D01*
G01Y570817D02*
Y570029D01*
G01Y573966D02*
Y573179D01*
G01Y577116D02*
Y576329D01*
G01Y580266D02*
Y579478D01*
G01Y583415D02*
Y582628D01*
G01Y586565D02*
Y585777D01*
G01Y589714D02*
Y588927D01*
G01Y592864D02*
Y592077D01*
G01Y596014D02*
Y595226D01*
G01Y599163D02*
Y598376D01*
G01Y602313D02*
Y601525D01*
G01X2350333Y608966D02*
Y608907D01*
G01X2349740Y588317D02*
Y586742D01*
G01X2349694Y608514D02*
Y611270D01*
G01X2348743Y561368D02*
Y560581D01*
G01Y564518D02*
Y563730D01*
G01Y567667D02*
Y566880D01*
G01Y570817D02*
Y570029D01*
G01Y573966D02*
Y573179D01*
G01Y577116D02*
Y576329D01*
G01Y580266D02*
Y579478D01*
G01Y583415D02*
Y582628D01*
G01Y586565D02*
Y585777D01*
G01Y589714D02*
Y588927D01*
G01Y592864D02*
Y592077D01*
G01Y596014D02*
Y595226D01*
G01Y599163D02*
Y598376D01*
G01Y602313D02*
Y601525D01*
G01X2348638Y632549D02*
Y619616D01*
G01X2348039Y618214D02*
Y612460D01*
G01X2347772Y563317D02*
Y561742D01*
G01Y568317D02*
Y566742D01*
G01Y573317D02*
Y571742D01*
G01Y578317D02*
Y576742D01*
G01Y583317D02*
Y581742D01*
G01Y593317D02*
Y591742D01*
G01Y598317D02*
Y596742D01*
G01Y603317D02*
Y601742D01*
G01X2347091Y598376D02*
Y599163D01*
G01Y601525D02*
Y602313D01*
G01Y595226D02*
Y596014D01*
G01Y588927D02*
Y589714D01*
G01Y592077D02*
Y592864D01*
G01Y585777D02*
Y586565D01*
G01Y579478D02*
Y580266D01*
G01Y582628D02*
Y583415D01*
G01Y576329D02*
Y577116D01*
G01Y570029D02*
Y570817D01*
G01Y573179D02*
Y573966D01*
G01Y566880D02*
Y567667D01*
G01Y560581D02*
Y561368D01*
G01Y563730D02*
Y564518D01*
G01X2346579Y618214D02*
Y612460D01*
G01X2345363Y560581D02*
Y558218D01*
G01Y563730D02*
Y561368D01*
G01Y566880D02*
Y564518D01*
G01Y570029D02*
Y567667D01*
G01Y573179D02*
Y570817D01*
G01Y576329D02*
Y573966D01*
G01Y579478D02*
Y577116D01*
G01Y582628D02*
Y580266D01*
G01Y585777D02*
Y583415D01*
G01Y588927D02*
Y586565D01*
G01Y592077D02*
Y589714D01*
G01Y595226D02*
Y592864D01*
G01Y598376D02*
Y596014D01*
G01Y601525D02*
Y599163D01*
G01Y603986D02*
Y602313D01*
G01X2344424Y598376D02*
Y599163D01*
G01Y601525D02*
Y602313D01*
G01Y595226D02*
Y596014D01*
G01Y588927D02*
Y589714D01*
G01Y592077D02*
Y592864D01*
G01Y585777D02*
Y586565D01*
G01Y579478D02*
Y580266D01*
G01Y582628D02*
Y583415D01*
G01Y576329D02*
Y577116D01*
G01Y570029D02*
Y570817D01*
G01Y573179D02*
Y573966D01*
G01Y566880D02*
Y567667D01*
G01Y560581D02*
Y561368D01*
G01Y563730D02*
Y564518D01*
G01X2344277Y598376D02*
Y599163D01*
G01Y601525D02*
Y602313D01*
G01Y595226D02*
Y596014D01*
G01Y588927D02*
Y589714D01*
G01Y592077D02*
Y592864D01*
G01Y585777D02*
Y586565D01*
G01Y579478D02*
Y580266D01*
G01Y582628D02*
Y583415D01*
G01Y576329D02*
Y577116D01*
G01Y570029D02*
Y570817D01*
G01Y573179D02*
Y573966D01*
G01Y566880D02*
Y567667D01*
G01Y560581D02*
Y561368D01*
G01Y563730D02*
Y564518D01*
G01X2342685Y598376D02*
Y599163D01*
G01Y601525D02*
Y602313D01*
G01Y595226D02*
Y596014D01*
G01Y588927D02*
Y589714D01*
G01Y592077D02*
Y592864D01*
G01Y585777D02*
Y586565D01*
G01Y579478D02*
Y580266D01*
G01Y582628D02*
Y583415D01*
G01Y576329D02*
Y577116D01*
G01Y570029D02*
Y570817D01*
G01Y573179D02*
Y573966D01*
G01Y566880D02*
Y567667D01*
G01Y560581D02*
Y561368D01*
G01Y563730D02*
Y564518D01*
G01X2341820Y608514D02*
Y611270D01*
G01X2341743Y561368D02*
Y560581D01*
G01Y564518D02*
Y563730D01*
G01Y567667D02*
Y566880D01*
G01Y570817D02*
Y570029D01*
G01Y573966D02*
Y573179D01*
G01Y577116D02*
Y576329D01*
G01Y580266D02*
Y579478D01*
G01Y583415D02*
Y582628D01*
G01Y586565D02*
Y585777D01*
G01Y589714D02*
Y588927D01*
G01Y592864D02*
Y592077D01*
G01Y596014D02*
Y595226D01*
G01Y599163D02*
Y598376D01*
G01Y602313D02*
Y601525D01*
G01X2338907Y561368D02*
Y560581D01*
G01Y564518D02*
Y563730D01*
G01Y567667D02*
Y566880D01*
G01Y570817D02*
Y570029D01*
G01Y573966D02*
Y573179D01*
G01Y577116D02*
Y576329D01*
G01Y580266D02*
Y579478D01*
G01Y583415D02*
Y582628D01*
G01Y586565D02*
Y585777D01*
G01Y589714D02*
Y588927D01*
G01Y592864D02*
Y592077D01*
G01Y596014D02*
Y595226D01*
G01Y599163D02*
Y598376D01*
G01Y602313D02*
Y601525D01*
G01X2338718Y598376D02*
Y599163D01*
G01Y601525D02*
Y602313D01*
G01Y595226D02*
Y596014D01*
G01Y588927D02*
Y589714D01*
G01Y592077D02*
Y592864D01*
G01Y585777D02*
Y586565D01*
G01Y579478D02*
Y580266D01*
G01Y582628D02*
Y583415D01*
G01Y576329D02*
Y577116D01*
G01Y570029D02*
Y570817D01*
G01Y573179D02*
Y573966D01*
G01Y566880D02*
Y567667D01*
G01Y560581D02*
Y561368D01*
G01Y563730D02*
Y564518D01*
G01X2336945Y598376D02*
Y599163D01*
G01Y601525D02*
Y602313D01*
G01Y595226D02*
Y596014D01*
G01Y588927D02*
Y589714D01*
G01Y592077D02*
Y592864D01*
G01Y585777D02*
Y586565D01*
G01Y579478D02*
Y580266D01*
G01Y582628D02*
Y583415D01*
G01Y576329D02*
Y577116D01*
G01Y570029D02*
Y570817D01*
G01Y573179D02*
Y573966D01*
G01Y566880D02*
Y567667D01*
G01Y560581D02*
Y561368D01*
G01Y563730D02*
Y564518D01*
G01X2335966Y608514D02*
Y605738D01*
G01X2335491Y611270D02*
Y605738D01*
G01X2335173Y619616D02*
Y605738D01*
G01X2349529Y612116D02*
X2349547Y612060D01*
X2349599Y611895D01*
X2349678Y611636D01*
X2349774Y611309D01*
X2349878Y610935D01*
G01X2345620Y617549D02*
X2345602Y617605D01*
X2345550Y617771D01*
X2345471Y618029D01*
X2345376Y618356D01*
X2345271Y618730D01*
G01X2338463Y618214D02*
X2339208Y616937D01*
G01X2336914Y618214D02*
X2338235Y616059D01*
G01X2339011Y615194D02*
X2339617Y614207D01*
G01X2339965Y616067D02*
X2341233Y614207D01*
G01X2354661Y628218D02*
X2358992D01*
G01X2354036Y627431D02*
X2359617D01*
G01Y625856D02*
X2354036D01*
G01X2358992Y625069D02*
X2354661D01*
G01X2365016Y622372D02*
X2348638D01*
G01X2335173Y619616D02*
X2389110D01*
G01X2349878Y618730D02*
X2345271D01*
G01X2389110Y618435D02*
X2362732D01*
G01X2338463Y618214D02*
X2336914D01*
G01X2341407D02*
X2339999D01*
G01X2348039D02*
X2346579D01*
G01X2355231D02*
X2353838D01*
G01X2358121D02*
X2356661D01*
G01X2360992D02*
X2359551D01*
G01X2358795Y617648D02*
X2335173D01*
G01X2345620Y617549D02*
X2349529D01*
G01X2343067Y617058D02*
X2341564D01*
G01X2344433Y616615D02*
X2341433D01*
G01X2344432Y615789D02*
X2343007D01*
G01X2338322Y614207D02*
X2336940D01*
G01X2341233D02*
X2339617D01*
G01X2360992D02*
X2359549D01*
G01X2358795Y613868D02*
X2335173D01*
G01X2348039Y612460D02*
X2346579D01*
G01X2349529Y612116D02*
X2345620D01*
G01X2358795Y611900D02*
X2335173D01*
G01X2385173Y611270D02*
X2335173D01*
G01X2345271Y610935D02*
X2349878D01*
G01X2335173Y609498D02*
X2358795D01*
G01X2350333Y608966D02*
X2356433D01*
G01X2350333Y608907D02*
X2356433D01*
G01X2335966Y608514D02*
X2356433D01*
G01X2355331Y607333D02*
X2364701D01*
G01X2387142Y606742D02*
X2356433D01*
G01X2385173Y606348D02*
X2366669D01*
G01X2365016Y606151D02*
X2358480D01*
G01X2335173Y605738D02*
X2355331D01*
G01Y605561D02*
X2364701D01*
G01X2352890Y604104D02*
X2351905D01*
G01X2351315Y603986D02*
X2342330D01*
G01X2352890Y603907D02*
X2351905D01*
G01X2352890Y603514D02*
X2351905D01*
G01X2347772Y603317D02*
X2354937D01*
G01X2344277Y602313D02*
X2336945D01*
G01X2356433D02*
X2344424D01*
G01X2347772Y601742D02*
X2354937D01*
G01X2352890Y601545D02*
X2351905D01*
G01X2344424Y601525D02*
X2356433D01*
G01X2336945D02*
X2344277D01*
G01X2352890Y601151D02*
X2351905D01*
G01X2352890Y600955D02*
X2351905D01*
G01X2344277Y599163D02*
X2336945D01*
G01X2356433D02*
X2344424D01*
G01X2352890Y599104D02*
X2351905D01*
G01X2352890Y598907D02*
X2351905D01*
G01X2352890Y598514D02*
X2351905D01*
G01X2344424Y598376D02*
X2356433D01*
G01X2336945D02*
X2344277D01*
G01X2347772Y598317D02*
X2354937D01*
G01X2347772Y596742D02*
X2354937D01*
G01X2352890Y596545D02*
X2351905D01*
G01X2352890Y596151D02*
X2351905D01*
G01X2344277Y596014D02*
X2336945D01*
G01X2356433D02*
X2344424D01*
G01X2352890Y595955D02*
X2351905D01*
G01X2344424Y595226D02*
X2356433D01*
G01X2336945D02*
X2344277D01*
G01X2352890Y594104D02*
X2351905D01*
G01X2352890Y593907D02*
X2351905D01*
G01X2352890Y593514D02*
X2351905D01*
G01X2347772Y593317D02*
X2354937D01*
G01X2344277Y592864D02*
X2336945D01*
G01X2356433D02*
X2344424D01*
G01Y592077D02*
X2356433D01*
G01X2336945D02*
X2344277D01*
G01X2347772Y591742D02*
X2354937D01*
G01X2352890Y591545D02*
X2351905D01*
G01X2352890Y591151D02*
X2351905D01*
G01X2352890Y590955D02*
X2351905D01*
G01X2356433Y589734D02*
X2355331D01*
G01X2344277Y589714D02*
X2336945D01*
G01X2356433D02*
X2344424D01*
G01X2354858Y589104D02*
X2353874D01*
G01X2344424Y588927D02*
X2356433D01*
G01X2336945D02*
X2344277D01*
G01X2354858Y588907D02*
X2353874D01*
G01X2385173Y588632D02*
X2358480D01*
G01X2354858Y588514D02*
X2353874D01*
G01X2355331Y588317D02*
X2349740D01*
G01X2355331Y586742D02*
X2349740D01*
G01X2344277Y586565D02*
X2336945D01*
G01X2356433D02*
X2344424D01*
G01X2354858Y586545D02*
X2353874D01*
G01X2385173Y586270D02*
X2358480D01*
G01X2354858Y586151D02*
X2353874D01*
G01X2354858Y585955D02*
X2353874D01*
G01X2344424Y585777D02*
X2356433D01*
G01X2336945D02*
X2344277D01*
G01X2356433Y585325D02*
X2355331D01*
G01X2352890Y584104D02*
X2351905D01*
G01X2352890Y583907D02*
X2351905D01*
G01X2352890Y583514D02*
X2351905D01*
G01X2344277Y583415D02*
X2336945D01*
G01X2356433D02*
X2344424D01*
G01X2347772Y583317D02*
X2354937D01*
G01X2344424Y582628D02*
X2356433D01*
G01X2336945D02*
X2344277D01*
G01X2347772Y581742D02*
X2354937D01*
G01X2352890Y581545D02*
X2351905D01*
G01X2352890Y581151D02*
X2351905D01*
G01X2352890Y580955D02*
X2351905D01*
G01X2344277Y580266D02*
X2336945D01*
G01X2356433D02*
X2344424D01*
G01Y579478D02*
X2356433D01*
G01X2336945D02*
X2344277D01*
G01X2352890Y579104D02*
X2351905D01*
G01X2352890Y578907D02*
X2351905D01*
G01X2352890Y578514D02*
X2351905D01*
G01X2347772Y578317D02*
X2354937D01*
G01X2344277Y577116D02*
X2336945D01*
G01X2356433D02*
X2344424D01*
G01X2347772Y576742D02*
X2354937D01*
G01X2352890Y576545D02*
X2351905D01*
G01X2344424Y576329D02*
X2356433D01*
G01X2336945D02*
X2344277D01*
G01X2352890Y576151D02*
X2351905D01*
G01X2352890Y575955D02*
X2351905D01*
G01X2352890Y574104D02*
X2351905D01*
G01X2344277Y573966D02*
X2336945D01*
G01X2356433D02*
X2344424D01*
G01X2352890Y573907D02*
X2351905D01*
G01X2352890Y573514D02*
X2351905D01*
G01X2347772Y573317D02*
X2354937D01*
G01X2344424Y573179D02*
X2356433D01*
G01X2336945D02*
X2344277D01*
G01X2347772Y571742D02*
X2354937D01*
G01X2352890Y571545D02*
X2351905D01*
G01X2352890Y571151D02*
X2351905D01*
G01X2352890Y570955D02*
X2351905D01*
G01X2344277Y570817D02*
X2336945D01*
G01X2356433D02*
X2344424D01*
G01Y570029D02*
X2356433D01*
G01X2336945D02*
X2344277D01*
G01X2385173Y569734D02*
X2358480D01*
G01X2352890Y569104D02*
X2351905D01*
G01X2352890Y568907D02*
X2351905D01*
G01X2352890Y568514D02*
X2351905D01*
G01X2347772Y568317D02*
X2354937D01*
G01X2344277Y567667D02*
X2336945D01*
G01X2356433D02*
X2344424D01*
G01X2385173Y567372D02*
X2358480D01*
G01X2344424Y566880D02*
X2356433D01*
G01X2336945D02*
X2344277D01*
G01X2347772Y566742D02*
X2354937D01*
G01X2352890Y566545D02*
X2351905D01*
G01X2352890Y566151D02*
X2351905D01*
G01X2352890Y565955D02*
X2351905D01*
G01X2344277Y564518D02*
X2336945D01*
G01X2356433D02*
X2344424D01*
G01X2352890Y564104D02*
X2351905D01*
G01X2352890Y563907D02*
X2351905D01*
G01X2344424Y563730D02*
X2356433D01*
G01X2336945D02*
X2344277D01*
G01X2352890Y563514D02*
X2351905D01*
G01X2347772Y563317D02*
X2354937D01*
G01X2347772Y561742D02*
X2354937D01*
G01X2352890Y561545D02*
X2351905D01*
G01X2344277Y561368D02*
X2336945D01*
G01X2356433D02*
X2344424D01*
G01X2352890Y561151D02*
X2351905D01*
G01X2352890Y560955D02*
X2351905D01*
G01X2344424Y560581D02*
X2356433D01*
G01X2336945D02*
X2344277D01*
G01X2352890Y559104D02*
X2351905D01*
G01X2352890Y558907D02*
X2351905D01*
G01X2352890Y558514D02*
X2351905D01*
G01X2347772Y558317D02*
X2354937D01*
G01X2344277Y558218D02*
X2336945D01*
G01X2356433D02*
X2344424D01*
G01X2365016Y632549D02*
X2348638D01*
G01X2359976Y840148D02*
G03Y838966I0J-591D01*
G01Y842903D02*
G03Y841722I0J-591D01*
G01X2353677Y838966D02*
G03Y840148I0J591D01*
G01Y841722D02*
G03Y842903I0J591D01*
G01X2353688Y839768D02*
X2353594Y839657D01*
G01Y839784D02*
X2353688Y839896D01*
G01X2361551Y838671D02*
Y840640D01*
G01Y843199D02*
Y841230D01*
G01X2359976Y840148D02*
Y841722D01*
G01Y842903D02*
Y843494D01*
G01Y838376D02*
Y838966D01*
G01X2358992Y838376D02*
Y843494D01*
G01X2358795D02*
Y838376D01*
G01X2358401Y841230D02*
Y843199D01*
G01Y840640D02*
Y838671D01*
G01X2355252Y841230D02*
Y843199D01*
G01Y840640D02*
Y838671D01*
G01X2354858Y843494D02*
Y838376D01*
G01X2354661D02*
Y843494D01*
G01X2353781Y839896D02*
Y839148D01*
G01X2353688D02*
Y839768D01*
G01X2353677Y838966D02*
Y838376D01*
G01Y841722D02*
Y840148D01*
G01Y843494D02*
Y842903D01*
G01X2353594Y839657D02*
Y839784D01*
G01X2352102Y838671D02*
Y840640D01*
G01Y843199D02*
Y841230D01*
G01X2359976Y843494D02*
X2353677D01*
G01X2358401Y843199D02*
X2361551D01*
G01X2355252D02*
X2352102D01*
G01Y841230D02*
X2355252D01*
G01X2361551D02*
X2358401D01*
G01X2352102Y840640D02*
X2355252D01*
G01X2361551D02*
X2358401D01*
G01X2353688Y839896D02*
X2353781D01*
G01Y839148D02*
X2353688D01*
G01X2358401Y838671D02*
X2361551D01*
G01X2355252D02*
X2352102D01*
G01X2353677Y838376D02*
X2359976D01*
G01X2358992Y857352D02*
G03Y860502I0J1575D01*
G01X2353234Y869441D02*
G03X2352164Y867618I2809J-2874D01*
G01X2360210Y872342D02*
G03X2357996Y867175I6938J-6031D01*
G01X2361096Y872416D02*
G03X2358881Y867175I7141J-6107D01*
G01X2354937Y883829D02*
G03X2355331Y884222I0J394D01*
G01Y881860D02*
G03X2354937Y882254I-394J0D01*
G01Y913829D02*
G03X2355331Y914222I0J394D01*
G01Y911860D02*
G03X2354937Y912254I-394J0D01*
G01Y908829D02*
G03X2355331Y909222I0J394D01*
G01Y906860D02*
G03X2354937Y907254I-394J0D01*
G01Y903829D02*
G03X2355331Y904222I0J394D01*
G01Y901860D02*
G03X2354937Y902254I-394J0D01*
G01Y893829D02*
G03X2355331Y894222I0J394D01*
G01Y891860D02*
G03X2354937Y892254I-394J0D01*
G01Y898829D02*
G03X2355331Y899222I0J394D01*
G01Y896860D02*
G03X2354937Y897254I-394J0D01*
G01Y888829D02*
G03X2355331Y889222I0J394D01*
G01Y886860D02*
G03X2354937Y887254I-394J0D01*
G01X2354661Y860502D02*
G03Y857352I0J-1575D01*
G01X2353739Y868897D02*
G03X2353197Y867913I1276J-1344D01*
G01X2349740Y870738D02*
G03I-2165J0D01*
G01X2350921D02*
G03I-3346J0D01*
G01X2351079D02*
G03I-3504J0D01*
G01X2352102D02*
G03I-4527J0D01*
G01X2339762Y872342D02*
G03X2337548Y867175I6938J-6031D01*
G01X2340648Y872416D02*
G03X2338433Y867175I7141J-6107D01*
G01X2355368Y870444D02*
X2353739Y868897D01*
G01X2354796Y870969D02*
X2353234Y869441D01*
G01X2360621Y881138D02*
X2360359Y881053D01*
G01X2358879Y881394D02*
X2358617Y881309D01*
G01X2358356Y883442D02*
X2358094Y883356D01*
G01X2360098Y883697D02*
X2359750Y883527D01*
G01X2358182Y882844D02*
X2358356Y882930D01*
G01X2360708Y880627D02*
X2361144Y880882D01*
G01X2353528Y872102D02*
X2353815Y872280D01*
X2354169Y872342D01*
G01X2349338Y870783D02*
X2349621Y870961D01*
X2349808Y871226D01*
X2349875Y871528D01*
X2349811Y871829D01*
X2349625Y872095D01*
X2349340Y872277D01*
X2348990Y872342D01*
G01X2348641Y872277D02*
X2348358Y872100D01*
X2348171Y871834D01*
X2348104Y871533D01*
X2348168Y871232D01*
X2348354Y870965D01*
X2348639Y870784D01*
X2348990Y870718D01*
G01X2344171Y870783D02*
X2344454Y870961D01*
X2344641Y871226D01*
X2344708Y871528D01*
X2344644Y871829D01*
X2344458Y872095D01*
X2344173Y872277D01*
X2343822Y872342D01*
G01X2343473Y872277D02*
X2343191Y872100D01*
X2343004Y871834D01*
X2342937Y871533D01*
X2343001Y871232D01*
X2343186Y870965D01*
X2343472Y870784D01*
X2343822Y870718D01*
G01X2359924Y883015D02*
X2360185Y883186D01*
G01X2349413Y867991D02*
X2349773Y868227D01*
X2350011Y868577D01*
X2350097Y868981D01*
X2350014Y869383D01*
X2349778Y869735D01*
X2349414Y869975D01*
X2348990Y870060D01*
G01X2348567Y869976D02*
X2348206Y869740D01*
X2347968Y869390D01*
X2347882Y868986D01*
X2347965Y868584D01*
X2348201Y868232D01*
X2348565Y867992D01*
X2348990Y867907D01*
G01X2344245Y867991D02*
X2344606Y868227D01*
X2344844Y868577D01*
X2344929Y868981D01*
X2344847Y869383D01*
X2344610Y869735D01*
X2344247Y869975D01*
X2343822Y870060D01*
G01X2343399Y869976D02*
X2343039Y869740D01*
X2342800Y869390D01*
X2342715Y868986D01*
X2342798Y868584D01*
X2343034Y868232D01*
X2343397Y867992D01*
X2343822Y867907D01*
G01X2358094Y883356D02*
X2357746Y883100D01*
G01X2347792Y870432D02*
X2347340Y869991D01*
X2347070Y869456D01*
X2347000Y868885D01*
X2347141Y868321D01*
X2347488Y867797D01*
X2348015Y867403D01*
X2348658Y867200D01*
X2349337Y867202D01*
X2349977Y867410D01*
X2350500Y867807D01*
X2350842Y868330D01*
X2350980Y868891D01*
X2350908Y869459D01*
X2350638Y869993D01*
G01X2342624Y870432D02*
X2342173Y869991D01*
X2341903Y869456D01*
X2341832Y868885D01*
X2341974Y868321D01*
X2342321Y867797D01*
X2342848Y867403D01*
X2343491Y867200D01*
X2344170Y867202D01*
X2344810Y867410D01*
X2345333Y867807D01*
X2345674Y868330D01*
X2345812Y868891D01*
X2345741Y869459D01*
X2345470Y869993D01*
G01X2360882Y881394D02*
X2360621Y881138D01*
G01X2359053Y880882D02*
X2359401Y881224D01*
G01X2359750Y883527D02*
X2359401Y883186D01*
G01X2358007Y882674D02*
X2358182Y882844D01*
G01X2350187Y870432D02*
X2350510Y870851D01*
X2350673Y871334D01*
X2350651Y871839D01*
X2350448Y872316D01*
X2350081Y872719D01*
X2349575Y872987D01*
X2348984Y873081D01*
X2348395Y872984D01*
X2347892Y872715D01*
X2347528Y872311D01*
X2347327Y871833D01*
X2347308Y871328D01*
X2347471Y870847D01*
X2347792Y870432D01*
G01X2345020D02*
X2345343Y870851D01*
X2345505Y871334D01*
X2345484Y871839D01*
X2345281Y872316D01*
X2344914Y872719D01*
X2344408Y872987D01*
X2343816Y873081D01*
X2343227Y872984D01*
X2342725Y872715D01*
X2342361Y872311D01*
X2342159Y871833D01*
X2342140Y871328D01*
X2342304Y870847D01*
X2342624Y870432D01*
G01X2357746Y883100D02*
X2357485Y882759D01*
G01X2355368Y870444D02*
X2355705Y870905D01*
X2355850Y871424D01*
X2355790Y871942D01*
X2355539Y872425D01*
X2355102Y872820D01*
X2354529Y873043D01*
X2353895Y873062D01*
X2353310Y872876D01*
X2352855Y872523D01*
X2352563Y872051D01*
X2352459Y871530D01*
G01X2353528Y872102D02*
X2353338Y871834D01*
G01X2354796Y870969D02*
X2354979Y871234D01*
X2355043Y871532D01*
X2354978Y871829D01*
G01X2359053Y881650D02*
X2358879Y881394D01*
G01X2359750Y882759D02*
X2359924Y883015D01*
G01X2361144Y880882D02*
X2361405Y881309D01*
G01X2359401Y881224D02*
X2359575Y881565D01*
G01X2359401Y883186D02*
X2359227Y882844D01*
G01X2359140Y881906D02*
X2359053Y881650D01*
G01X2357920Y882418D02*
X2358007Y882674D01*
G01X2360969Y881735D02*
X2360882Y881394D01*
G01X2359575Y881565D02*
X2359663Y881906D01*
G01Y882418D02*
X2359750Y882759D01*
G01X2353338Y871835D02*
X2353271Y871530D01*
G01X2361405Y881309D02*
X2361492Y881735D01*
G01X2359227Y882844D02*
X2359140Y882418D01*
G01X2357485Y882759D02*
X2357398Y882333D01*
G01X2352459Y871530D02*
X2352546Y872007D01*
X2352793Y872450D01*
X2353182Y872801D01*
X2353688Y873021D01*
X2354266Y873077D01*
X2354829Y872955D01*
X2355305Y872673D01*
X2355644Y872268D01*
X2355824Y871811D01*
X2355839Y871331D01*
X2355682Y870861D01*
X2355368Y870444D01*
G01X2366669Y1011860D02*
Y879222D01*
G01X2365016Y853022D02*
Y879419D01*
G01X2364701Y880010D02*
Y878238D01*
G01X2362732Y865955D02*
Y874301D01*
G01X2361492Y881735D02*
Y882418D01*
G01Y885403D02*
Y884892D01*
G01X2361096Y872416D02*
Y873081D01*
G01X2360969Y882418D02*
Y881735D01*
G01X2360449Y895837D02*
Y879419D01*
G01Y913435D02*
Y898199D01*
G01Y935285D02*
Y915797D01*
G01X2360359Y881053D02*
Y880541D01*
G01X2359663Y881906D02*
Y882418D01*
G01X2359617Y858140D02*
Y859714D01*
G01X2359583D02*
Y858140D01*
G01X2359558Y859714D02*
Y858140D01*
G01X2359140Y882418D02*
Y881906D01*
G01X2358795Y871703D02*
Y867923D01*
G01Y876112D02*
Y873671D01*
G01X2358480Y879419D02*
Y1011663D01*
G01X2358356Y882930D02*
Y883442D01*
G01X2358235Y858140D02*
Y859714D01*
G01X2357920Y881906D02*
Y882418D01*
G01X2357865Y859714D02*
Y858140D01*
G01X2357398Y884892D02*
Y885403D01*
G01Y882333D02*
Y881906D01*
G01X2357257Y873081D02*
Y872342D01*
G01X2356433Y1014478D02*
Y876604D01*
G01X2356076Y867175D02*
Y867913D01*
G01X2355788Y858140D02*
Y859714D01*
G01X2355418D02*
Y858140D01*
G01X2355331Y877057D02*
Y1014025D01*
G01X2355252Y935187D02*
Y915896D01*
G01X2354937D02*
Y935187D01*
G01X2354878Y882077D02*
Y884045D01*
G01X2354491Y915699D02*
Y916486D01*
G01Y918848D02*
Y919636D01*
G01Y912549D02*
Y913337D01*
G01Y906250D02*
Y907037D01*
G01Y909400D02*
Y910187D01*
G01Y903100D02*
Y903888D01*
G01Y896801D02*
Y897588D01*
G01Y899951D02*
Y900738D01*
G01Y893651D02*
Y894439D01*
G01Y890502D02*
Y891289D01*
G01Y884203D02*
Y884990D01*
G01Y887352D02*
Y888140D01*
G01X2354464Y915699D02*
Y916486D01*
G01Y918848D02*
Y919636D01*
G01Y912549D02*
Y913337D01*
G01Y906250D02*
Y907037D01*
G01Y909400D02*
Y910187D01*
G01Y903100D02*
Y903888D01*
G01Y896801D02*
Y897588D01*
G01Y899951D02*
Y900738D01*
G01Y893651D02*
Y894439D01*
G01Y890502D02*
Y891289D01*
G01Y884203D02*
Y884990D01*
G01Y887352D02*
Y888140D01*
G01X2354424Y918848D02*
Y916486D01*
G01Y921998D02*
Y919636D01*
G01X2354149Y935187D02*
Y915896D01*
G01X2354095Y858140D02*
Y859714D01*
G01X2354088Y915699D02*
Y916486D01*
G01Y918848D02*
Y919636D01*
G01Y912549D02*
Y913337D01*
G01Y906250D02*
Y907037D01*
G01Y909400D02*
Y910187D01*
G01Y903100D02*
Y903888D01*
G01Y896801D02*
Y897588D01*
G01Y899951D02*
Y900738D01*
G01Y893651D02*
Y894439D01*
G01Y890502D02*
Y891289D01*
G01Y884203D02*
Y884990D01*
G01Y887352D02*
Y888140D01*
G01X2354071Y858140D02*
Y859714D01*
G01X2354036D02*
Y858140D01*
G01X2353874Y883829D02*
Y882254D01*
G01Y888829D02*
Y887254D01*
G01Y893829D02*
Y892254D01*
G01Y898829D02*
Y897254D01*
G01Y903829D02*
Y902254D01*
G01Y908829D02*
Y907254D01*
G01Y913829D02*
Y912254D01*
G01X2353649Y935187D02*
Y915896D01*
G01X2353439Y916388D02*
Y934695D01*
G01X2353271Y871383D02*
Y871530D01*
G01X2352890Y876604D02*
Y874301D01*
G01Y884616D02*
Y881466D01*
G01Y889616D02*
Y886466D01*
G01Y894616D02*
Y891466D01*
G01Y899616D02*
Y896466D01*
G01Y904616D02*
Y901466D01*
G01Y909616D02*
Y906466D01*
G01Y914616D02*
Y911466D01*
G01X2352732Y915896D02*
Y935187D01*
G01X2352459Y871530D02*
Y871383D01*
G01X2352455Y918258D02*
Y917077D01*
G01Y921407D02*
Y920226D01*
G01X2352164Y867618D02*
Y867175D01*
G01X2351905Y884616D02*
Y881466D01*
G01Y889616D02*
Y886466D01*
G01Y894616D02*
Y891466D01*
G01Y899616D02*
Y896466D01*
G01Y904616D02*
Y901466D01*
G01Y909616D02*
Y906466D01*
G01Y914616D02*
Y911466D01*
G01X2351315Y877057D02*
Y1014025D01*
G01X2350921Y883829D02*
Y882254D01*
G01Y888829D02*
Y887254D01*
G01Y893829D02*
Y892254D01*
G01Y898829D02*
Y897254D01*
G01Y903829D02*
Y902254D01*
G01Y908829D02*
Y907254D01*
G01Y913829D02*
Y912254D01*
G01X2350860Y879636D02*
Y1011250D01*
G01X2350726Y884990D02*
Y884203D01*
G01Y888140D02*
Y887352D01*
G01Y891289D02*
Y890502D01*
G01Y894439D02*
Y893651D01*
G01Y897588D02*
Y896801D01*
G01Y900738D02*
Y899951D01*
G01Y903888D02*
Y903100D01*
G01Y907037D02*
Y906250D01*
G01Y910187D02*
Y909400D01*
G01Y913337D02*
Y912549D01*
G01Y916486D02*
Y915699D01*
G01Y919636D02*
Y918848D01*
G01X2350333Y876663D02*
Y876604D01*
G01X2349694Y874301D02*
Y877057D01*
G01X2349376Y915896D02*
Y935187D01*
G01X2349324Y921919D02*
Y919714D01*
G01X2349305Y918258D02*
Y917077D01*
G01Y921407D02*
Y920226D01*
G01X2348898Y915896D02*
Y919714D01*
G01X2348743Y884990D02*
Y884203D01*
G01Y888140D02*
Y887352D01*
G01Y891289D02*
Y890502D01*
G01Y894439D02*
Y893651D01*
G01Y897588D02*
Y896801D01*
G01Y900738D02*
Y899951D01*
G01Y903888D02*
Y903100D01*
G01Y907037D02*
Y906250D01*
G01Y910187D02*
Y909400D01*
G01Y913337D02*
Y912549D01*
G01Y916486D02*
Y915699D01*
G01Y919636D02*
Y918848D01*
G01X2348638Y865955D02*
Y853022D01*
G01X2347772Y883829D02*
Y882254D01*
G01Y888829D02*
Y887254D01*
G01Y893829D02*
Y892254D01*
G01Y898829D02*
Y897254D01*
G01Y903829D02*
Y902254D01*
G01Y908829D02*
Y907254D01*
G01Y913829D02*
Y912254D01*
G01X2347441Y919714D02*
Y921919D01*
G01X2347091Y915699D02*
Y916486D01*
G01Y918848D02*
Y919636D01*
G01Y912549D02*
Y913337D01*
G01Y906250D02*
Y907037D01*
G01Y909400D02*
Y910187D01*
G01Y903100D02*
Y903888D01*
G01Y896801D02*
Y897588D01*
G01Y899951D02*
Y900738D01*
G01Y893651D02*
Y894439D01*
G01Y890502D02*
Y891289D01*
G01Y884203D02*
Y884990D01*
G01Y887352D02*
Y888140D01*
G01X2346807Y884045D02*
Y882077D01*
G01X2345363Y887352D02*
Y884990D01*
G01Y884203D02*
Y881624D01*
G01Y890502D02*
Y888140D01*
G01Y893651D02*
Y891289D01*
G01Y896801D02*
Y894439D01*
G01Y899951D02*
Y897588D01*
G01Y903100D02*
Y900738D01*
G01Y906250D02*
Y903888D01*
G01Y909400D02*
Y907037D01*
G01Y912549D02*
Y910187D01*
G01Y915699D02*
Y913337D01*
G01Y918848D02*
Y916486D01*
G01Y921998D02*
Y919636D01*
G01X2344424Y915699D02*
Y916486D01*
G01Y918848D02*
Y919636D01*
G01Y912549D02*
Y913337D01*
G01Y906250D02*
Y907037D01*
G01Y909400D02*
Y910187D01*
G01Y903100D02*
Y903888D01*
G01Y896801D02*
Y897588D01*
G01Y899951D02*
Y900738D01*
G01Y893651D02*
Y894439D01*
G01Y890502D02*
Y891289D01*
G01Y884203D02*
Y884990D01*
G01Y887352D02*
Y888140D01*
G01X2344277Y915699D02*
Y916486D01*
G01Y918848D02*
Y919636D01*
G01Y912549D02*
Y913337D01*
G01Y906250D02*
Y907037D01*
G01Y909400D02*
Y910187D01*
G01Y903100D02*
Y903888D01*
G01Y896801D02*
Y897588D01*
G01Y899951D02*
Y900738D01*
G01Y893651D02*
Y894439D01*
G01Y890502D02*
Y891289D01*
G01Y884203D02*
Y884990D01*
G01Y887352D02*
Y888140D01*
G01X2342685Y915699D02*
Y916486D01*
G01Y918848D02*
Y919636D01*
G01Y912549D02*
Y913337D01*
G01Y906250D02*
Y907037D01*
G01Y909400D02*
Y910187D01*
G01Y903100D02*
Y903888D01*
G01Y896801D02*
Y897588D01*
G01Y899951D02*
Y900738D01*
G01Y893651D02*
Y894439D01*
G01Y890502D02*
Y891289D01*
G01Y884203D02*
Y884990D01*
G01Y887352D02*
Y888140D01*
G01X2342330Y1014025D02*
Y877057D01*
G01X2341820Y874301D02*
Y877057D01*
G01X2341743Y884990D02*
Y884203D01*
G01Y888140D02*
Y887352D01*
G01Y891289D02*
Y890502D01*
G01Y894439D02*
Y893651D01*
G01Y897588D02*
Y896801D01*
G01Y900738D02*
Y899951D01*
G01Y903888D02*
Y903100D01*
G01Y907037D02*
Y906250D01*
G01Y910187D02*
Y909400D01*
G01Y913337D02*
Y912549D01*
G01Y916486D02*
Y915699D01*
G01Y919636D02*
Y918848D01*
G01X2340648Y872416D02*
Y873081D01*
G01X2338907Y884990D02*
Y884203D01*
G01Y888140D02*
Y887352D01*
G01Y891289D02*
Y890502D01*
G01Y894439D02*
Y893651D01*
G01Y897588D02*
Y896801D01*
G01Y900738D02*
Y899951D01*
G01Y903888D02*
Y903100D01*
G01Y907037D02*
Y906250D01*
G01Y910187D02*
Y909400D01*
G01Y913337D02*
Y912549D01*
G01Y916486D02*
Y915699D01*
G01Y919636D02*
Y918848D01*
G01X2338718Y915699D02*
Y916486D01*
G01Y918848D02*
Y919636D01*
G01Y912549D02*
Y913337D01*
G01Y906250D02*
Y907037D01*
G01Y909400D02*
Y910187D01*
G01Y903100D02*
Y903888D01*
G01Y896801D02*
Y897588D01*
G01Y899951D02*
Y900738D01*
G01Y893651D02*
Y894439D01*
G01Y890502D02*
Y891289D01*
G01Y884203D02*
Y884990D01*
G01Y887352D02*
Y888140D01*
G01X2336945Y915699D02*
Y916486D01*
G01Y918848D02*
Y919636D01*
G01Y912549D02*
Y913337D01*
G01Y906250D02*
Y907037D01*
G01Y909400D02*
Y910187D01*
G01Y903100D02*
Y903888D01*
G01Y896801D02*
Y897588D01*
G01Y899951D02*
Y900738D01*
G01Y893651D02*
Y894439D01*
G01Y890502D02*
Y891289D01*
G01Y884203D02*
Y884990D01*
G01Y887352D02*
Y888140D01*
G01X2336809Y873081D02*
Y872342D01*
G01X2335966Y879636D02*
Y877057D01*
G01X2335491Y879636D02*
Y874301D01*
G01X2335173Y879636D02*
Y865955D01*
G01X2361492Y882418D02*
X2361405Y882844D01*
G01X2360882Y882759D02*
X2360969Y882418D01*
G01X2357398Y881906D02*
X2357485Y881565D01*
G01X2358007Y881650D02*
X2357920Y881906D01*
G01X2361405Y882844D02*
X2361231Y883186D01*
G01X2357485Y881565D02*
X2357659Y881224D01*
G01X2350078Y877057D02*
X2350333Y876663D01*
G01X2360708Y883015D02*
X2360882Y882759D01*
G01X2358182Y881394D02*
X2358007Y881650D01*
G01X2354796Y872093D02*
X2354978Y871828D01*
X2355043Y871529D01*
X2354978Y871232D01*
G01X2347792Y870432D02*
X2347469Y870851D01*
X2347307Y871334D01*
X2347328Y871839D01*
X2347531Y872316D01*
X2347898Y872719D01*
X2348404Y872987D01*
X2348995Y873081D01*
X2349585Y872984D01*
X2350087Y872715D01*
X2350451Y872311D01*
X2350652Y871833D01*
X2350672Y871328D01*
X2350508Y870847D01*
X2350187Y870432D01*
G01X2342624D02*
X2342302Y870851D01*
X2342139Y871334D01*
X2342161Y871839D01*
X2342364Y872316D01*
X2342731Y872719D01*
X2343237Y872987D01*
X2343828Y873081D01*
X2344417Y872984D01*
X2344920Y872715D01*
X2345284Y872311D01*
X2345485Y871833D01*
X2345504Y871328D01*
X2345340Y870847D01*
X2345020Y870432D01*
G01X2361231Y883186D02*
X2360882Y883527D01*
G01X2357659Y881224D02*
X2358007Y880882D01*
G01X2350187Y870432D02*
X2350639Y869991D01*
X2350909Y869456D01*
X2350979Y868885D01*
X2350838Y868321D01*
X2350491Y867797D01*
X2349964Y867403D01*
X2349321Y867200D01*
X2348642Y867202D01*
X2348002Y867410D01*
X2347479Y867807D01*
X2347137Y868330D01*
X2346999Y868891D01*
X2347071Y869459D01*
X2347341Y869993D01*
G01X2345020Y870432D02*
X2345472Y869991D01*
X2345742Y869456D01*
X2345812Y868885D01*
X2345670Y868321D01*
X2345324Y867797D01*
X2344796Y867403D01*
X2344154Y867200D01*
X2343474Y867202D01*
X2342834Y867410D01*
X2342312Y867807D01*
X2341970Y868330D01*
X2341832Y868891D01*
X2341904Y869459D01*
X2342174Y869993D01*
G01X2358094Y884892D02*
X2358704Y884380D01*
G01X2358007D02*
X2357398Y884892D01*
G01X2349413Y869976D02*
X2349773Y869740D01*
X2350011Y869390D01*
X2350097Y868986D01*
X2350014Y868584D01*
X2349778Y868232D01*
X2349414Y867992D01*
X2348990Y867907D01*
G01X2348567Y867991D02*
X2348206Y868227D01*
X2347968Y868577D01*
X2347882Y868981D01*
X2347965Y869383D01*
X2348201Y869735D01*
X2348565Y869975D01*
X2348990Y870060D01*
G01X2344245Y869976D02*
X2344606Y869740D01*
X2344844Y869390D01*
X2344929Y868986D01*
X2344847Y868584D01*
X2344610Y868232D01*
X2344247Y867992D01*
X2343822Y867907D01*
G01X2343399Y867991D02*
X2343039Y868227D01*
X2342800Y868577D01*
X2342715Y868981D01*
X2342798Y869383D01*
X2343034Y869735D01*
X2343397Y869975D01*
X2343822Y870060D01*
G01X2360447Y883186D02*
X2360708Y883015D01*
G01X2354516Y872273D02*
X2354796Y872092D01*
G01X2349338Y872277D02*
X2349621Y872100D01*
X2349808Y871834D01*
X2349875Y871533D01*
X2349811Y871232D01*
X2349625Y870965D01*
X2349340Y870784D01*
X2348990Y870718D01*
G01X2348641Y870783D02*
X2348358Y870961D01*
X2348171Y871226D01*
X2348104Y871528D01*
X2348168Y871829D01*
X2348354Y872095D01*
X2348639Y872277D01*
X2348990Y872342D01*
G01X2344171Y872277D02*
X2344454Y872100D01*
X2344641Y871834D01*
X2344708Y871533D01*
X2344644Y871232D01*
X2344458Y870965D01*
X2344173Y870784D01*
X2343822Y870718D01*
G01X2343473Y870783D02*
X2343191Y870961D01*
X2343004Y871226D01*
X2342937Y871528D01*
X2343001Y871829D01*
X2343186Y872095D01*
X2343472Y872277D01*
X2343822Y872342D01*
G01X2360882Y883527D02*
X2360534Y883697D01*
G01X2358443Y881309D02*
X2358182Y881394D01*
G01X2358007Y880882D02*
X2358356Y880797D01*
G01X2354169Y872342D02*
X2354517Y872273D01*
G01X2355331Y920226D02*
X2349305D01*
G01X2354424Y920029D02*
X2353439D01*
G01X2354424Y919833D02*
X2353439D01*
G01X2347441Y919714D02*
X2349324D01*
G01X2344277Y919636D02*
X2336945D01*
G01X2356433D02*
X2344424D01*
G01Y918848D02*
X2356433D01*
G01X2336945D02*
X2344277D01*
G01X2354424Y918651D02*
X2353439D01*
G01X2354424Y918455D02*
X2353439D01*
G01X2355331Y918258D02*
X2349305D01*
G01X2355331Y917077D02*
X2349305D01*
G01X2354424Y916880D02*
X2353439D01*
G01X2354424Y916683D02*
X2353439D01*
G01X2344277Y916486D02*
X2336945D01*
G01X2356433D02*
X2344424D01*
G01X2353439Y916388D02*
X2351315D01*
G01X2348898Y915896D02*
X2356433D01*
G01X2380673Y915797D02*
X2358480D01*
G01X2356433Y915777D02*
X2355331D01*
G01X2385173D02*
X2366669D01*
G01X2344424Y915699D02*
X2356433D01*
G01X2336945D02*
X2344277D01*
G01X2352890Y914616D02*
X2351905D01*
G01X2352890Y914419D02*
X2351905D01*
G01X2352890Y914025D02*
X2351905D01*
G01X2347772Y913829D02*
X2354937D01*
G01X2385173Y913435D02*
X2358480D01*
G01X2344277Y913337D02*
X2336945D01*
G01X2356433D02*
X2344424D01*
G01Y912549D02*
X2356433D01*
G01X2336945D02*
X2344277D01*
G01X2347772Y912254D02*
X2354937D01*
G01X2352890Y912057D02*
X2351905D01*
G01X2352890Y911663D02*
X2351905D01*
G01X2352890Y911466D02*
X2351905D01*
G01X2344277Y910187D02*
X2336945D01*
G01X2356433D02*
X2344424D01*
G01X2352890Y909616D02*
X2351905D01*
G01X2386130Y909439D02*
X2366669D01*
G01X2352890Y909419D02*
X2351905D01*
G01X2344424Y909400D02*
X2356433D01*
G01X2336945D02*
X2344277D01*
G01X2352890Y909025D02*
X2351905D01*
G01X2347772Y908829D02*
X2354937D01*
G01X2347772Y907254D02*
X2354937D01*
G01X2352890Y907057D02*
X2351905D01*
G01X2344277Y907037D02*
X2336945D01*
G01X2356433D02*
X2344424D01*
G01X2352890Y906663D02*
X2351905D01*
G01X2352890Y906466D02*
X2351905D01*
G01X2344424Y906250D02*
X2356433D01*
G01X2336945D02*
X2344277D01*
G01X2352890Y904616D02*
X2351905D01*
G01X2352890Y904419D02*
X2351905D01*
G01X2352890Y904025D02*
X2351905D01*
G01X2344277Y903888D02*
X2336945D01*
G01X2356433D02*
X2344424D01*
G01X2347772Y903829D02*
X2354937D01*
G01X2344424Y903100D02*
X2356433D01*
G01X2336945D02*
X2344277D01*
G01X2347772Y902254D02*
X2354937D01*
G01X2352890Y902057D02*
X2351905D01*
G01X2352890Y901663D02*
X2351905D01*
G01X2352890Y901466D02*
X2351905D01*
G01X2344277Y900738D02*
X2336945D01*
G01X2356433D02*
X2344424D01*
G01Y899951D02*
X2356433D01*
G01X2336945D02*
X2344277D01*
G01X2352890Y899616D02*
X2351905D01*
G01X2352890Y899419D02*
X2351905D01*
G01X2352890Y899025D02*
X2351905D01*
G01X2347772Y898829D02*
X2354937D01*
G01X2385173Y898199D02*
X2358480D01*
G01X2344277Y897588D02*
X2336945D01*
G01X2356433D02*
X2344424D01*
G01X2347772Y897254D02*
X2354937D01*
G01X2352890Y897057D02*
X2351905D01*
G01X2344424Y896801D02*
X2356433D01*
G01X2336945D02*
X2344277D01*
G01X2352890Y896663D02*
X2351905D01*
G01X2352890Y896466D02*
X2351905D01*
G01X2385173Y895837D02*
X2358480D01*
G01X2352890Y894616D02*
X2351905D01*
G01X2344277Y894439D02*
X2336945D01*
G01X2356433D02*
X2344424D01*
G01X2352890Y894419D02*
X2351905D01*
G01X2352890Y894025D02*
X2351905D01*
G01X2347772Y893829D02*
X2354937D01*
G01X2344424Y893651D02*
X2356433D01*
G01X2336945D02*
X2344277D01*
G01X2347772Y892254D02*
X2354937D01*
G01X2352890Y892057D02*
X2351905D01*
G01X2352890Y891663D02*
X2351905D01*
G01X2352890Y891466D02*
X2351905D01*
G01X2344277Y891289D02*
X2336945D01*
G01X2356433D02*
X2344424D01*
G01Y890502D02*
X2356433D01*
G01X2336945D02*
X2344277D01*
G01X2352890Y889616D02*
X2351905D01*
G01X2352890Y889419D02*
X2351905D01*
G01X2352890Y889025D02*
X2351905D01*
G01X2347772Y888829D02*
X2354937D01*
G01X2344277Y888140D02*
X2336945D01*
G01X2356433D02*
X2344424D01*
G01Y887352D02*
X2356433D01*
G01X2336945D02*
X2344277D01*
G01X2347772Y887254D02*
X2354937D01*
G01X2352890Y887057D02*
X2351905D01*
G01X2352890Y886663D02*
X2351905D01*
G01X2352890Y886466D02*
X2351905D01*
G01X2357398Y885403D02*
X2361492D01*
G01X2344277Y884990D02*
X2336945D01*
G01X2356433D02*
X2344424D01*
G01X2361492Y884892D02*
X2358094D01*
G01X2352890Y884616D02*
X2351905D01*
G01X2352890Y884419D02*
X2351905D01*
G01X2358704Y884380D02*
X2358007D01*
G01X2344424Y884203D02*
X2356433D01*
G01X2336945D02*
X2344277D01*
G01X2354878Y884045D02*
X2346807D01*
G01X2352890Y884025D02*
X2351905D01*
G01X2347772Y883829D02*
X2354937D01*
G01X2360534Y883697D02*
X2360098D01*
G01X2360185Y883186D02*
X2360447D01*
G01X2347772Y882254D02*
X2354937D01*
G01X2346807Y882077D02*
X2354878D01*
G01X2352890Y882057D02*
X2351905D01*
G01X2352890Y881663D02*
X2351905D01*
G01X2351315Y881624D02*
X2342330D01*
G01X2352890Y881466D02*
X2351905D01*
G01X2358617Y881309D02*
X2358443D01*
G01X2358356Y880797D02*
X2358704D01*
G01X2355331Y880010D02*
X2364701D01*
G01X2355331Y879636D02*
X2335173D01*
G01X2365016Y879419D02*
X2358480D01*
G01X2385173Y879222D02*
X2366669D01*
G01X2356433Y878829D02*
X2387142D01*
G01X2355331Y878238D02*
X2364701D01*
G01X2335966Y877057D02*
X2356433D01*
G01X2350333Y876663D02*
X2356433D01*
G01Y876604D02*
X2350333D01*
G01X2358795Y876112D02*
X2335173D01*
G01X2385173Y874301D02*
X2335173D01*
G01Y873671D02*
X2358795D01*
G01X2340648Y873081D02*
X2336809D01*
G01X2361096D02*
X2357257D01*
G01Y872342D02*
X2360210D01*
G01X2336809D02*
X2339762D01*
G01X2358795Y871703D02*
X2335173D01*
G01X2352459Y871383D02*
X2353271D01*
G01X2358795Y867923D02*
X2335173D01*
G01X2356076Y867913D02*
X2353197D01*
G01X2357995Y867175D02*
X2358881D01*
G01X2352164D02*
X2356076D01*
G01X2337548D02*
X2338433D01*
G01X2362732Y867136D02*
X2389110D01*
G01Y865955D02*
X2335173D01*
G01X2365016Y863199D02*
X2348638D01*
G01X2354661Y860502D02*
X2358992D01*
G01X2354036Y859714D02*
X2359617D01*
G01Y858140D02*
X2354036D01*
G01X2358992Y857352D02*
X2354661D01*
G01X2365016Y853022D02*
X2348638D01*
G01X2358704Y880797D02*
X2359053Y880882D01*
G01X2360359Y880541D02*
X2360708Y880627D01*
G01X2354491Y921998D02*
Y922785D01*
G01X2354464Y921998D02*
Y922785D01*
G01X2354088Y921998D02*
Y922785D01*
G01X2350726D02*
Y921998D01*
G01X2348898Y921919D02*
Y929163D01*
G01X2348743Y922785D02*
Y921998D01*
G01X2347091D02*
Y922785D01*
G01X2344424Y921998D02*
Y922785D01*
G01X2344277Y921998D02*
Y922785D01*
G01X2342685Y921998D02*
Y922785D01*
G01X2341743D02*
Y921998D01*
G01X2338907Y922785D02*
Y921998D01*
G01X2338718D02*
Y922785D01*
G01X2336945Y921998D02*
Y922785D01*
G01X2344424Y921998D02*
X2356433D01*
G01X2336945D02*
X2344277D01*
G01X2349324Y921919D02*
X2347441D01*
G01X2354424Y921801D02*
X2353439D01*
G01X2354424Y921604D02*
X2353439D01*
G01X2355331Y921407D02*
X2349305D01*
G01X2354937Y988829D02*
G03X2355331Y989222I0J394D01*
G01Y986860D02*
G03X2354937Y987254I-394J0D01*
G01Y958829D02*
G03X2355331Y959222I0J394D01*
G01Y956860D02*
G03X2354937Y957254I-394J0D01*
G01Y943829D02*
G03X2355331Y944222I0J394D01*
G01Y941860D02*
G03X2354937Y942254I-394J0D01*
G01Y948829D02*
G03X2355331Y949222I0J394D01*
G01Y946860D02*
G03X2354937Y947254I-394J0D01*
G01Y968829D02*
G03X2355331Y969222I0J394D01*
G01Y966860D02*
G03X2354937Y967254I-394J0D01*
G01Y973829D02*
G03X2355331Y974222I0J394D01*
G01Y971860D02*
G03X2354937Y972254I-394J0D01*
G01Y983829D02*
G03X2355331Y984222I0J394D01*
G01Y981860D02*
G03X2354937Y982254I-394J0D01*
G01Y978829D02*
G03X2355331Y979222I0J394D01*
G01Y976860D02*
G03X2354937Y977254I-394J0D01*
G01Y963829D02*
G03X2355331Y964222I0J394D01*
G01Y961860D02*
G03X2354937Y962254I-394J0D01*
G01Y938829D02*
G03X2355331Y939222I0J394D01*
G01Y936860D02*
G03X2354937Y937254I-394J0D01*
G01X2360449Y975246D02*
Y991781D01*
G01Y956348D02*
Y972884D01*
G01Y937648D02*
Y953986D01*
G01X2354858Y954616D02*
Y951466D01*
G01Y994616D02*
Y991466D01*
G01X2354491Y991289D02*
Y992077D01*
G01Y988140D02*
Y988927D01*
G01Y981840D02*
Y982628D01*
G01Y984990D02*
Y985777D01*
G01Y978691D02*
Y979478D01*
G01Y972392D02*
Y973179D01*
G01Y975541D02*
Y976329D01*
G01Y969242D02*
Y970029D01*
G01Y962943D02*
Y963730D01*
G01Y966092D02*
Y966880D01*
G01Y959793D02*
Y960581D01*
G01Y953494D02*
Y954281D01*
G01Y956644D02*
Y957431D01*
G01Y950344D02*
Y951132D01*
G01Y944045D02*
Y944833D01*
G01Y947195D02*
Y947982D01*
G01Y940896D02*
Y941683D01*
G01Y934596D02*
Y935384D01*
G01Y937746D02*
Y938533D01*
G01Y931447D02*
Y932234D01*
G01Y925148D02*
Y925935D01*
G01Y928297D02*
Y929085D01*
G01X2354464Y991289D02*
Y992077D01*
G01Y988140D02*
Y988927D01*
G01Y981840D02*
Y982628D01*
G01Y984990D02*
Y985777D01*
G01Y978691D02*
Y979478D01*
G01Y972392D02*
Y973179D01*
G01Y975541D02*
Y976329D01*
G01Y969242D02*
Y970029D01*
G01Y962943D02*
Y963730D01*
G01Y966092D02*
Y966880D01*
G01Y959793D02*
Y960581D01*
G01Y953494D02*
Y954281D01*
G01Y956644D02*
Y957431D01*
G01Y950344D02*
Y951132D01*
G01Y944045D02*
Y944833D01*
G01Y947195D02*
Y947982D01*
G01Y940896D02*
Y941683D01*
G01Y934596D02*
Y935384D01*
G01Y937746D02*
Y938533D01*
G01Y931447D02*
Y932234D01*
G01Y925148D02*
Y925935D01*
G01Y928297D02*
Y929085D01*
G01X2354424Y925148D02*
Y922785D01*
G01Y928297D02*
Y925935D01*
G01Y931447D02*
Y929085D01*
G01Y934596D02*
Y932234D01*
G01X2354088Y991289D02*
Y992077D01*
G01Y988140D02*
Y988927D01*
G01Y981840D02*
Y982628D01*
G01Y984990D02*
Y985777D01*
G01Y978691D02*
Y979478D01*
G01Y972392D02*
Y973179D01*
G01Y975541D02*
Y976329D01*
G01Y969242D02*
Y970029D01*
G01Y962943D02*
Y963730D01*
G01Y966092D02*
Y966880D01*
G01Y959793D02*
Y960581D01*
G01Y953494D02*
Y954281D01*
G01Y956644D02*
Y957431D01*
G01Y950344D02*
Y951132D01*
G01Y944045D02*
Y944833D01*
G01Y947195D02*
Y947982D01*
G01Y940896D02*
Y941683D01*
G01Y934596D02*
Y935384D01*
G01Y937746D02*
Y938533D01*
G01Y931447D02*
Y932234D01*
G01Y925148D02*
Y925935D01*
G01Y928297D02*
Y929085D01*
G01X2353874Y938829D02*
Y937254D01*
G01Y943829D02*
Y942254D01*
G01Y948829D02*
Y947254D01*
G01Y954616D02*
Y951466D01*
G01Y958829D02*
Y957254D01*
G01Y963829D02*
Y962254D01*
G01Y968829D02*
Y967254D01*
G01Y973829D02*
Y972254D01*
G01Y978829D02*
Y977254D01*
G01Y983829D02*
Y982254D01*
G01Y988829D02*
Y987254D01*
G01Y994616D02*
Y991466D01*
G01X2352890Y939616D02*
Y936466D01*
G01Y944616D02*
Y941466D01*
G01Y949616D02*
Y946466D01*
G01Y953829D02*
Y952254D01*
G01Y959616D02*
Y956466D01*
G01Y964616D02*
Y961466D01*
G01Y969616D02*
Y966466D01*
G01Y974616D02*
Y971466D01*
G01Y979616D02*
Y976466D01*
G01Y984616D02*
Y981466D01*
G01Y989616D02*
Y986466D01*
G01Y993829D02*
Y992254D01*
G01X2352455Y924557D02*
Y923376D01*
G01Y927707D02*
Y926525D01*
G01Y934006D02*
Y932825D01*
G01Y930856D02*
Y929675D01*
G01X2351905Y939616D02*
Y936466D01*
G01Y944616D02*
Y941466D01*
G01Y949616D02*
Y946466D01*
G01Y959616D02*
Y956466D01*
G01Y964616D02*
Y961466D01*
G01Y969616D02*
Y966466D01*
G01Y974616D02*
Y971466D01*
G01Y979616D02*
Y976466D01*
G01Y984616D02*
Y981466D01*
G01Y989616D02*
Y986466D01*
G01X2350921Y938829D02*
Y937254D01*
G01Y943829D02*
Y942254D01*
G01Y948829D02*
Y947254D01*
G01Y958829D02*
Y957254D01*
G01Y963829D02*
Y962254D01*
G01Y968829D02*
Y967254D01*
G01Y973829D02*
Y972254D01*
G01Y978829D02*
Y977254D01*
G01Y983829D02*
Y982254D01*
G01Y988829D02*
Y987254D01*
G01X2350726Y925935D02*
Y925148D01*
G01Y929085D02*
Y928297D01*
G01Y932234D02*
Y931447D01*
G01Y935384D02*
Y934596D01*
G01Y938533D02*
Y937746D01*
G01Y941683D02*
Y940896D01*
G01Y944833D02*
Y944045D01*
G01Y947982D02*
Y947195D01*
G01Y951132D02*
Y950344D01*
G01Y954281D02*
Y953494D01*
G01Y957431D02*
Y956644D01*
G01Y960581D02*
Y959793D01*
G01Y963730D02*
Y962943D01*
G01Y966880D02*
Y966092D01*
G01Y970029D02*
Y969242D01*
G01Y973179D02*
Y972392D01*
G01Y976329D02*
Y975541D01*
G01Y979478D02*
Y978691D01*
G01Y982628D02*
Y981840D01*
G01Y985777D02*
Y984990D01*
G01Y988927D02*
Y988140D01*
G01Y992077D02*
Y991289D01*
G01X2349740Y953829D02*
Y952254D01*
G01Y993829D02*
Y992254D01*
G01X2349324Y931368D02*
Y929163D01*
G01X2349305Y924557D02*
Y923376D01*
G01Y927707D02*
Y926525D01*
G01Y934006D02*
Y932825D01*
G01Y930856D02*
Y929675D01*
G01X2348898Y931368D02*
Y935187D01*
G01X2348743Y925935D02*
Y925148D01*
G01Y929085D02*
Y928297D01*
G01Y932234D02*
Y931447D01*
G01Y935384D02*
Y934596D01*
G01Y938533D02*
Y937746D01*
G01Y941683D02*
Y940896D01*
G01Y944833D02*
Y944045D01*
G01Y947982D02*
Y947195D01*
G01Y951132D02*
Y950344D01*
G01Y954281D02*
Y953494D01*
G01Y957431D02*
Y956644D01*
G01Y960581D02*
Y959793D01*
G01Y963730D02*
Y962943D01*
G01Y966880D02*
Y966092D01*
G01Y970029D02*
Y969242D01*
G01Y973179D02*
Y972392D01*
G01Y976329D02*
Y975541D01*
G01Y979478D02*
Y978691D01*
G01Y982628D02*
Y981840D01*
G01Y985777D02*
Y984990D01*
G01Y988927D02*
Y988140D01*
G01Y992077D02*
Y991289D01*
G01X2347772Y938829D02*
Y937254D01*
G01Y943829D02*
Y942254D01*
G01Y948829D02*
Y947254D01*
G01Y958829D02*
Y957254D01*
G01Y963829D02*
Y962254D01*
G01Y968829D02*
Y967254D01*
G01Y973829D02*
Y972254D01*
G01Y978829D02*
Y977254D01*
G01Y983829D02*
Y982254D01*
G01Y988829D02*
Y987254D01*
G01X2347441Y929163D02*
Y931368D01*
G01X2347091Y991289D02*
Y992077D01*
G01Y988140D02*
Y988927D01*
G01Y981840D02*
Y982628D01*
G01Y984990D02*
Y985777D01*
G01Y978691D02*
Y979478D01*
G01Y972392D02*
Y973179D01*
G01Y975541D02*
Y976329D01*
G01Y969242D02*
Y970029D01*
G01Y962943D02*
Y963730D01*
G01Y966092D02*
Y966880D01*
G01Y959793D02*
Y960581D01*
G01Y953494D02*
Y954281D01*
G01Y956644D02*
Y957431D01*
G01Y950344D02*
Y951132D01*
G01Y944045D02*
Y944833D01*
G01Y947195D02*
Y947982D01*
G01Y940896D02*
Y941683D01*
G01Y934596D02*
Y935384D01*
G01Y937746D02*
Y938533D01*
G01Y931447D02*
Y932234D01*
G01Y925148D02*
Y925935D01*
G01Y928297D02*
Y929085D01*
G01X2345363Y925148D02*
Y922785D01*
G01Y928297D02*
Y925935D01*
G01Y931447D02*
Y929085D01*
G01Y934596D02*
Y932234D01*
G01Y937746D02*
Y935384D01*
G01Y940896D02*
Y938533D01*
G01Y944045D02*
Y941683D01*
G01Y947195D02*
Y944833D01*
G01Y950344D02*
Y947982D01*
G01Y953494D02*
Y951132D01*
G01Y956644D02*
Y954281D01*
G01Y959793D02*
Y957431D01*
G01Y962943D02*
Y960581D01*
G01Y966092D02*
Y963730D01*
G01Y969242D02*
Y966880D01*
G01Y972392D02*
Y970029D01*
G01Y975541D02*
Y973179D01*
G01Y978691D02*
Y976329D01*
G01Y981840D02*
Y979478D01*
G01Y984990D02*
Y982628D01*
G01Y988140D02*
Y985777D01*
G01Y991289D02*
Y988927D01*
G01Y994439D02*
Y992077D01*
G01X2344424Y991289D02*
Y992077D01*
G01Y988140D02*
Y988927D01*
G01Y981840D02*
Y982628D01*
G01Y984990D02*
Y985777D01*
G01Y978691D02*
Y979478D01*
G01Y972392D02*
Y973179D01*
G01Y975541D02*
Y976329D01*
G01Y969242D02*
Y970029D01*
G01Y962943D02*
Y963730D01*
G01Y966092D02*
Y966880D01*
G01Y959793D02*
Y960581D01*
G01Y953494D02*
Y954281D01*
G01Y956644D02*
Y957431D01*
G01Y950344D02*
Y951132D01*
G01Y944045D02*
Y944833D01*
G01Y947195D02*
Y947982D01*
G01Y940896D02*
Y941683D01*
G01Y934596D02*
Y935384D01*
G01Y937746D02*
Y938533D01*
G01Y931447D02*
Y932234D01*
G01Y925148D02*
Y925935D01*
G01Y928297D02*
Y929085D01*
G01X2344277Y991289D02*
Y992077D01*
G01Y988140D02*
Y988927D01*
G01Y981840D02*
Y982628D01*
G01Y984990D02*
Y985777D01*
G01Y978691D02*
Y979478D01*
G01Y972392D02*
Y973179D01*
G01Y975541D02*
Y976329D01*
G01Y969242D02*
Y970029D01*
G01Y962943D02*
Y963730D01*
G01Y966092D02*
Y966880D01*
G01Y959793D02*
Y960581D01*
G01Y953494D02*
Y954281D01*
G01Y956644D02*
Y957431D01*
G01Y950344D02*
Y951132D01*
G01Y944045D02*
Y944833D01*
G01Y947195D02*
Y947982D01*
G01Y940896D02*
Y941683D01*
G01Y934596D02*
Y935384D01*
G01Y937746D02*
Y938533D01*
G01Y931447D02*
Y932234D01*
G01Y925148D02*
Y925935D01*
G01Y928297D02*
Y929085D01*
G01X2342685Y991289D02*
Y992077D01*
G01Y988140D02*
Y988927D01*
G01Y981840D02*
Y982628D01*
G01Y984990D02*
Y985777D01*
G01Y978691D02*
Y979478D01*
G01Y972392D02*
Y973179D01*
G01Y975541D02*
Y976329D01*
G01Y969242D02*
Y970029D01*
G01Y962943D02*
Y963730D01*
G01Y966092D02*
Y966880D01*
G01Y959793D02*
Y960581D01*
G01Y953494D02*
Y954281D01*
G01Y956644D02*
Y957431D01*
G01Y950344D02*
Y951132D01*
G01Y944045D02*
Y944833D01*
G01Y947195D02*
Y947982D01*
G01Y940896D02*
Y941683D01*
G01Y934596D02*
Y935384D01*
G01Y937746D02*
Y938533D01*
G01Y931447D02*
Y932234D01*
G01Y925148D02*
Y925935D01*
G01Y928297D02*
Y929085D01*
G01X2341743Y925935D02*
Y925148D01*
G01Y929085D02*
Y928297D01*
G01Y932234D02*
Y931447D01*
G01Y935384D02*
Y934596D01*
G01Y938533D02*
Y937746D01*
G01Y941683D02*
Y940896D01*
G01Y944833D02*
Y944045D01*
G01Y947982D02*
Y947195D01*
G01Y951132D02*
Y950344D01*
G01Y954281D02*
Y953494D01*
G01Y957431D02*
Y956644D01*
G01Y960581D02*
Y959793D01*
G01Y963730D02*
Y962943D01*
G01Y966880D02*
Y966092D01*
G01Y970029D02*
Y969242D01*
G01Y973179D02*
Y972392D01*
G01Y976329D02*
Y975541D01*
G01Y979478D02*
Y978691D01*
G01Y982628D02*
Y981840D01*
G01Y985777D02*
Y984990D01*
G01Y988927D02*
Y988140D01*
G01Y992077D02*
Y991289D01*
G01X2338907Y925935D02*
Y925148D01*
G01Y929085D02*
Y928297D01*
G01Y932234D02*
Y931447D01*
G01Y935384D02*
Y934596D01*
G01Y938533D02*
Y937746D01*
G01Y941683D02*
Y940896D01*
G01Y944833D02*
Y944045D01*
G01Y947982D02*
Y947195D01*
G01Y951132D02*
Y950344D01*
G01Y954281D02*
Y953494D01*
G01Y957431D02*
Y956644D01*
G01Y960581D02*
Y959793D01*
G01Y963730D02*
Y962943D01*
G01Y966880D02*
Y966092D01*
G01Y970029D02*
Y969242D01*
G01Y973179D02*
Y972392D01*
G01Y976329D02*
Y975541D01*
G01Y979478D02*
Y978691D01*
G01Y982628D02*
Y981840D01*
G01Y985777D02*
Y984990D01*
G01Y988927D02*
Y988140D01*
G01Y992077D02*
Y991289D01*
G01X2338718D02*
Y992077D01*
G01Y988140D02*
Y988927D01*
G01Y981840D02*
Y982628D01*
G01Y984990D02*
Y985777D01*
G01Y978691D02*
Y979478D01*
G01Y972392D02*
Y973179D01*
G01Y975541D02*
Y976329D01*
G01Y969242D02*
Y970029D01*
G01Y962943D02*
Y963730D01*
G01Y966092D02*
Y966880D01*
G01Y959793D02*
Y960581D01*
G01Y953494D02*
Y954281D01*
G01Y956644D02*
Y957431D01*
G01Y950344D02*
Y951132D01*
G01Y944045D02*
Y944833D01*
G01Y947195D02*
Y947982D01*
G01Y940896D02*
Y941683D01*
G01Y934596D02*
Y935384D01*
G01Y937746D02*
Y938533D01*
G01Y931447D02*
Y932234D01*
G01Y925148D02*
Y925935D01*
G01Y928297D02*
Y929085D01*
G01X2336945Y991289D02*
Y992077D01*
G01Y988140D02*
Y988927D01*
G01Y981840D02*
Y982628D01*
G01Y984990D02*
Y985777D01*
G01Y978691D02*
Y979478D01*
G01Y972392D02*
Y973179D01*
G01Y975541D02*
Y976329D01*
G01Y969242D02*
Y970029D01*
G01Y962943D02*
Y963730D01*
G01Y966092D02*
Y966880D01*
G01Y959793D02*
Y960581D01*
G01Y953494D02*
Y954281D01*
G01Y956644D02*
Y957431D01*
G01Y950344D02*
Y951132D01*
G01Y944045D02*
Y944833D01*
G01Y947195D02*
Y947982D01*
G01Y940896D02*
Y941683D01*
G01Y934596D02*
Y935384D01*
G01Y937746D02*
Y938533D01*
G01Y931447D02*
Y932234D01*
G01Y925148D02*
Y925935D01*
G01Y928297D02*
Y929085D01*
G01X2355331Y992254D02*
X2349740D01*
G01X2344277Y992077D02*
X2336945D01*
G01X2356433D02*
X2344424D01*
G01X2354858Y992057D02*
X2353874D01*
G01X2385173Y991781D02*
X2358480D01*
G01X2354858Y991663D02*
X2353874D01*
G01X2354858Y991466D02*
X2353874D01*
G01X2344424Y991289D02*
X2356433D01*
G01X2336945D02*
X2344277D01*
G01X2356433Y990837D02*
X2355331D01*
G01X2352890Y989616D02*
X2351905D01*
G01X2352890Y989419D02*
X2351905D01*
G01X2352890Y989025D02*
X2351905D01*
G01X2344277Y988927D02*
X2336945D01*
G01X2356433D02*
X2344424D01*
G01X2347772Y988829D02*
X2354937D01*
G01X2344424Y988140D02*
X2356433D01*
G01X2336945D02*
X2344277D01*
G01X2347772Y987254D02*
X2354937D01*
G01X2352890Y987057D02*
X2351905D01*
G01X2352890Y986663D02*
X2351905D01*
G01X2352890Y986466D02*
X2351905D01*
G01X2344277Y985777D02*
X2336945D01*
G01X2356433D02*
X2344424D01*
G01Y984990D02*
X2356433D01*
G01X2336945D02*
X2344277D01*
G01X2352890Y984616D02*
X2351905D01*
G01X2352890Y984419D02*
X2351905D01*
G01X2352890Y984025D02*
X2351905D01*
G01X2347772Y983829D02*
X2354937D01*
G01X2344277Y982628D02*
X2336945D01*
G01X2356433D02*
X2344424D01*
G01X2347772Y982254D02*
X2354937D01*
G01X2352890Y982057D02*
X2351905D01*
G01X2344424Y981840D02*
X2356433D01*
G01X2336945D02*
X2344277D01*
G01X2352890Y981663D02*
X2351905D01*
G01X2352890Y981466D02*
X2351905D01*
G01X2352890Y979616D02*
X2351905D01*
G01X2344277Y979478D02*
X2336945D01*
G01X2356433D02*
X2344424D01*
G01X2352890Y979419D02*
X2351905D01*
G01X2352890Y979025D02*
X2351905D01*
G01X2347772Y978829D02*
X2354937D01*
G01X2344424Y978691D02*
X2356433D01*
G01X2336945D02*
X2344277D01*
G01X2347772Y977254D02*
X2354937D01*
G01X2352890Y977057D02*
X2351905D01*
G01X2352890Y976663D02*
X2351905D01*
G01X2352890Y976466D02*
X2351905D01*
G01X2344277Y976329D02*
X2336945D01*
G01X2356433D02*
X2344424D01*
G01Y975541D02*
X2356433D01*
G01X2336945D02*
X2344277D01*
G01X2385173Y975246D02*
X2358480D01*
G01X2352890Y974616D02*
X2351905D01*
G01X2352890Y974419D02*
X2351905D01*
G01X2352890Y974025D02*
X2351905D01*
G01X2347772Y973829D02*
X2354937D01*
G01X2344277Y973179D02*
X2336945D01*
G01X2356433D02*
X2344424D01*
G01X2385173Y972884D02*
X2358480D01*
G01X2344424Y972392D02*
X2356433D01*
G01X2336945D02*
X2344277D01*
G01X2347772Y972254D02*
X2354937D01*
G01X2352890Y972057D02*
X2351905D01*
G01X2352890Y971663D02*
X2351905D01*
G01X2352890Y971466D02*
X2351905D01*
G01X2344277Y970029D02*
X2336945D01*
G01X2356433D02*
X2344424D01*
G01X2352890Y969616D02*
X2351905D01*
G01X2352890Y969419D02*
X2351905D01*
G01X2344424Y969242D02*
X2356433D01*
G01X2336945D02*
X2344277D01*
G01X2352890Y969025D02*
X2351905D01*
G01X2347772Y968829D02*
X2354937D01*
G01X2347772Y967254D02*
X2354937D01*
G01X2352890Y967057D02*
X2351905D01*
G01X2344277Y966880D02*
X2336945D01*
G01X2356433D02*
X2344424D01*
G01X2352890Y966663D02*
X2351905D01*
G01X2352890Y966466D02*
X2351905D01*
G01X2344424Y966092D02*
X2356433D01*
G01X2336945D02*
X2344277D01*
G01X2352890Y964616D02*
X2351905D01*
G01X2352890Y964419D02*
X2351905D01*
G01X2352890Y964025D02*
X2351905D01*
G01X2347772Y963829D02*
X2354937D01*
G01X2344277Y963730D02*
X2336945D01*
G01X2356433D02*
X2344424D01*
G01Y962943D02*
X2356433D01*
G01X2336945D02*
X2344277D01*
G01X2347772Y962254D02*
X2354937D01*
G01X2352890Y962057D02*
X2351905D01*
G01X2352890Y961663D02*
X2351905D01*
G01X2352890Y961466D02*
X2351905D01*
G01X2344277Y960581D02*
X2336945D01*
G01X2356433D02*
X2344424D01*
G01Y959793D02*
X2356433D01*
G01X2336945D02*
X2344277D01*
G01X2352890Y959616D02*
X2351905D01*
G01X2352890Y959419D02*
X2351905D01*
G01X2352890Y959025D02*
X2351905D01*
G01X2347772Y958829D02*
X2354937D01*
G01X2344277Y957431D02*
X2336945D01*
G01X2356433D02*
X2344424D01*
G01X2347772Y957254D02*
X2354937D01*
G01X2352890Y957057D02*
X2351905D01*
G01X2352890Y956663D02*
X2351905D01*
G01X2344424Y956644D02*
X2356433D01*
G01X2336945D02*
X2344277D01*
G01X2352890Y956466D02*
X2351905D01*
G01X2385173Y956348D02*
X2358480D01*
G01X2355331Y955246D02*
X2356433D01*
G01X2354858Y954616D02*
X2353874D01*
G01X2354858Y954419D02*
X2353874D01*
G01X2344277Y954281D02*
X2336945D01*
G01X2356433D02*
X2344424D01*
G01X2354858Y954025D02*
X2353874D01*
G01X2385173Y953986D02*
X2358480D01*
G01X2355331Y953829D02*
X2349740D01*
G01X2344424Y953494D02*
X2356433D01*
G01X2336945D02*
X2344277D01*
G01X2355331Y952254D02*
X2349740D01*
G01X2354858Y952057D02*
X2353874D01*
G01X2354858Y951663D02*
X2353874D01*
G01X2354858Y951466D02*
X2353874D01*
G01X2344277Y951132D02*
X2336945D01*
G01X2356433D02*
X2344424D01*
G01X2356433Y950837D02*
X2355331D01*
G01X2344424Y950344D02*
X2356433D01*
G01X2336945D02*
X2344277D01*
G01X2352890Y949616D02*
X2351905D01*
G01X2352890Y949419D02*
X2351905D01*
G01X2352890Y949025D02*
X2351905D01*
G01X2347772Y948829D02*
X2354937D01*
G01X2344277Y947982D02*
X2336945D01*
G01X2356433D02*
X2344424D01*
G01X2347772Y947254D02*
X2354937D01*
G01X2344424Y947195D02*
X2356433D01*
G01X2336945D02*
X2344277D01*
G01X2352890Y947057D02*
X2351905D01*
G01X2352890Y946663D02*
X2351905D01*
G01X2352890Y946466D02*
X2351905D01*
G01X2344277Y944833D02*
X2336945D01*
G01X2356433D02*
X2344424D01*
G01X2352890Y944616D02*
X2351905D01*
G01X2352890Y944419D02*
X2351905D01*
G01X2344424Y944045D02*
X2356433D01*
G01X2336945D02*
X2344277D01*
G01X2352890Y944025D02*
X2351905D01*
G01X2347772Y943829D02*
X2354937D01*
G01X2347772Y942254D02*
X2354937D01*
G01X2352890Y942057D02*
X2351905D01*
G01X2386130Y941742D02*
X2366669D01*
G01X2344277Y941683D02*
X2336945D01*
G01X2356433D02*
X2344424D01*
G01X2352890Y941663D02*
X2351905D01*
G01X2352890Y941466D02*
X2351905D01*
G01X2344424Y940896D02*
X2356433D01*
G01X2336945D02*
X2344277D01*
G01X2352890Y939616D02*
X2351905D01*
G01X2352890Y939419D02*
X2351905D01*
G01X2352890Y939025D02*
X2351905D01*
G01X2347772Y938829D02*
X2354937D01*
G01X2344277Y938533D02*
X2336945D01*
G01X2356433D02*
X2344424D01*
G01Y937746D02*
X2356433D01*
G01X2336945D02*
X2344277D01*
G01X2385173Y937648D02*
X2358480D01*
G01X2347772Y937254D02*
X2354937D01*
G01X2352890Y937057D02*
X2351905D01*
G01X2352890Y936663D02*
X2351905D01*
G01X2352890Y936466D02*
X2351905D01*
G01X2344277Y935384D02*
X2336945D01*
G01X2356433D02*
X2344424D01*
G01X2366669Y935305D02*
X2385173D01*
G01X2356433D02*
X2355331D01*
G01X2380673Y935285D02*
X2358480D01*
G01X2356433Y935187D02*
X2348898D01*
G01X2353439Y934695D02*
X2351315D01*
G01X2344424Y934596D02*
X2356433D01*
G01X2336945D02*
X2344277D01*
G01X2354424Y934400D02*
X2353439D01*
G01X2354424Y934203D02*
X2353439D01*
G01X2355331Y934006D02*
X2349305D01*
G01X2355331Y932825D02*
X2349305D01*
G01X2354424Y932628D02*
X2353439D01*
G01X2354424Y932431D02*
X2353439D01*
G01X2344277Y932234D02*
X2336945D01*
G01X2356433D02*
X2344424D01*
G01Y931447D02*
X2356433D01*
G01X2336945D02*
X2344277D01*
G01X2349324Y931368D02*
X2347441D01*
G01X2354424Y931250D02*
X2353439D01*
G01X2354424Y931053D02*
X2353439D01*
G01X2355331Y930856D02*
X2349305D01*
G01X2355331Y929675D02*
X2349305D01*
G01X2354424Y929478D02*
X2353439D01*
G01X2354424Y929281D02*
X2353439D01*
G01X2347441Y929163D02*
X2349324D01*
G01X2344277Y929085D02*
X2336945D01*
G01X2356433D02*
X2344424D01*
G01Y928297D02*
X2356433D01*
G01X2336945D02*
X2344277D01*
G01X2354424Y928100D02*
X2353439D01*
G01X2354424Y927903D02*
X2353439D01*
G01X2355331Y927707D02*
X2349305D01*
G01X2355331Y926525D02*
X2349305D01*
G01X2354424Y926329D02*
X2353439D01*
G01X2354424Y926132D02*
X2353439D01*
G01X2344277Y925935D02*
X2336945D01*
G01X2356433D02*
X2344424D01*
G01Y925148D02*
X2356433D01*
G01X2336945D02*
X2344277D01*
G01X2354424Y924951D02*
X2353439D01*
G01X2354424Y924754D02*
X2353439D01*
G01X2355331Y924557D02*
X2349305D01*
G01X2355331Y923376D02*
X2349305D01*
G01X2354424Y923179D02*
X2353439D01*
G01X2354424Y922982D02*
X2353439D01*
G01X2344277Y922785D02*
X2336945D01*
G01X2356433D02*
X2344424D01*
G01X2360449Y994144D02*
Y1011663D01*
G01X2354491Y994439D02*
Y995226D01*
G01X2354464Y994439D02*
Y995226D01*
G01X2354088Y994439D02*
Y995226D01*
G01X2350726D02*
Y994439D01*
G01X2348743Y995226D02*
Y994439D01*
G01X2347091D02*
Y995226D01*
G01X2345363Y997588D02*
Y995226D01*
G01X2344424Y994439D02*
Y995226D01*
G01X2344277Y994439D02*
Y995226D01*
G01X2342685Y994439D02*
Y995226D01*
G01X2341743D02*
Y994439D01*
G01X2338907Y995226D02*
Y994439D01*
G01X2338718D02*
Y995226D01*
G01X2336945Y994439D02*
Y995226D01*
G01X2356433Y995246D02*
X2355331D01*
G01X2344277Y995226D02*
X2336945D01*
G01X2356433D02*
X2344424D01*
G01X2354858Y994616D02*
X2353874D01*
G01X2344424Y994439D02*
X2356433D01*
G01X2336945D02*
X2344277D01*
G01X2354858Y994419D02*
X2353874D01*
G01X2385173Y994144D02*
X2358480D01*
G01X2354858Y994025D02*
X2353874D01*
G01X2355331Y993829D02*
X2349740D01*
G01X2358121Y1021201D02*
G03X2359551I715J0D01*
G01X2355231D02*
G03X2356661I715J0D01*
G01X2358992Y1030581D02*
G03Y1033730I0J1575D01*
G01X2354132Y1020126D02*
G03X2356768Y1020271I1248J1351D01*
G01D02*
G03X2359549Y1020276I1388J1206D01*
G01X2354937Y1008829D02*
G03X2355331Y1009222I0J394D01*
G01Y1006860D02*
G03X2354937Y1007254I-394J0D01*
G01Y998829D02*
G03X2355331Y999222I0J394D01*
G01Y996860D02*
G03X2354937Y997254I-394J0D01*
G01Y1003829D02*
G03X2355331Y1004222I0J394D01*
G01Y1001860D02*
G03X2354937Y1002254I-394J0D01*
G01X2353838Y1020797D02*
G03X2354132Y1020126I914J0D01*
G01X2354661Y1033730D02*
G03Y1030581I0J-1574D01*
G01X2350159Y1022617D02*
G03Y1020933I2236J-842D01*
G01X2351632Y1022617D02*
G03X2350159I-736J-277D01*
G01Y1020933D02*
G03X2351632I737J277D01*
G01X2352904Y1022952D02*
G03X2352383Y1023517I-1351J-723D01*
G01X2349337Y1023516D02*
G03X2348816Y1022950I831J-1288D01*
G01X2348817Y1020638D02*
G03X2349338Y1020073I1351J723D01*
G01X2352384D02*
G03X2352905Y1020638I-830J1288D01*
G01X2351632Y1020933D02*
G03Y1022617I-2237J842D01*
G01X2352905Y1020638D02*
G03X2352904Y1022952I-2163J1156D01*
G01X2348816Y1022950D02*
G03X2348817Y1020638I2163J-1155D01*
G01X2352383Y1023517D02*
G03X2349337Y1023516I-1522J-2362D01*
G01X2349338Y1020073D02*
G03X2352384I1523J2361D01*
G01X2349740Y1020344D02*
G03I-2165J0D01*
G01X2345620Y1023061D02*
G03Y1017628I1955J-2717D01*
G01X2349529D02*
G03Y1023061I-1954J2717D01*
G01X2351079Y1020344D02*
G03I-3504J0D01*
G01X2349878Y1016447D02*
G03Y1024242I-2304J3898D01*
G01X2345271D02*
G03Y1016447I2304J-3898D01*
G01X2343658Y1022935D02*
G03X2343068Y1022570I-9J-645D01*
G01X2344432Y1022127D02*
G03X2343658Y1022935I-792J16D01*
G01X2342407Y1023639D02*
G03X2341564Y1022570I704J-1422D01*
G01X2341772Y1020684D02*
G03X2343007Y1019710I1735J930D01*
G01X2344649Y1019754D02*
G03X2345814Y1020893I-729J1911D01*
G01X2345727Y1022909D02*
G03X2343989Y1023926I-1807J-1094D01*
G01X2343007Y1019711D02*
G03X2344649Y1019754I757J2475D01*
G01X2345988Y1022049D02*
G03X2345726Y1022911I-2971J-432D01*
G01X2341433Y1022127D02*
G03X2341772Y1020684I3015J-53D01*
G01X2345988Y1021553D02*
G03Y1022050I-3524J248D01*
G01X2345814Y1020893D02*
G03X2345988Y1021553I-4018J1412D01*
G01X2343007Y1021301D02*
G03X2344432I712J-82D01*
G01X2343992Y1023926D02*
G03X2342407Y1023639I-262J-3073D01*
G01X2338235Y1021571D02*
X2336940Y1019719D01*
G01X2339011Y1020705D02*
X2338322Y1019719D01*
G01X2341407Y1023726D02*
X2339965Y1021579D01*
G01X2350333Y1014419D02*
X2350078Y1014025D01*
G01X2339999Y1023726D02*
X2339208Y1022448D01*
G01X2345620Y1017628D02*
X2345603Y1017572D01*
X2345550Y1017407D01*
X2345472Y1017148D01*
X2345376Y1016821D01*
X2345271Y1016447D01*
G01X2349878Y1024242D02*
X2349775Y1023873D01*
X2349679Y1023543D01*
X2349599Y1023281D01*
X2349546Y1023115D01*
X2349529Y1023061D01*
G01X2365016Y1011663D02*
Y1038061D01*
G01X2364701Y1012844D02*
Y1011073D01*
G01X2362732Y1025128D02*
Y1016781D01*
G01X2360992Y1023726D02*
Y1019719D01*
G01X2359617Y1031368D02*
Y1032943D01*
G01X2359583D02*
Y1031368D01*
G01X2359558Y1032943D02*
Y1031368D01*
G01X2359551Y1021201D02*
Y1023726D01*
G01X2359549Y1020276D02*
Y1019719D01*
G01X2358795Y1017411D02*
Y1015010D01*
G01Y1023159D02*
Y1019380D01*
G01X2358235Y1031368D02*
Y1032943D01*
G01X2358121Y1023726D02*
Y1021201D01*
G01X2357865Y1032943D02*
Y1031368D01*
G01X2356661Y1021201D02*
Y1023726D01*
G01X2355788Y1031368D02*
Y1032943D01*
G01X2355418D02*
Y1031368D01*
G01X2355231Y1023726D02*
Y1021201D01*
G01X2354491Y1007037D02*
Y1007825D01*
G01Y1000738D02*
Y1001525D01*
G01Y1003888D02*
Y1004675D01*
G01Y997588D02*
Y998376D01*
G01X2354464Y1007037D02*
Y1007825D01*
G01Y1000738D02*
Y1001525D01*
G01Y1003888D02*
Y1004675D01*
G01Y997588D02*
Y998376D01*
G01X2354095Y1031368D02*
Y1032943D01*
G01X2354088Y1007037D02*
Y1007825D01*
G01Y1000738D02*
Y1001525D01*
G01Y1003888D02*
Y1004675D01*
G01Y997588D02*
Y998376D01*
G01X2354071Y1031368D02*
Y1032943D01*
G01X2354036D02*
Y1031368D01*
G01X2353874Y998829D02*
Y997254D01*
G01Y1003829D02*
Y1002254D01*
G01Y1008829D02*
Y1007254D01*
G01X2353838Y1023726D02*
Y1020797D01*
G01X2352890Y999616D02*
Y996466D01*
G01Y1004616D02*
Y1001466D01*
G01Y1009616D02*
Y1006466D01*
G01Y1016781D02*
Y1014478D01*
G01X2351905Y999616D02*
Y996466D01*
G01Y1004616D02*
Y1001466D01*
G01Y1009616D02*
Y1006466D01*
G01X2350921Y998829D02*
Y997254D01*
G01Y1003829D02*
Y1002254D01*
G01Y1008829D02*
Y1007254D01*
G01X2350726Y998376D02*
Y997588D01*
G01Y1001525D02*
Y1000738D01*
G01Y1004675D02*
Y1003888D01*
G01Y1007825D02*
Y1007037D01*
G01X2350333Y1014478D02*
Y1014419D01*
G01X2349694Y1014025D02*
Y1016781D01*
G01X2348743Y998376D02*
Y997588D01*
G01Y1001525D02*
Y1000738D01*
G01Y1004675D02*
Y1003888D01*
G01Y1007825D02*
Y1007037D01*
G01X2348638Y1038061D02*
Y1025128D01*
G01X2348039Y1023726D02*
Y1017972D01*
G01X2347772Y998829D02*
Y997254D01*
G01Y1003829D02*
Y1002254D01*
G01Y1008829D02*
Y1007254D01*
G01X2347091Y1007037D02*
Y1007825D01*
G01Y1000738D02*
Y1001525D01*
G01Y1003888D02*
Y1004675D01*
G01Y997588D02*
Y998376D01*
G01X2346579Y1023726D02*
Y1017972D01*
G01X2345363Y1000738D02*
Y998376D01*
G01Y1003888D02*
Y1001525D01*
G01Y1007037D02*
Y1004675D01*
G01Y1009498D02*
Y1007825D01*
G01X2344424Y1007037D02*
Y1007825D01*
G01Y1000738D02*
Y1001525D01*
G01Y1003888D02*
Y1004675D01*
G01Y997588D02*
Y998376D01*
G01X2344277Y1007037D02*
Y1007825D01*
G01Y1000738D02*
Y1001525D01*
G01Y1003888D02*
Y1004675D01*
G01Y997588D02*
Y998376D01*
G01X2342685Y1007037D02*
Y1007825D01*
G01Y1000738D02*
Y1001525D01*
G01Y1003888D02*
Y1004675D01*
G01Y997588D02*
Y998376D01*
G01X2341820Y1014025D02*
Y1016781D01*
G01X2341743Y998376D02*
Y997588D01*
G01Y1001525D02*
Y1000738D01*
G01Y1004675D02*
Y1003888D01*
G01Y1007825D02*
Y1007037D01*
G01X2338907Y998376D02*
Y997588D01*
G01Y1001525D02*
Y1000738D01*
G01Y1004675D02*
Y1003888D01*
G01Y1007825D02*
Y1007037D01*
G01X2338718D02*
Y1007825D01*
G01Y1000738D02*
Y1001525D01*
G01Y1003888D02*
Y1004675D01*
G01Y997588D02*
Y998376D01*
G01X2336945Y1007037D02*
Y1007825D01*
G01Y1000738D02*
Y1001525D01*
G01Y1003888D02*
Y1004675D01*
G01Y997588D02*
Y998376D01*
G01X2335966Y1014025D02*
Y1011250D01*
G01X2335491Y1016781D02*
Y1011250D01*
G01X2335173Y1025128D02*
Y1011250D01*
G01X2349529Y1017628D02*
X2349547Y1017572D01*
X2349599Y1017406D01*
X2349678Y1017148D01*
X2349774Y1016821D01*
X2349878Y1016447D01*
G01X2345620Y1023061D02*
X2345602Y1023117D01*
X2345550Y1023282D01*
X2345471Y1023541D01*
X2345376Y1023868D01*
X2345271Y1024242D01*
G01X2338463Y1023726D02*
X2339208Y1022448D01*
G01X2336914Y1023726D02*
X2338235Y1021571D01*
G01X2339011Y1020705D02*
X2339617Y1019719D01*
G01X2339965Y1021579D02*
X2341233Y1019719D01*
G01X2365016Y1038061D02*
X2348638D01*
G01X2354661Y1033730D02*
X2358992D01*
G01X2354036Y1032943D02*
X2359617D01*
G01Y1031368D02*
X2354036D01*
G01X2358992Y1030581D02*
X2354661D01*
G01X2365016Y1027884D02*
X2348638D01*
G01X2335173Y1025128D02*
X2389110D01*
G01X2349878Y1024242D02*
X2345271D01*
G01X2389110Y1023947D02*
X2362732D01*
G01X2338463Y1023726D02*
X2336914D01*
G01X2341407D02*
X2339999D01*
G01X2348039D02*
X2346579D01*
G01X2355231D02*
X2353838D01*
G01X2358121D02*
X2356661D01*
G01X2360992D02*
X2359551D01*
G01X2358795Y1023159D02*
X2335173D01*
G01X2345620Y1023061D02*
X2349529D01*
G01X2343067Y1022570D02*
X2341564D01*
G01X2344433Y1022127D02*
X2341433D01*
G01X2344432Y1021301D02*
X2343007D01*
G01X2338322Y1019719D02*
X2336940D01*
G01X2341233D02*
X2339617D01*
G01X2360992D02*
X2359549D01*
G01X2358795Y1019380D02*
X2335173D01*
G01X2348039Y1017972D02*
X2346579D01*
G01X2349529Y1017628D02*
X2345620D01*
G01X2358795Y1017411D02*
X2335173D01*
G01X2385173Y1016781D02*
X2335173D01*
G01X2345271Y1016447D02*
X2349878D01*
G01X2335173Y1015010D02*
X2358795D01*
G01X2350333Y1014478D02*
X2356433D01*
G01X2350333Y1014419D02*
X2356433D01*
G01X2335966Y1014025D02*
X2356433D01*
G01X2355331Y1012844D02*
X2364701D01*
G01X2387142Y1012254D02*
X2356433D01*
G01X2385173Y1011860D02*
X2366669D01*
G01X2365016Y1011663D02*
X2358480D01*
G01X2335173Y1011250D02*
X2355331D01*
G01Y1011073D02*
X2364701D01*
G01X2352890Y1009616D02*
X2351905D01*
G01X2351315Y1009498D02*
X2342330D01*
G01X2352890Y1009419D02*
X2351905D01*
G01X2352890Y1009025D02*
X2351905D01*
G01X2347772Y1008829D02*
X2354937D01*
G01X2344277Y1007825D02*
X2336945D01*
G01X2356433D02*
X2344424D01*
G01X2347772Y1007254D02*
X2354937D01*
G01X2352890Y1007057D02*
X2351905D01*
G01X2344424Y1007037D02*
X2356433D01*
G01X2336945D02*
X2344277D01*
G01X2352890Y1006663D02*
X2351905D01*
G01X2352890Y1006466D02*
X2351905D01*
G01X2344277Y1004675D02*
X2336945D01*
G01X2356433D02*
X2344424D01*
G01X2352890Y1004616D02*
X2351905D01*
G01X2352890Y1004419D02*
X2351905D01*
G01X2352890Y1004025D02*
X2351905D01*
G01X2344424Y1003888D02*
X2356433D01*
G01X2336945D02*
X2344277D01*
G01X2347772Y1003829D02*
X2354937D01*
G01X2347772Y1002254D02*
X2354937D01*
G01X2352890Y1002057D02*
X2351905D01*
G01X2352890Y1001663D02*
X2351905D01*
G01X2344277Y1001525D02*
X2336945D01*
G01X2356433D02*
X2344424D01*
G01X2352890Y1001466D02*
X2351905D01*
G01X2344424Y1000738D02*
X2356433D01*
G01X2336945D02*
X2344277D01*
G01X2352890Y999616D02*
X2351905D01*
G01X2352890Y999419D02*
X2351905D01*
G01X2352890Y999025D02*
X2351905D01*
G01X2347772Y998829D02*
X2354937D01*
G01X2344277Y998376D02*
X2336945D01*
G01X2356433D02*
X2344424D01*
G01Y997588D02*
X2356433D01*
G01X2336945D02*
X2344277D01*
G01X2347772Y997254D02*
X2354937D01*
G01X2352890Y997057D02*
X2351905D01*
G01X2352890Y996663D02*
X2351905D01*
G01X2352890Y996466D02*
X2351905D01*
G01X2353234Y1274953D02*
G03X2352164Y1273130I2809J-2874D01*
G01X2360210Y1277854D02*
G03X2357996Y1272687I6938J-6031D01*
G01X2361096Y1277928D02*
G03X2358881Y1272687I7141J-6107D01*
G01X2353739Y1274409D02*
G03X2353197Y1273425I1276J-1344D01*
G01X2349740Y1276250D02*
G03I-2165J0D01*
G01X2350921D02*
G03I-3346J0D01*
G01X2351079D02*
G03I-3504J0D01*
G01X2352102D02*
G03I-4527J0D01*
G01X2339762Y1277854D02*
G03X2337548Y1272687I6938J-6031D01*
G01X2340648Y1277928D02*
G03X2338433Y1272687I7142J-6107D01*
G01X2359976Y1245659D02*
G03Y1244478I0J-591D01*
G01Y1248415D02*
G03Y1247234I0J-590D01*
G01X2358992Y1262864D02*
G03Y1266014I0J1575D01*
G01X2353677Y1244478D02*
G03Y1245659I0J590D01*
G01Y1247234D02*
G03Y1248415I0J591D01*
G01X2354661Y1266014D02*
G03Y1262864I0J-1575D01*
G01X2365016Y1258533D02*
Y1284931D01*
G01X2364701Y1285522D02*
Y1283750D01*
G01X2350078Y1282569D02*
X2350333Y1282175D01*
G01X2354796Y1277605D02*
X2354978Y1277340D01*
X2355043Y1277041D01*
X2354978Y1276744D01*
G01X2353338Y1277347D02*
X2353271Y1277042D01*
G01X2352459D02*
X2352546Y1277519D01*
X2352793Y1277961D01*
X2353182Y1278313D01*
X2353688Y1278533D01*
X2354266Y1278589D01*
X2354829Y1278467D01*
X2355305Y1278185D01*
X2355644Y1277780D01*
X2355824Y1277323D01*
X2355839Y1276843D01*
X2355682Y1276373D01*
X2355368Y1275956D01*
G01X2362732Y1271466D02*
Y1279813D01*
G01X2361551Y1244183D02*
Y1246151D01*
G01Y1248711D02*
Y1246742D01*
G01X2361096Y1277928D02*
Y1278592D01*
G01X2359976Y1248415D02*
Y1249006D01*
G01Y1245659D02*
Y1247234D01*
G01Y1243888D02*
Y1244478D01*
G01X2359617Y1263651D02*
Y1265226D01*
G01X2359583D02*
Y1263651D01*
G01X2359558Y1265226D02*
Y1263651D01*
G01X2358992Y1243888D02*
Y1249006D01*
G01X2358795D02*
Y1243888D01*
G01Y1277214D02*
Y1273435D01*
G01Y1281624D02*
Y1279183D01*
G01X2358401Y1246742D02*
Y1248711D01*
G01Y1246151D02*
Y1244183D01*
G01X2358235Y1263651D02*
Y1265226D01*
G01X2357865D02*
Y1263651D01*
G01X2357257Y1278592D02*
Y1277854D01*
G01X2356433Y1419990D02*
Y1282116D01*
G01X2356076Y1272687D02*
Y1273425D01*
G01X2355788Y1263651D02*
Y1265226D01*
G01X2355418D02*
Y1263651D01*
G01X2355331Y1282569D02*
Y1419537D01*
G01X2355252Y1246742D02*
Y1248711D01*
G01Y1246151D02*
Y1244183D01*
G01X2354858Y1249006D02*
Y1243888D01*
G01X2354661D02*
Y1249006D01*
G01X2354095Y1263651D02*
Y1265226D01*
G01X2354071Y1263651D02*
Y1265226D01*
G01X2354036D02*
Y1263651D01*
G01X2353781Y1245407D02*
Y1244659D01*
G01X2353688D02*
Y1245280D01*
G01X2353677Y1244478D02*
Y1243888D01*
G01Y1247234D02*
Y1245659D01*
G01Y1249006D02*
Y1248415D01*
G01X2353594Y1245169D02*
Y1245296D01*
G01X2353271Y1276895D02*
Y1277042D01*
G01X2352890Y1282116D02*
Y1279813D01*
G01X2352459Y1277042D02*
Y1276895D01*
G01X2352164Y1273130D02*
Y1272687D01*
G01X2352102Y1244183D02*
Y1246151D01*
G01Y1248711D02*
Y1246742D01*
G01X2351315Y1282569D02*
Y1419537D01*
G01X2350333Y1282175D02*
Y1282116D01*
G01X2349694Y1279813D02*
Y1282569D01*
G01X2348638Y1271466D02*
Y1258533D01*
G01X2342330Y1419537D02*
Y1282569D01*
G01X2341820Y1279813D02*
Y1282569D01*
G01X2340648Y1277928D02*
Y1278592D01*
G01X2336809D02*
Y1277854D01*
G01X2335966Y1285148D02*
Y1282569D01*
G01X2335491Y1285148D02*
Y1279813D01*
G01X2335173Y1285148D02*
Y1271466D01*
G01X2347792Y1275943D02*
X2347469Y1276363D01*
X2347307Y1276846D01*
X2347328Y1277351D01*
X2347531Y1277828D01*
X2347898Y1278231D01*
X2348404Y1278499D01*
X2348995Y1278592D01*
X2349585Y1278495D01*
X2350087Y1278227D01*
X2350451Y1277823D01*
X2350652Y1277345D01*
X2350672Y1276840D01*
X2350508Y1276359D01*
X2350187Y1275943D01*
G01X2342624D02*
X2342302Y1276363D01*
X2342139Y1276846D01*
X2342161Y1277351D01*
X2342364Y1277828D01*
X2342731Y1278231D01*
X2343237Y1278499D01*
X2343828Y1278592D01*
X2344417Y1278495D01*
X2344920Y1278227D01*
X2345284Y1277823D01*
X2345485Y1277345D01*
X2345504Y1276840D01*
X2345340Y1276359D01*
X2345020Y1275943D01*
G01X2350187D02*
X2350639Y1275503D01*
X2350909Y1274967D01*
X2350979Y1274397D01*
X2350838Y1273833D01*
X2350491Y1273308D01*
X2349964Y1272915D01*
X2349321Y1272712D01*
X2348642Y1272714D01*
X2348002Y1272922D01*
X2347479Y1273318D01*
X2347137Y1273842D01*
X2346999Y1274403D01*
X2347071Y1274971D01*
X2347341Y1275505D01*
G01X2345020Y1275943D02*
X2345472Y1275503D01*
X2345742Y1274967D01*
X2345812Y1274397D01*
X2345670Y1273833D01*
X2345324Y1273308D01*
X2344796Y1272915D01*
X2344154Y1272712D01*
X2343474Y1272714D01*
X2342834Y1272922D01*
X2342312Y1273318D01*
X2341970Y1273842D01*
X2341832Y1274403D01*
X2341904Y1274971D01*
X2342174Y1275505D01*
G01X2355368Y1275956D02*
X2353739Y1274409D01*
G01X2347792Y1275943D02*
X2347340Y1275503D01*
X2347070Y1274967D01*
X2347000Y1274397D01*
X2347141Y1273833D01*
X2347488Y1273308D01*
X2348015Y1272915D01*
X2348658Y1272712D01*
X2349337Y1272714D01*
X2349977Y1272922D01*
X2350500Y1273318D01*
X2350842Y1273842D01*
X2350980Y1274403D01*
X2350908Y1274971D01*
X2350638Y1275505D01*
G01X2342624Y1275943D02*
X2342173Y1275503D01*
X2341903Y1274967D01*
X2341832Y1274397D01*
X2341974Y1273833D01*
X2342321Y1273308D01*
X2342848Y1272915D01*
X2343491Y1272712D01*
X2344170Y1272714D01*
X2344810Y1272922D01*
X2345333Y1273318D01*
X2345674Y1273842D01*
X2345812Y1274403D01*
X2345741Y1274971D01*
X2345470Y1275505D01*
G01X2354796Y1276480D02*
X2353234Y1274953D01*
G01X2353688Y1245280D02*
X2353594Y1245169D01*
G01Y1245296D02*
X2353688Y1245407D01*
G01X2350187Y1275943D02*
X2350510Y1276363D01*
X2350673Y1276846D01*
X2350651Y1277351D01*
X2350448Y1277828D01*
X2350081Y1278231D01*
X2349575Y1278499D01*
X2348984Y1278592D01*
X2348395Y1278495D01*
X2347892Y1278227D01*
X2347528Y1277823D01*
X2347327Y1277345D01*
X2347308Y1276840D01*
X2347471Y1276359D01*
X2347792Y1275943D01*
G01X2345020D02*
X2345343Y1276363D01*
X2345505Y1276846D01*
X2345484Y1277351D01*
X2345281Y1277828D01*
X2344914Y1278231D01*
X2344408Y1278499D01*
X2343816Y1278592D01*
X2343227Y1278495D01*
X2342725Y1278227D01*
X2342361Y1277823D01*
X2342159Y1277345D01*
X2342140Y1276840D01*
X2342304Y1276359D01*
X2342624Y1275943D01*
G01X2355368Y1275956D02*
X2355705Y1276417D01*
X2355850Y1276936D01*
X2355790Y1277453D01*
X2355539Y1277937D01*
X2355102Y1278332D01*
X2354529Y1278555D01*
X2353895Y1278574D01*
X2353310Y1278388D01*
X2352855Y1278035D01*
X2352563Y1277563D01*
X2352459Y1277042D01*
G01X2353528Y1277614D02*
X2353338Y1277346D01*
G01X2354796Y1276480D02*
X2354979Y1276746D01*
X2355043Y1277044D01*
X2354978Y1277341D01*
G01X2349413Y1275488D02*
X2349773Y1275252D01*
X2350011Y1274902D01*
X2350097Y1274498D01*
X2350014Y1274096D01*
X2349778Y1273744D01*
X2349414Y1273504D01*
X2348990Y1273419D01*
G01X2348567Y1273503D02*
X2348206Y1273739D01*
X2347968Y1274089D01*
X2347882Y1274493D01*
X2347965Y1274895D01*
X2348201Y1275247D01*
X2348565Y1275487D01*
X2348990Y1275572D01*
G01X2344245Y1275488D02*
X2344606Y1275252D01*
X2344844Y1274902D01*
X2344929Y1274498D01*
X2344847Y1274096D01*
X2344610Y1273744D01*
X2344247Y1273504D01*
X2343822Y1273419D01*
G01X2343399Y1273503D02*
X2343039Y1273739D01*
X2342800Y1274089D01*
X2342715Y1274493D01*
X2342798Y1274895D01*
X2343034Y1275247D01*
X2343397Y1275487D01*
X2343822Y1275572D01*
G01X2354516Y1277785D02*
X2354796Y1277604D01*
G01X2349338Y1277789D02*
X2349621Y1277611D01*
X2349808Y1277346D01*
X2349875Y1277044D01*
X2349811Y1276744D01*
X2349625Y1276477D01*
X2349340Y1276296D01*
X2348990Y1276230D01*
G01X2348641Y1276295D02*
X2348358Y1276473D01*
X2348171Y1276738D01*
X2348104Y1277040D01*
X2348168Y1277340D01*
X2348354Y1277607D01*
X2348639Y1277789D01*
X2348990Y1277854D01*
G01X2344171Y1277789D02*
X2344454Y1277611D01*
X2344641Y1277346D01*
X2344708Y1277044D01*
X2344644Y1276744D01*
X2344458Y1276477D01*
X2344173Y1276296D01*
X2343822Y1276230D01*
G01X2343473Y1276295D02*
X2343191Y1276473D01*
X2343004Y1276738D01*
X2342937Y1277040D01*
X2343001Y1277340D01*
X2343186Y1277607D01*
X2343472Y1277789D01*
X2343822Y1277854D01*
G01X2353528Y1277614D02*
X2353815Y1277792D01*
X2354169Y1277854D01*
G01X2349338Y1276295D02*
X2349621Y1276473D01*
X2349808Y1276738D01*
X2349875Y1277040D01*
X2349811Y1277340D01*
X2349625Y1277607D01*
X2349340Y1277789D01*
X2348990Y1277854D01*
G01X2348641Y1277789D02*
X2348358Y1277611D01*
X2348171Y1277346D01*
X2348104Y1277044D01*
X2348168Y1276744D01*
X2348354Y1276477D01*
X2348639Y1276296D01*
X2348990Y1276230D01*
G01X2344171Y1276295D02*
X2344454Y1276473D01*
X2344641Y1276738D01*
X2344708Y1277040D01*
X2344644Y1277340D01*
X2344458Y1277607D01*
X2344173Y1277789D01*
X2343822Y1277854D01*
G01X2343473Y1277789D02*
X2343191Y1277611D01*
X2343004Y1277346D01*
X2342937Y1277044D01*
X2343001Y1276744D01*
X2343186Y1276477D01*
X2343472Y1276296D01*
X2343822Y1276230D01*
G01X2349413Y1273503D02*
X2349773Y1273739D01*
X2350011Y1274089D01*
X2350097Y1274493D01*
X2350014Y1274895D01*
X2349778Y1275247D01*
X2349414Y1275487D01*
X2348990Y1275572D01*
G01X2348567Y1275488D02*
X2348206Y1275252D01*
X2347968Y1274902D01*
X2347882Y1274498D01*
X2347965Y1274096D01*
X2348201Y1273744D01*
X2348565Y1273504D01*
X2348990Y1273419D01*
G01X2344245Y1273503D02*
X2344606Y1273739D01*
X2344844Y1274089D01*
X2344929Y1274493D01*
X2344847Y1274895D01*
X2344610Y1275247D01*
X2344247Y1275487D01*
X2343822Y1275572D01*
G01X2343399Y1275488D02*
X2343039Y1275252D01*
X2342800Y1274902D01*
X2342715Y1274498D01*
X2342798Y1274096D01*
X2343034Y1273744D01*
X2343397Y1273504D01*
X2343822Y1273419D01*
G01X2354169Y1277854D02*
X2354517Y1277785D01*
G01X2356433Y1284340D02*
X2387142D01*
G01X2355331Y1283750D02*
X2364701D01*
G01X2335966Y1282569D02*
X2356433D01*
G01X2350333Y1282175D02*
X2356433D01*
G01Y1282116D02*
X2350333D01*
G01X2358795Y1281624D02*
X2335173D01*
G01X2385173Y1279813D02*
X2335173D01*
G01Y1279183D02*
X2358795D01*
G01X2340648Y1278592D02*
X2336809D01*
G01X2361096D02*
X2357257D01*
G01Y1277854D02*
X2360210D01*
G01X2336809D02*
X2339762D01*
G01X2358795Y1277214D02*
X2335173D01*
G01X2352459Y1276895D02*
X2353271D01*
G01X2358795Y1273435D02*
X2335173D01*
G01X2356076Y1273425D02*
X2353197D01*
G01X2357995Y1272687D02*
X2358881D01*
G01X2352164D02*
X2356076D01*
G01X2337548D02*
X2338433D01*
G01X2362732Y1272648D02*
X2389110D01*
G01Y1271466D02*
X2335173D01*
G01X2365016Y1268711D02*
X2348638D01*
G01X2354661Y1266014D02*
X2358992D01*
G01X2354036Y1265226D02*
X2359617D01*
G01Y1263651D02*
X2354036D01*
G01X2358992Y1262864D02*
X2354661D01*
G01X2365016Y1258533D02*
X2348638D01*
G01X2359976Y1249006D02*
X2353677D01*
G01X2358401Y1248711D02*
X2361551D01*
G01X2355252D02*
X2352102D01*
G01Y1246742D02*
X2355252D01*
G01X2361551D02*
X2358401D01*
G01X2352102Y1246151D02*
X2355252D01*
G01X2361551D02*
X2358401D01*
G01X2353688Y1245407D02*
X2353781D01*
G01Y1244659D02*
X2353688D01*
G01X2358401Y1244183D02*
X2361551D01*
G01X2355252D02*
X2352102D01*
G01X2353677Y1243888D02*
X2359976D01*
G01X2366669Y1417372D02*
Y1284734D01*
G01X2357485Y1287077D02*
X2357659Y1286735D01*
G01X2358182Y1286906D02*
X2358007Y1287162D01*
G01X2361144Y1286394D02*
X2361405Y1286821D01*
G01X2359401Y1286735D02*
X2359575Y1287077D01*
G01X2360969Y1287247D02*
X2360882Y1286906D01*
G01X2361405Y1286821D02*
X2361492Y1287247D01*
G01X2360449Y1301348D02*
Y1284931D01*
G01X2360359Y1286565D02*
Y1286053D01*
G01X2358480Y1284931D02*
Y1417175D01*
G01X2350860Y1285148D02*
Y1416762D01*
G01X2357659Y1286735D02*
X2358007Y1286394D01*
G01X2360882Y1286906D02*
X2360621Y1286650D01*
G01X2359053Y1286394D02*
X2359401Y1286735D01*
G01X2359053Y1287162D02*
X2358879Y1286906D01*
G01X2360708Y1286138D02*
X2361144Y1286394D01*
G01X2358443Y1286821D02*
X2358182Y1286906D01*
G01X2358007Y1286394D02*
X2358356Y1286309D01*
G01X2360621Y1286650D02*
X2360359Y1286565D01*
G01X2358879Y1286906D02*
X2358617Y1286821D01*
G01D02*
X2358443D01*
G01X2358356Y1286309D02*
X2358704D01*
G01X2355331Y1285522D02*
X2364701D01*
G01X2355331Y1285148D02*
X2335173D01*
G01X2365016Y1284931D02*
X2358480D01*
G01X2385173Y1284734D02*
X2366669D01*
G01X2358704Y1286309D02*
X2359053Y1286394D01*
G01X2360359Y1286053D02*
X2360708Y1286138D01*
G01X2354937Y1349340D02*
G03X2355331Y1349734I0J394D01*
G01Y1347372D02*
G03X2354937Y1347766I-394J0D01*
G01Y1354340D02*
G03X2355331Y1354734I0J394D01*
G01Y1352372D02*
G03X2354937Y1352766I-394J0D01*
G01Y1289340D02*
G03X2355331Y1289734I0J394D01*
G01Y1287372D02*
G03X2354937Y1287766I-394J0D01*
G01Y1319340D02*
G03X2355331Y1319734I0J394D01*
G01Y1317372D02*
G03X2354937Y1317766I-394J0D01*
G01Y1314340D02*
G03X2355331Y1314734I0J394D01*
G01Y1312372D02*
G03X2354937Y1312766I-394J0D01*
G01Y1344340D02*
G03X2355331Y1344734I0J394D01*
G01Y1342372D02*
G03X2354937Y1342766I-394J0D01*
G01Y1309340D02*
G03X2355331Y1309734I0J394D01*
G01Y1307372D02*
G03X2354937Y1307766I-394J0D01*
G01Y1299340D02*
G03X2355331Y1299734I0J394D01*
G01Y1297372D02*
G03X2354937Y1297766I-394J0D01*
G01Y1304340D02*
G03X2355331Y1304734I0J394D01*
G01Y1302372D02*
G03X2354937Y1302766I-394J0D01*
G01Y1294340D02*
G03X2355331Y1294734I0J394D01*
G01Y1292372D02*
G03X2354937Y1292766I-394J0D01*
G01X2361492Y1287930D02*
X2361405Y1288356D01*
G01X2360882Y1288271D02*
X2360969Y1287930D01*
G01X2357398Y1287418D02*
X2357485Y1287077D01*
G01X2358007Y1287162D02*
X2357920Y1287418D01*
G01X2361405Y1288356D02*
X2361231Y1288697D01*
G01X2360708Y1288527D02*
X2360882Y1288271D01*
G01X2359401Y1288697D02*
X2359227Y1288356D01*
G01X2359140Y1287418D02*
X2359053Y1287162D01*
G01X2357920Y1287930D02*
X2358007Y1288186D01*
G01X2359575Y1287077D02*
X2359663Y1287418D01*
G01Y1287930D02*
X2359750Y1288271D01*
G01X2359227Y1288356D02*
X2359140Y1287930D01*
G01X2357485Y1288271D02*
X2357398Y1287844D01*
G01X2361492Y1287247D02*
Y1287930D01*
G01Y1290915D02*
Y1290403D01*
G01X2360969Y1287930D02*
Y1287247D01*
G01X2360449Y1343159D02*
Y1359498D01*
G01Y1318947D02*
Y1303711D01*
G01Y1340797D02*
Y1321309D01*
G01X2359663Y1287418D02*
Y1287930D01*
G01X2359140D02*
Y1287418D01*
G01X2358356Y1288442D02*
Y1288953D01*
G01X2357920Y1287418D02*
Y1287930D01*
G01X2357398Y1290403D02*
Y1290915D01*
G01Y1287844D02*
Y1287418D01*
G01X2355252Y1340699D02*
Y1321407D01*
G01X2354937D02*
Y1340699D01*
G01X2354878Y1287588D02*
Y1289557D01*
G01X2354858Y1360128D02*
Y1356978D01*
G01X2354491Y1355856D02*
Y1356644D01*
G01Y1352707D02*
Y1353494D01*
G01Y1346407D02*
Y1347195D01*
G01Y1349557D02*
Y1350344D01*
G01Y1343258D02*
Y1344045D01*
G01Y1336959D02*
Y1337746D01*
G01Y1340108D02*
Y1340896D01*
G01Y1333809D02*
Y1334596D01*
G01Y1327510D02*
Y1328297D01*
G01Y1330659D02*
Y1331447D01*
G01Y1324360D02*
Y1325148D01*
G01Y1321211D02*
Y1321998D01*
G01Y1314911D02*
Y1315699D01*
G01Y1318061D02*
Y1318848D01*
G01Y1311762D02*
Y1312549D01*
G01Y1305463D02*
Y1306250D01*
G01Y1308612D02*
Y1309400D01*
G01Y1302313D02*
Y1303100D01*
G01Y1296014D02*
Y1296801D01*
G01Y1299163D02*
Y1299951D01*
G01Y1292864D02*
Y1293651D01*
G01Y1289714D02*
Y1290502D01*
G01X2354464Y1355856D02*
Y1356644D01*
G01Y1352707D02*
Y1353494D01*
G01Y1346407D02*
Y1347195D01*
G01Y1349557D02*
Y1350344D01*
G01Y1343258D02*
Y1344045D01*
G01Y1336959D02*
Y1337746D01*
G01Y1340108D02*
Y1340896D01*
G01Y1333809D02*
Y1334596D01*
G01Y1327510D02*
Y1328297D01*
G01Y1330659D02*
Y1331447D01*
G01Y1324360D02*
Y1325148D01*
G01Y1321211D02*
Y1321998D01*
G01Y1314911D02*
Y1315699D01*
G01Y1318061D02*
Y1318848D01*
G01Y1311762D02*
Y1312549D01*
G01Y1305463D02*
Y1306250D01*
G01Y1308612D02*
Y1309400D01*
G01Y1302313D02*
Y1303100D01*
G01Y1296014D02*
Y1296801D01*
G01Y1299163D02*
Y1299951D01*
G01Y1292864D02*
Y1293651D01*
G01Y1289714D02*
Y1290502D01*
G01X2354424Y1324360D02*
Y1321998D01*
G01Y1327510D02*
Y1325148D01*
G01Y1330659D02*
Y1328297D01*
G01Y1333809D02*
Y1331447D01*
G01Y1336959D02*
Y1334596D01*
G01Y1340108D02*
Y1337746D01*
G01X2354149Y1340699D02*
Y1321407D01*
G01X2354088Y1355856D02*
Y1356644D01*
G01Y1352707D02*
Y1353494D01*
G01Y1346407D02*
Y1347195D01*
G01Y1349557D02*
Y1350344D01*
G01Y1343258D02*
Y1344045D01*
G01Y1336959D02*
Y1337746D01*
G01Y1340108D02*
Y1340896D01*
G01Y1333809D02*
Y1334596D01*
G01Y1327510D02*
Y1328297D01*
G01Y1330659D02*
Y1331447D01*
G01Y1324360D02*
Y1325148D01*
G01Y1321211D02*
Y1321998D01*
G01Y1314911D02*
Y1315699D01*
G01Y1318061D02*
Y1318848D01*
G01Y1311762D02*
Y1312549D01*
G01Y1305463D02*
Y1306250D01*
G01Y1308612D02*
Y1309400D01*
G01Y1302313D02*
Y1303100D01*
G01Y1296014D02*
Y1296801D01*
G01Y1299163D02*
Y1299951D01*
G01Y1292864D02*
Y1293651D01*
G01Y1289714D02*
Y1290502D01*
G01X2353874Y1289340D02*
Y1287766D01*
G01Y1294340D02*
Y1292766D01*
G01Y1299340D02*
Y1297766D01*
G01Y1304340D02*
Y1302766D01*
G01Y1309340D02*
Y1307766D01*
G01Y1314340D02*
Y1312766D01*
G01Y1319340D02*
Y1317766D01*
G01Y1344340D02*
Y1342766D01*
G01Y1349340D02*
Y1347766D01*
G01Y1354340D02*
Y1352766D01*
G01Y1360128D02*
Y1356978D01*
G01X2353649Y1340699D02*
Y1321407D01*
G01X2353439Y1321900D02*
Y1340207D01*
G01X2352890Y1290128D02*
Y1286978D01*
G01Y1295128D02*
Y1291978D01*
G01Y1300128D02*
Y1296978D01*
G01Y1305128D02*
Y1301978D01*
G01Y1310128D02*
Y1306978D01*
G01Y1315128D02*
Y1311978D01*
G01Y1320128D02*
Y1316978D01*
G01Y1345128D02*
Y1341978D01*
G01Y1350128D02*
Y1346978D01*
G01Y1355128D02*
Y1351978D01*
G01X2352732Y1321407D02*
Y1340699D01*
G01X2352455Y1323770D02*
Y1322588D01*
G01Y1326919D02*
Y1325738D01*
G01Y1330069D02*
Y1328888D01*
G01Y1333218D02*
Y1332037D01*
G01Y1336368D02*
Y1335187D01*
G01Y1339518D02*
Y1338337D01*
G01X2351905Y1290128D02*
Y1286978D01*
G01Y1295128D02*
Y1291978D01*
G01Y1300128D02*
Y1296978D01*
G01Y1305128D02*
Y1301978D01*
G01Y1310128D02*
Y1306978D01*
G01Y1315128D02*
Y1311978D01*
G01Y1320128D02*
Y1316978D01*
G01Y1345128D02*
Y1341978D01*
G01Y1350128D02*
Y1346978D01*
G01Y1355128D02*
Y1351978D01*
G01X2350921Y1289340D02*
Y1287766D01*
G01Y1294340D02*
Y1292766D01*
G01Y1299340D02*
Y1297766D01*
G01Y1304340D02*
Y1302766D01*
G01Y1309340D02*
Y1307766D01*
G01Y1314340D02*
Y1312766D01*
G01Y1319340D02*
Y1317766D01*
G01Y1344340D02*
Y1342766D01*
G01Y1349340D02*
Y1347766D01*
G01Y1354340D02*
Y1352766D01*
G01X2350726Y1290502D02*
Y1289714D01*
G01Y1293651D02*
Y1292864D01*
G01Y1296801D02*
Y1296014D01*
G01Y1299951D02*
Y1299163D01*
G01Y1303100D02*
Y1302313D01*
G01Y1306250D02*
Y1305463D01*
G01Y1309400D02*
Y1308612D01*
G01Y1312549D02*
Y1311762D01*
G01Y1315699D02*
Y1314911D01*
G01Y1318848D02*
Y1318061D01*
G01Y1321998D02*
Y1321211D01*
G01Y1325148D02*
Y1324360D01*
G01Y1328297D02*
Y1327510D01*
G01Y1331447D02*
Y1330659D01*
G01Y1334596D02*
Y1333809D01*
G01Y1337746D02*
Y1336959D01*
G01Y1340896D02*
Y1340108D01*
G01Y1344045D02*
Y1343258D01*
G01Y1347195D02*
Y1346407D01*
G01Y1350344D02*
Y1349557D01*
G01Y1353494D02*
Y1352707D01*
G01Y1356644D02*
Y1355856D01*
G01X2349376Y1321407D02*
Y1340699D01*
G01X2349324Y1327431D02*
Y1325226D01*
G01Y1336880D02*
Y1334675D01*
G01X2349305Y1323770D02*
Y1322588D01*
G01Y1326919D02*
Y1325738D01*
G01Y1330069D02*
Y1328888D01*
G01Y1333218D02*
Y1332037D01*
G01Y1336368D02*
Y1335187D01*
G01Y1339518D02*
Y1338337D01*
G01X2348898Y1336880D02*
Y1340699D01*
G01Y1327431D02*
Y1334675D01*
G01Y1321407D02*
Y1325226D01*
G01X2348743Y1290502D02*
Y1289714D01*
G01Y1293651D02*
Y1292864D01*
G01Y1296801D02*
Y1296014D01*
G01Y1299951D02*
Y1299163D01*
G01Y1303100D02*
Y1302313D01*
G01Y1306250D02*
Y1305463D01*
G01Y1309400D02*
Y1308612D01*
G01Y1312549D02*
Y1311762D01*
G01Y1315699D02*
Y1314911D01*
G01Y1318848D02*
Y1318061D01*
G01Y1321998D02*
Y1321211D01*
G01Y1325148D02*
Y1324360D01*
G01Y1328297D02*
Y1327510D01*
G01Y1331447D02*
Y1330659D01*
G01Y1334596D02*
Y1333809D01*
G01Y1337746D02*
Y1336959D01*
G01Y1340896D02*
Y1340108D01*
G01Y1344045D02*
Y1343258D01*
G01Y1347195D02*
Y1346407D01*
G01Y1350344D02*
Y1349557D01*
G01Y1353494D02*
Y1352707D01*
G01Y1356644D02*
Y1355856D01*
G01X2347772Y1289340D02*
Y1287766D01*
G01Y1294340D02*
Y1292766D01*
G01Y1299340D02*
Y1297766D01*
G01Y1304340D02*
Y1302766D01*
G01Y1309340D02*
Y1307766D01*
G01Y1314340D02*
Y1312766D01*
G01Y1319340D02*
Y1317766D01*
G01Y1344340D02*
Y1342766D01*
G01Y1349340D02*
Y1347766D01*
G01Y1354340D02*
Y1352766D01*
G01X2347441Y1334675D02*
Y1336880D01*
G01Y1325226D02*
Y1327431D01*
G01X2347091Y1355856D02*
Y1356644D01*
G01Y1352707D02*
Y1353494D01*
G01Y1346407D02*
Y1347195D01*
G01Y1349557D02*
Y1350344D01*
G01Y1343258D02*
Y1344045D01*
G01Y1336959D02*
Y1337746D01*
G01Y1340108D02*
Y1340896D01*
G01Y1333809D02*
Y1334596D01*
G01Y1327510D02*
Y1328297D01*
G01Y1330659D02*
Y1331447D01*
G01Y1324360D02*
Y1325148D01*
G01Y1321211D02*
Y1321998D01*
G01Y1314911D02*
Y1315699D01*
G01Y1318061D02*
Y1318848D01*
G01Y1311762D02*
Y1312549D01*
G01Y1305463D02*
Y1306250D01*
G01Y1308612D02*
Y1309400D01*
G01Y1302313D02*
Y1303100D01*
G01Y1296014D02*
Y1296801D01*
G01Y1299163D02*
Y1299951D01*
G01Y1292864D02*
Y1293651D01*
G01Y1289714D02*
Y1290502D01*
G01X2346807Y1289557D02*
Y1287588D01*
G01X2345363Y1289714D02*
Y1287136D01*
G01Y1292864D02*
Y1290502D01*
G01Y1296014D02*
Y1293651D01*
G01Y1299163D02*
Y1296801D01*
G01Y1302313D02*
Y1299951D01*
G01Y1305463D02*
Y1303100D01*
G01Y1308612D02*
Y1306250D01*
G01Y1311762D02*
Y1309400D01*
G01Y1314911D02*
Y1312549D01*
G01Y1318061D02*
Y1315699D01*
G01Y1321211D02*
Y1318848D01*
G01Y1324360D02*
Y1321998D01*
G01Y1327510D02*
Y1325148D01*
G01Y1330659D02*
Y1328297D01*
G01Y1333809D02*
Y1331447D01*
G01Y1336959D02*
Y1334596D01*
G01Y1340108D02*
Y1337746D01*
G01Y1343258D02*
Y1340896D01*
G01Y1346407D02*
Y1344045D01*
G01Y1349557D02*
Y1347195D01*
G01Y1352707D02*
Y1350344D01*
G01Y1355856D02*
Y1353494D01*
G01Y1359006D02*
Y1356644D01*
G01X2344424Y1355856D02*
Y1356644D01*
G01Y1352707D02*
Y1353494D01*
G01Y1346407D02*
Y1347195D01*
G01Y1349557D02*
Y1350344D01*
G01Y1343258D02*
Y1344045D01*
G01Y1336959D02*
Y1337746D01*
G01Y1340108D02*
Y1340896D01*
G01Y1333809D02*
Y1334596D01*
G01Y1327510D02*
Y1328297D01*
G01Y1330659D02*
Y1331447D01*
G01Y1324360D02*
Y1325148D01*
G01Y1321211D02*
Y1321998D01*
G01Y1314911D02*
Y1315699D01*
G01Y1318061D02*
Y1318848D01*
G01Y1311762D02*
Y1312549D01*
G01Y1305463D02*
Y1306250D01*
G01Y1308612D02*
Y1309400D01*
G01Y1302313D02*
Y1303100D01*
G01Y1296014D02*
Y1296801D01*
G01Y1299163D02*
Y1299951D01*
G01Y1292864D02*
Y1293651D01*
G01Y1289714D02*
Y1290502D01*
G01X2344277Y1355856D02*
Y1356644D01*
G01Y1352707D02*
Y1353494D01*
G01Y1346407D02*
Y1347195D01*
G01Y1349557D02*
Y1350344D01*
G01Y1343258D02*
Y1344045D01*
G01Y1336959D02*
Y1337746D01*
G01Y1340108D02*
Y1340896D01*
G01Y1333809D02*
Y1334596D01*
G01Y1327510D02*
Y1328297D01*
G01Y1330659D02*
Y1331447D01*
G01Y1324360D02*
Y1325148D01*
G01Y1321211D02*
Y1321998D01*
G01Y1314911D02*
Y1315699D01*
G01Y1318061D02*
Y1318848D01*
G01Y1311762D02*
Y1312549D01*
G01Y1305463D02*
Y1306250D01*
G01Y1308612D02*
Y1309400D01*
G01Y1302313D02*
Y1303100D01*
G01Y1296014D02*
Y1296801D01*
G01Y1299163D02*
Y1299951D01*
G01Y1292864D02*
Y1293651D01*
G01Y1289714D02*
Y1290502D01*
G01X2342685Y1355856D02*
Y1356644D01*
G01Y1352707D02*
Y1353494D01*
G01Y1346407D02*
Y1347195D01*
G01Y1349557D02*
Y1350344D01*
G01Y1343258D02*
Y1344045D01*
G01Y1336959D02*
Y1337746D01*
G01Y1340108D02*
Y1340896D01*
G01Y1333809D02*
Y1334596D01*
G01Y1327510D02*
Y1328297D01*
G01Y1330659D02*
Y1331447D01*
G01Y1324360D02*
Y1325148D01*
G01Y1321211D02*
Y1321998D01*
G01Y1314911D02*
Y1315699D01*
G01Y1318061D02*
Y1318848D01*
G01Y1311762D02*
Y1312549D01*
G01Y1305463D02*
Y1306250D01*
G01Y1308612D02*
Y1309400D01*
G01Y1302313D02*
Y1303100D01*
G01Y1296014D02*
Y1296801D01*
G01Y1299163D02*
Y1299951D01*
G01Y1292864D02*
Y1293651D01*
G01Y1289714D02*
Y1290502D01*
G01X2341743D02*
Y1289714D01*
G01Y1293651D02*
Y1292864D01*
G01Y1296801D02*
Y1296014D01*
G01Y1299951D02*
Y1299163D01*
G01Y1303100D02*
Y1302313D01*
G01Y1306250D02*
Y1305463D01*
G01Y1309400D02*
Y1308612D01*
G01Y1312549D02*
Y1311762D01*
G01Y1315699D02*
Y1314911D01*
G01Y1318848D02*
Y1318061D01*
G01Y1321998D02*
Y1321211D01*
G01Y1325148D02*
Y1324360D01*
G01Y1328297D02*
Y1327510D01*
G01Y1331447D02*
Y1330659D01*
G01Y1334596D02*
Y1333809D01*
G01Y1337746D02*
Y1336959D01*
G01Y1340896D02*
Y1340108D01*
G01Y1344045D02*
Y1343258D01*
G01Y1347195D02*
Y1346407D01*
G01Y1350344D02*
Y1349557D01*
G01Y1353494D02*
Y1352707D01*
G01Y1356644D02*
Y1355856D01*
G01X2338907Y1290502D02*
Y1289714D01*
G01Y1293651D02*
Y1292864D01*
G01Y1296801D02*
Y1296014D01*
G01Y1299951D02*
Y1299163D01*
G01Y1303100D02*
Y1302313D01*
G01Y1306250D02*
Y1305463D01*
G01Y1309400D02*
Y1308612D01*
G01Y1312549D02*
Y1311762D01*
G01Y1315699D02*
Y1314911D01*
G01Y1318848D02*
Y1318061D01*
G01Y1321998D02*
Y1321211D01*
G01Y1325148D02*
Y1324360D01*
G01Y1328297D02*
Y1327510D01*
G01Y1331447D02*
Y1330659D01*
G01Y1334596D02*
Y1333809D01*
G01Y1337746D02*
Y1336959D01*
G01Y1340896D02*
Y1340108D01*
G01Y1344045D02*
Y1343258D01*
G01Y1347195D02*
Y1346407D01*
G01Y1350344D02*
Y1349557D01*
G01Y1353494D02*
Y1352707D01*
G01Y1356644D02*
Y1355856D01*
G01X2338718D02*
Y1356644D01*
G01Y1352707D02*
Y1353494D01*
G01Y1346407D02*
Y1347195D01*
G01Y1349557D02*
Y1350344D01*
G01Y1343258D02*
Y1344045D01*
G01Y1336959D02*
Y1337746D01*
G01Y1340108D02*
Y1340896D01*
G01Y1333809D02*
Y1334596D01*
G01Y1327510D02*
Y1328297D01*
G01Y1330659D02*
Y1331447D01*
G01Y1324360D02*
Y1325148D01*
G01Y1321211D02*
Y1321998D01*
G01Y1314911D02*
Y1315699D01*
G01Y1318061D02*
Y1318848D01*
G01Y1311762D02*
Y1312549D01*
G01Y1305463D02*
Y1306250D01*
G01Y1308612D02*
Y1309400D01*
G01Y1302313D02*
Y1303100D01*
G01Y1296014D02*
Y1296801D01*
G01Y1299163D02*
Y1299951D01*
G01Y1292864D02*
Y1293651D01*
G01Y1289714D02*
Y1290502D01*
G01X2336945Y1355856D02*
Y1356644D01*
G01Y1352707D02*
Y1353494D01*
G01Y1346407D02*
Y1347195D01*
G01Y1349557D02*
Y1350344D01*
G01Y1343258D02*
Y1344045D01*
G01Y1336959D02*
Y1337746D01*
G01Y1340108D02*
Y1340896D01*
G01Y1333809D02*
Y1334596D01*
G01Y1327510D02*
Y1328297D01*
G01Y1330659D02*
Y1331447D01*
G01Y1324360D02*
Y1325148D01*
G01Y1321211D02*
Y1321998D01*
G01Y1314911D02*
Y1315699D01*
G01Y1318061D02*
Y1318848D01*
G01Y1311762D02*
Y1312549D01*
G01Y1305463D02*
Y1306250D01*
G01Y1308612D02*
Y1309400D01*
G01Y1302313D02*
Y1303100D01*
G01Y1296014D02*
Y1296801D01*
G01Y1299163D02*
Y1299951D01*
G01Y1292864D02*
Y1293651D01*
G01Y1289714D02*
Y1290502D01*
G01X2361231Y1288697D02*
X2360882Y1289039D01*
G01X2358094Y1290403D02*
X2358704Y1289892D01*
G01X2358007D02*
X2357398Y1290403D01*
G01X2359750Y1289039D02*
X2359401Y1288697D01*
G01X2358007Y1288186D02*
X2358182Y1288356D01*
G01X2357746Y1288612D02*
X2357485Y1288271D01*
G01X2359750D02*
X2359924Y1288527D01*
G01X2360447Y1288697D02*
X2360708Y1288527D01*
G01X2360882Y1289039D02*
X2360534Y1289209D01*
G01X2359924Y1288527D02*
X2360185Y1288697D01*
G01X2358094Y1288868D02*
X2357746Y1288612D01*
G01X2354858Y1357175D02*
X2353874D01*
G01X2354858Y1356978D02*
X2353874D01*
G01X2344277Y1356644D02*
X2336945D01*
G01X2356433D02*
X2344424D01*
G01X2356433Y1356348D02*
X2355331D01*
G01X2344424Y1355856D02*
X2356433D01*
G01X2336945D02*
X2344277D01*
G01X2352890Y1355128D02*
X2351905D01*
G01X2352890Y1354931D02*
X2351905D01*
G01X2352890Y1354537D02*
X2351905D01*
G01X2347772Y1354340D02*
X2354937D01*
G01X2344277Y1353494D02*
X2336945D01*
G01X2356433D02*
X2344424D01*
G01X2347772Y1352766D02*
X2354937D01*
G01X2344424Y1352707D02*
X2356433D01*
G01X2336945D02*
X2344277D01*
G01X2352890Y1352569D02*
X2351905D01*
G01X2352890Y1352175D02*
X2351905D01*
G01X2352890Y1351978D02*
X2351905D01*
G01X2358356Y1288953D02*
X2358094Y1288868D01*
G01X2360098Y1289209D02*
X2359750Y1289039D01*
G01X2358182Y1288356D02*
X2358356Y1288442D01*
G01X2344277Y1350344D02*
X2336945D01*
G01X2356433D02*
X2344424D01*
G01X2352890Y1350128D02*
X2351905D01*
G01X2352890Y1349931D02*
X2351905D01*
G01X2344424Y1349557D02*
X2356433D01*
G01X2336945D02*
X2344277D01*
G01X2352890Y1349537D02*
X2351905D01*
G01X2347772Y1349340D02*
X2354937D01*
G01X2347772Y1347766D02*
X2354937D01*
G01X2352890Y1347569D02*
X2351905D01*
G01X2386130Y1347254D02*
X2366669D01*
G01X2344277Y1347195D02*
X2336945D01*
G01X2356433D02*
X2344424D01*
G01X2352890Y1347175D02*
X2351905D01*
G01X2352890Y1346978D02*
X2351905D01*
G01X2344424Y1346407D02*
X2356433D01*
G01X2336945D02*
X2344277D01*
G01X2352890Y1345128D02*
X2351905D01*
G01X2352890Y1344931D02*
X2351905D01*
G01X2352890Y1344537D02*
X2351905D01*
G01X2347772Y1344340D02*
X2354937D01*
G01X2344277Y1344045D02*
X2336945D01*
G01X2356433D02*
X2344424D01*
G01Y1343258D02*
X2356433D01*
G01X2336945D02*
X2344277D01*
G01X2385173Y1343159D02*
X2358480D01*
G01X2347772Y1342766D02*
X2354937D01*
G01X2352890Y1342569D02*
X2351905D01*
G01X2352890Y1342175D02*
X2351905D01*
G01X2352890Y1341978D02*
X2351905D01*
G01X2344277Y1340896D02*
X2336945D01*
G01X2356433D02*
X2344424D01*
G01X2366669Y1340817D02*
X2385173D01*
G01X2356433D02*
X2355331D01*
G01X2380673Y1340797D02*
X2358480D01*
G01X2356433Y1340699D02*
X2348898D01*
G01X2353439Y1340207D02*
X2351315D01*
G01X2344424Y1340108D02*
X2356433D01*
G01X2336945D02*
X2344277D01*
G01X2354424Y1339911D02*
X2353439D01*
G01X2354424Y1339714D02*
X2353439D01*
G01X2355331Y1339518D02*
X2349305D01*
G01X2355331Y1338337D02*
X2349305D01*
G01X2354424Y1338140D02*
X2353439D01*
G01X2354424Y1337943D02*
X2353439D01*
G01X2344277Y1337746D02*
X2336945D01*
G01X2356433D02*
X2344424D01*
G01Y1336959D02*
X2356433D01*
G01X2336945D02*
X2344277D01*
G01X2349324Y1336880D02*
X2347441D01*
G01X2354424Y1336762D02*
X2353439D01*
G01X2354424Y1336565D02*
X2353439D01*
G01X2355331Y1336368D02*
X2349305D01*
G01X2355331Y1335187D02*
X2349305D01*
G01X2354424Y1334990D02*
X2353439D01*
G01X2354424Y1334793D02*
X2353439D01*
G01X2347441Y1334675D02*
X2349324D01*
G01X2344277Y1334596D02*
X2336945D01*
G01X2356433D02*
X2344424D01*
G01Y1333809D02*
X2356433D01*
G01X2336945D02*
X2344277D01*
G01X2354424Y1333612D02*
X2353439D01*
G01X2354424Y1333415D02*
X2353439D01*
G01X2355331Y1333218D02*
X2349305D01*
G01X2355331Y1332037D02*
X2349305D01*
G01X2354424Y1331840D02*
X2353439D01*
G01X2354424Y1331644D02*
X2353439D01*
G01X2344277Y1331447D02*
X2336945D01*
G01X2356433D02*
X2344424D01*
G01Y1330659D02*
X2356433D01*
G01X2336945D02*
X2344277D01*
G01X2354424Y1330463D02*
X2353439D01*
G01X2354424Y1330266D02*
X2353439D01*
G01X2355331Y1330069D02*
X2349305D01*
G01X2355331Y1328888D02*
X2349305D01*
G01X2354424Y1328691D02*
X2353439D01*
G01X2354424Y1328494D02*
X2353439D01*
G01X2344277Y1328297D02*
X2336945D01*
G01X2356433D02*
X2344424D01*
G01Y1327510D02*
X2356433D01*
G01X2336945D02*
X2344277D01*
G01X2349324Y1327431D02*
X2347441D01*
G01X2354424Y1327313D02*
X2353439D01*
G01X2354424Y1327116D02*
X2353439D01*
G01X2355331Y1326919D02*
X2349305D01*
G01X2355331Y1325738D02*
X2349305D01*
G01X2354424Y1325541D02*
X2353439D01*
G01X2354424Y1325344D02*
X2353439D01*
G01X2347441Y1325226D02*
X2349324D01*
G01X2344277Y1325148D02*
X2336945D01*
G01X2356433D02*
X2344424D01*
G01Y1324360D02*
X2356433D01*
G01X2336945D02*
X2344277D01*
G01X2354424Y1324163D02*
X2353439D01*
G01X2354424Y1323966D02*
X2353439D01*
G01X2355331Y1323770D02*
X2349305D01*
G01X2355331Y1322588D02*
X2349305D01*
G01X2354424Y1322392D02*
X2353439D01*
G01X2354424Y1322195D02*
X2353439D01*
G01X2344277Y1321998D02*
X2336945D01*
G01X2356433D02*
X2344424D01*
G01X2353439Y1321900D02*
X2351315D01*
G01X2348898Y1321407D02*
X2356433D01*
G01X2380673Y1321309D02*
X2358480D01*
G01X2356433Y1321289D02*
X2355331D01*
G01X2385173D02*
X2366669D01*
G01X2344424Y1321211D02*
X2356433D01*
G01X2336945D02*
X2344277D01*
G01X2352890Y1320128D02*
X2351905D01*
G01X2352890Y1319931D02*
X2351905D01*
G01X2352890Y1319537D02*
X2351905D01*
G01X2347772Y1319340D02*
X2354937D01*
G01X2385173Y1318947D02*
X2358480D01*
G01X2344277Y1318848D02*
X2336945D01*
G01X2356433D02*
X2344424D01*
G01Y1318061D02*
X2356433D01*
G01X2336945D02*
X2344277D01*
G01X2347772Y1317766D02*
X2354937D01*
G01X2352890Y1317569D02*
X2351905D01*
G01X2352890Y1317175D02*
X2351905D01*
G01X2352890Y1316978D02*
X2351905D01*
G01X2344277Y1315699D02*
X2336945D01*
G01X2356433D02*
X2344424D01*
G01X2352890Y1315128D02*
X2351905D01*
G01X2386130Y1314951D02*
X2366669D01*
G01X2352890Y1314931D02*
X2351905D01*
G01X2344424Y1314911D02*
X2356433D01*
G01X2336945D02*
X2344277D01*
G01X2352890Y1314537D02*
X2351905D01*
G01X2347772Y1314340D02*
X2354937D01*
G01X2347772Y1312766D02*
X2354937D01*
G01X2352890Y1312569D02*
X2351905D01*
G01X2344277Y1312549D02*
X2336945D01*
G01X2356433D02*
X2344424D01*
G01X2352890Y1312175D02*
X2351905D01*
G01X2352890Y1311978D02*
X2351905D01*
G01X2344424Y1311762D02*
X2356433D01*
G01X2336945D02*
X2344277D01*
G01X2352890Y1310128D02*
X2351905D01*
G01X2352890Y1309931D02*
X2351905D01*
G01X2352890Y1309537D02*
X2351905D01*
G01X2344277Y1309400D02*
X2336945D01*
G01X2356433D02*
X2344424D01*
G01X2347772Y1309340D02*
X2354937D01*
G01X2344424Y1308612D02*
X2356433D01*
G01X2336945D02*
X2344277D01*
G01X2347772Y1307766D02*
X2354937D01*
G01X2352890Y1307569D02*
X2351905D01*
G01X2352890Y1307175D02*
X2351905D01*
G01X2352890Y1306978D02*
X2351905D01*
G01X2344277Y1306250D02*
X2336945D01*
G01X2356433D02*
X2344424D01*
G01Y1305463D02*
X2356433D01*
G01X2336945D02*
X2344277D01*
G01X2352890Y1305128D02*
X2351905D01*
G01X2352890Y1304931D02*
X2351905D01*
G01X2352890Y1304537D02*
X2351905D01*
G01X2347772Y1304340D02*
X2354937D01*
G01X2385173Y1303711D02*
X2358480D01*
G01X2344277Y1303100D02*
X2336945D01*
G01X2356433D02*
X2344424D01*
G01X2347772Y1302766D02*
X2354937D01*
G01X2352890Y1302569D02*
X2351905D01*
G01X2344424Y1302313D02*
X2356433D01*
G01X2336945D02*
X2344277D01*
G01X2352890Y1302175D02*
X2351905D01*
G01X2352890Y1301978D02*
X2351905D01*
G01X2385173Y1301348D02*
X2358480D01*
G01X2352890Y1300128D02*
X2351905D01*
G01X2344277Y1299951D02*
X2336945D01*
G01X2356433D02*
X2344424D01*
G01X2352890Y1299931D02*
X2351905D01*
G01X2352890Y1299537D02*
X2351905D01*
G01X2347772Y1299340D02*
X2354937D01*
G01X2344424Y1299163D02*
X2356433D01*
G01X2336945D02*
X2344277D01*
G01X2347772Y1297766D02*
X2354937D01*
G01X2352890Y1297569D02*
X2351905D01*
G01X2352890Y1297175D02*
X2351905D01*
G01X2352890Y1296978D02*
X2351905D01*
G01X2344277Y1296801D02*
X2336945D01*
G01X2356433D02*
X2344424D01*
G01Y1296014D02*
X2356433D01*
G01X2336945D02*
X2344277D01*
G01X2352890Y1295128D02*
X2351905D01*
G01X2352890Y1294931D02*
X2351905D01*
G01X2352890Y1294537D02*
X2351905D01*
G01X2347772Y1294340D02*
X2354937D01*
G01X2344277Y1293651D02*
X2336945D01*
G01X2356433D02*
X2344424D01*
G01Y1292864D02*
X2356433D01*
G01X2336945D02*
X2344277D01*
G01X2347772Y1292766D02*
X2354937D01*
G01X2352890Y1292569D02*
X2351905D01*
G01X2352890Y1292175D02*
X2351905D01*
G01X2352890Y1291978D02*
X2351905D01*
G01X2357398Y1290915D02*
X2361492D01*
G01X2344277Y1290502D02*
X2336945D01*
G01X2356433D02*
X2344424D01*
G01X2361492Y1290403D02*
X2358094D01*
G01X2352890Y1290128D02*
X2351905D01*
G01X2352890Y1289931D02*
X2351905D01*
G01X2358704Y1289892D02*
X2358007D01*
G01X2344424Y1289714D02*
X2356433D01*
G01X2336945D02*
X2344277D01*
G01X2354878Y1289557D02*
X2346807D01*
G01X2352890Y1289537D02*
X2351905D01*
G01X2347772Y1289340D02*
X2354937D01*
G01X2360534Y1289209D02*
X2360098D01*
G01X2360185Y1288697D02*
X2360447D01*
G01X2347772Y1287766D02*
X2354937D01*
G01X2346807Y1287588D02*
X2354878D01*
G01X2352890Y1287569D02*
X2351905D01*
G01X2352890Y1287175D02*
X2351905D01*
G01X2351315Y1287136D02*
X2342330D01*
G01X2352890Y1286978D02*
X2351905D01*
G01X2354491Y1359006D02*
Y1359793D01*
G01X2354464Y1359006D02*
Y1359793D01*
G01X2354088Y1359006D02*
Y1359793D01*
G01X2352890Y1359340D02*
Y1357766D01*
G01X2350726Y1359793D02*
Y1359006D01*
G01X2349740Y1359340D02*
Y1357766D01*
G01X2348743Y1359793D02*
Y1359006D01*
G01X2347091D02*
Y1359793D01*
G01X2345363Y1362155D02*
Y1359793D01*
G01X2344424Y1359006D02*
Y1359793D01*
G01X2344277Y1359006D02*
Y1359793D01*
G01X2342685Y1359006D02*
Y1359793D01*
G01X2341743D02*
Y1359006D01*
G01X2338907Y1359793D02*
Y1359006D01*
G01X2338718D02*
Y1359793D01*
G01X2336945Y1359006D02*
Y1359793D01*
G01X2344277D02*
X2336945D01*
G01X2356433D02*
X2344424D01*
G01X2354858Y1359537D02*
X2353874D01*
G01X2385173Y1359498D02*
X2358480D01*
G01X2355331Y1359340D02*
X2349740D01*
G01X2344424Y1359006D02*
X2356433D01*
G01X2336945D02*
X2344277D01*
G01X2355331Y1357766D02*
X2349740D01*
G01X2354858Y1357569D02*
X2353874D01*
G01X2358121Y1426713D02*
G03X2359551I715J0D01*
G01X2355231D02*
G03X2356661I715J0D01*
G01X2354132Y1425638D02*
G03X2356768Y1425782I1248J1351D01*
G01D02*
G03X2359549Y1425788I1388J1207D01*
G01X2354937Y1414340D02*
G03X2355331Y1414734I0J394D01*
G01Y1412372D02*
G03X2354937Y1412766I-394J0D01*
G01Y1404340D02*
G03X2355331Y1404734I0J394D01*
G01Y1402372D02*
G03X2354937Y1402766I-394J0D01*
G01Y1409340D02*
G03X2355331Y1409734I0J394D01*
G01Y1407372D02*
G03X2354937Y1407766I-394J0D01*
G01X2353838Y1426309D02*
G03X2354132Y1425638I913J0D01*
G01X2350159Y1428129D02*
G03Y1426444I2236J-843D01*
G01X2354937Y1364340D02*
G03X2355331Y1364734I0J394D01*
G01Y1362372D02*
G03X2354937Y1362766I-394J0D01*
G01Y1374340D02*
G03X2355331Y1374734I0J394D01*
G01Y1372372D02*
G03X2354937Y1372766I-394J0D01*
G01Y1379340D02*
G03X2355331Y1379734I0J394D01*
G01Y1377372D02*
G03X2354937Y1377766I-394J0D01*
G01Y1394340D02*
G03X2355331Y1394734I0J394D01*
G01Y1392372D02*
G03X2354937Y1392766I-394J0D01*
G01Y1389340D02*
G03X2355331Y1389734I0J394D01*
G01Y1387372D02*
G03X2354937Y1387766I-394J0D01*
G01Y1384340D02*
G03X2355331Y1384734I0J394D01*
G01Y1382372D02*
G03X2354937Y1382766I-394J0D01*
G01Y1369340D02*
G03X2355331Y1369734I0J394D01*
G01Y1367372D02*
G03X2354937Y1367766I-394J0D01*
G01X2351632Y1428129D02*
G03X2350159I-736J-277D01*
G01Y1426444D02*
G03X2351632I737J278D01*
G01X2352904Y1428464D02*
G03X2352383Y1429029I-1351J-723D01*
G01X2349337Y1429027D02*
G03X2348816Y1428462I830J-1288D01*
G01X2348817Y1426150D02*
G03X2349338Y1425585I1351J723D01*
G01X2352384D02*
G03X2352905Y1426150I-830J1288D01*
G01X2351632Y1426444D02*
G03Y1428129I-2237J842D01*
G01X2352905Y1426150D02*
G03X2352904Y1428464I-2163J1156D01*
G01X2348816Y1428462D02*
G03X2348817Y1426150I2163J-1155D01*
G01X2352383Y1429029D02*
G03X2349337Y1429028I-1522J-2362D01*
G01X2349338Y1425584D02*
G03X2352384Y1425585I1522J2362D01*
G01X2349740Y1425856D02*
G03I-2165J0D01*
G01X2345620Y1428573D02*
G03Y1423140I1955J-2716D01*
G01X2349529D02*
G03Y1428573I-1954J2717D01*
G01X2351079Y1425856D02*
G03I-3504J0D01*
G01X2349878Y1421959D02*
G03Y1429754I-2304J3898D01*
G01X2345271D02*
G03Y1421959I2304J-3898D01*
G01X2343658Y1428447D02*
G03X2343068Y1428082I-9J-646D01*
G01X2344432Y1427639D02*
G03X2343658Y1428447I-792J16D01*
G01X2342407Y1429151D02*
G03X2341564Y1428082I704J-1422D01*
G01X2341772Y1426196D02*
G03X2343007Y1425222I1735J930D01*
G01X2344649Y1425266D02*
G03X2345814Y1426404I-729J1911D01*
G01X2345727Y1428420D02*
G03X2343989Y1429438I-1807J-1093D01*
G01X2343007Y1425223D02*
G03X2344649Y1425266I757J2475D01*
G01X2345988Y1427560D02*
G03X2345726Y1428423I-2971J-431D01*
G01X2341433Y1427639D02*
G03X2341772Y1426196I3015J-53D01*
G01X2345988Y1427065D02*
G03Y1427562I-3524J249D01*
G01X2345814Y1426404D02*
G03X2345988Y1427065I-4018J1411D01*
G01X2343007Y1426813D02*
G03X2344432I712J-83D01*
G01X2343992Y1429438D02*
G03X2342407Y1429151I-262J-3073D01*
G01X2349529Y1423140D02*
X2349547Y1423084D01*
X2349599Y1422918D01*
X2349678Y1422660D01*
X2349774Y1422332D01*
X2349878Y1421959D01*
G01X2345620Y1428573D02*
X2345602Y1428629D01*
X2345550Y1428794D01*
X2345471Y1429053D01*
X2345376Y1429380D01*
X2345271Y1429754D01*
G01X2338463Y1429238D02*
X2339208Y1427960D01*
G01X2336914Y1429238D02*
X2338235Y1427082D01*
G01X2339011Y1426217D02*
X2339617Y1425231D01*
G01X2339965Y1427091D02*
X2341233Y1425231D01*
G01X2365016Y1417175D02*
Y1443573D01*
G01X2364701Y1418356D02*
Y1416585D01*
G01X2349878Y1429754D02*
X2349775Y1429385D01*
X2349679Y1429055D01*
X2349599Y1428793D01*
X2349546Y1428627D01*
X2349529Y1428573D01*
G01X2362732Y1430640D02*
Y1422293D01*
G01X2360992Y1429238D02*
Y1425231D01*
G01X2360449Y1399655D02*
Y1417175D01*
G01Y1380758D02*
Y1397293D01*
G01Y1361860D02*
Y1378396D01*
G01X2359551Y1426713D02*
Y1429238D01*
G01X2359549Y1425788D02*
Y1425231D01*
G01X2358795Y1422923D02*
Y1420522D01*
G01Y1428671D02*
Y1424892D01*
G01X2358121Y1429238D02*
Y1426713D01*
G01X2356661D02*
Y1429238D01*
G01X2355231D02*
Y1426713D01*
G01X2354858Y1400128D02*
Y1396978D01*
G01X2354491Y1412549D02*
Y1413337D01*
G01Y1409400D02*
Y1410187D01*
G01Y1403100D02*
Y1403888D01*
G01Y1406250D02*
Y1407037D01*
G01Y1399951D02*
Y1400738D01*
G01Y1393651D02*
Y1394439D01*
G01Y1396801D02*
Y1397588D01*
G01Y1390502D02*
Y1391289D01*
G01Y1384203D02*
Y1384990D01*
G01Y1387352D02*
Y1388140D01*
G01Y1381053D02*
Y1381840D01*
G01Y1374754D02*
Y1375541D01*
G01Y1377903D02*
Y1378691D01*
G01Y1371604D02*
Y1372392D01*
G01Y1365305D02*
Y1366092D01*
G01Y1368455D02*
Y1369242D01*
G01Y1362155D02*
Y1362943D01*
G01X2354464Y1412549D02*
Y1413337D01*
G01Y1409400D02*
Y1410187D01*
G01Y1403100D02*
Y1403888D01*
G01Y1406250D02*
Y1407037D01*
G01Y1399951D02*
Y1400738D01*
G01Y1393651D02*
Y1394439D01*
G01Y1396801D02*
Y1397588D01*
G01Y1390502D02*
Y1391289D01*
G01Y1384203D02*
Y1384990D01*
G01Y1387352D02*
Y1388140D01*
G01Y1381053D02*
Y1381840D01*
G01Y1374754D02*
Y1375541D01*
G01Y1377903D02*
Y1378691D01*
G01Y1371604D02*
Y1372392D01*
G01Y1365305D02*
Y1366092D01*
G01Y1368455D02*
Y1369242D01*
G01Y1362155D02*
Y1362943D01*
G01X2354088Y1412549D02*
Y1413337D01*
G01Y1409400D02*
Y1410187D01*
G01Y1403100D02*
Y1403888D01*
G01Y1406250D02*
Y1407037D01*
G01Y1399951D02*
Y1400738D01*
G01Y1393651D02*
Y1394439D01*
G01Y1396801D02*
Y1397588D01*
G01Y1390502D02*
Y1391289D01*
G01Y1384203D02*
Y1384990D01*
G01Y1387352D02*
Y1388140D01*
G01Y1381053D02*
Y1381840D01*
G01Y1374754D02*
Y1375541D01*
G01Y1377903D02*
Y1378691D01*
G01Y1371604D02*
Y1372392D01*
G01Y1365305D02*
Y1366092D01*
G01Y1368455D02*
Y1369242D01*
G01Y1362155D02*
Y1362943D01*
G01X2353874Y1364340D02*
Y1362766D01*
G01Y1369340D02*
Y1367766D01*
G01Y1374340D02*
Y1372766D01*
G01Y1379340D02*
Y1377766D01*
G01Y1384340D02*
Y1382766D01*
G01Y1389340D02*
Y1387766D01*
G01Y1394340D02*
Y1392766D01*
G01Y1400128D02*
Y1396978D01*
G01Y1404340D02*
Y1402766D01*
G01Y1409340D02*
Y1407766D01*
G01Y1414340D02*
Y1412766D01*
G01X2353838Y1429238D02*
Y1426309D01*
G01X2352890Y1365128D02*
Y1361978D01*
G01Y1370128D02*
Y1366978D01*
G01Y1375128D02*
Y1371978D01*
G01Y1380128D02*
Y1376978D01*
G01Y1385128D02*
Y1381978D01*
G01Y1390128D02*
Y1386978D01*
G01Y1395128D02*
Y1391978D01*
G01Y1399340D02*
Y1397766D01*
G01Y1405128D02*
Y1401978D01*
G01Y1410128D02*
Y1406978D01*
G01Y1415128D02*
Y1411978D01*
G01Y1422293D02*
Y1419990D01*
G01X2351905Y1365128D02*
Y1361978D01*
G01Y1370128D02*
Y1366978D01*
G01Y1375128D02*
Y1371978D01*
G01Y1380128D02*
Y1376978D01*
G01Y1385128D02*
Y1381978D01*
G01Y1390128D02*
Y1386978D01*
G01Y1395128D02*
Y1391978D01*
G01Y1405128D02*
Y1401978D01*
G01Y1410128D02*
Y1406978D01*
G01Y1415128D02*
Y1411978D01*
G01X2350921Y1364340D02*
Y1362766D01*
G01Y1369340D02*
Y1367766D01*
G01Y1374340D02*
Y1372766D01*
G01Y1379340D02*
Y1377766D01*
G01Y1384340D02*
Y1382766D01*
G01Y1389340D02*
Y1387766D01*
G01Y1394340D02*
Y1392766D01*
G01Y1404340D02*
Y1402766D01*
G01Y1409340D02*
Y1407766D01*
G01Y1414340D02*
Y1412766D01*
G01X2350726Y1362943D02*
Y1362155D01*
G01Y1366092D02*
Y1365305D01*
G01Y1369242D02*
Y1368455D01*
G01Y1372392D02*
Y1371604D01*
G01Y1375541D02*
Y1374754D01*
G01Y1378691D02*
Y1377903D01*
G01Y1381840D02*
Y1381053D01*
G01Y1384990D02*
Y1384203D01*
G01Y1388140D02*
Y1387352D01*
G01Y1391289D02*
Y1390502D01*
G01Y1394439D02*
Y1393651D01*
G01Y1397588D02*
Y1396801D01*
G01Y1400738D02*
Y1399951D01*
G01Y1403888D02*
Y1403100D01*
G01Y1407037D02*
Y1406250D01*
G01Y1410187D02*
Y1409400D01*
G01Y1413337D02*
Y1412549D01*
G01X2350333Y1419990D02*
Y1419931D01*
G01X2349740Y1399340D02*
Y1397766D01*
G01X2349694Y1419537D02*
Y1422293D01*
G01X2348743Y1362943D02*
Y1362155D01*
G01Y1366092D02*
Y1365305D01*
G01Y1369242D02*
Y1368455D01*
G01Y1372392D02*
Y1371604D01*
G01Y1375541D02*
Y1374754D01*
G01Y1378691D02*
Y1377903D01*
G01Y1381840D02*
Y1381053D01*
G01Y1384990D02*
Y1384203D01*
G01Y1388140D02*
Y1387352D01*
G01Y1391289D02*
Y1390502D01*
G01Y1394439D02*
Y1393651D01*
G01Y1397588D02*
Y1396801D01*
G01Y1400738D02*
Y1399951D01*
G01Y1403888D02*
Y1403100D01*
G01Y1407037D02*
Y1406250D01*
G01Y1410187D02*
Y1409400D01*
G01Y1413337D02*
Y1412549D01*
G01X2348039Y1429238D02*
Y1423484D01*
G01X2347772Y1364340D02*
Y1362766D01*
G01Y1369340D02*
Y1367766D01*
G01Y1374340D02*
Y1372766D01*
G01Y1379340D02*
Y1377766D01*
G01Y1384340D02*
Y1382766D01*
G01Y1389340D02*
Y1387766D01*
G01Y1394340D02*
Y1392766D01*
G01Y1404340D02*
Y1402766D01*
G01Y1409340D02*
Y1407766D01*
G01Y1414340D02*
Y1412766D01*
G01X2347091Y1412549D02*
Y1413337D01*
G01Y1409400D02*
Y1410187D01*
G01Y1403100D02*
Y1403888D01*
G01Y1406250D02*
Y1407037D01*
G01Y1399951D02*
Y1400738D01*
G01Y1393651D02*
Y1394439D01*
G01Y1396801D02*
Y1397588D01*
G01Y1390502D02*
Y1391289D01*
G01Y1384203D02*
Y1384990D01*
G01Y1387352D02*
Y1388140D01*
G01Y1381053D02*
Y1381840D01*
G01Y1374754D02*
Y1375541D01*
G01Y1377903D02*
Y1378691D01*
G01Y1371604D02*
Y1372392D01*
G01Y1365305D02*
Y1366092D01*
G01Y1368455D02*
Y1369242D01*
G01Y1362155D02*
Y1362943D01*
G01X2346579Y1429238D02*
Y1423484D01*
G01X2345363Y1365305D02*
Y1362943D01*
G01Y1368455D02*
Y1366092D01*
G01Y1371604D02*
Y1369242D01*
G01Y1374754D02*
Y1372392D01*
G01Y1377903D02*
Y1375541D01*
G01Y1381053D02*
Y1378691D01*
G01Y1384203D02*
Y1381840D01*
G01Y1387352D02*
Y1384990D01*
G01Y1390502D02*
Y1388140D01*
G01Y1393651D02*
Y1391289D01*
G01Y1396801D02*
Y1394439D01*
G01Y1399951D02*
Y1397588D01*
G01Y1403100D02*
Y1400738D01*
G01Y1406250D02*
Y1403888D01*
G01Y1409400D02*
Y1407037D01*
G01Y1412549D02*
Y1410187D01*
G01Y1415010D02*
Y1413337D01*
G01X2344424Y1412549D02*
Y1413337D01*
G01Y1409400D02*
Y1410187D01*
G01Y1403100D02*
Y1403888D01*
G01Y1406250D02*
Y1407037D01*
G01Y1399951D02*
Y1400738D01*
G01Y1393651D02*
Y1394439D01*
G01Y1396801D02*
Y1397588D01*
G01Y1390502D02*
Y1391289D01*
G01Y1384203D02*
Y1384990D01*
G01Y1387352D02*
Y1388140D01*
G01Y1381053D02*
Y1381840D01*
G01Y1374754D02*
Y1375541D01*
G01Y1377903D02*
Y1378691D01*
G01Y1371604D02*
Y1372392D01*
G01Y1365305D02*
Y1366092D01*
G01Y1368455D02*
Y1369242D01*
G01Y1362155D02*
Y1362943D01*
G01X2344277Y1412549D02*
Y1413337D01*
G01Y1409400D02*
Y1410187D01*
G01Y1403100D02*
Y1403888D01*
G01Y1406250D02*
Y1407037D01*
G01Y1399951D02*
Y1400738D01*
G01Y1393651D02*
Y1394439D01*
G01Y1396801D02*
Y1397588D01*
G01Y1390502D02*
Y1391289D01*
G01Y1384203D02*
Y1384990D01*
G01Y1387352D02*
Y1388140D01*
G01Y1381053D02*
Y1381840D01*
G01Y1374754D02*
Y1375541D01*
G01Y1377903D02*
Y1378691D01*
G01Y1371604D02*
Y1372392D01*
G01Y1365305D02*
Y1366092D01*
G01Y1368455D02*
Y1369242D01*
G01Y1362155D02*
Y1362943D01*
G01X2342685Y1412549D02*
Y1413337D01*
G01Y1409400D02*
Y1410187D01*
G01Y1403100D02*
Y1403888D01*
G01Y1406250D02*
Y1407037D01*
G01Y1399951D02*
Y1400738D01*
G01Y1393651D02*
Y1394439D01*
G01Y1396801D02*
Y1397588D01*
G01Y1390502D02*
Y1391289D01*
G01Y1384203D02*
Y1384990D01*
G01Y1387352D02*
Y1388140D01*
G01Y1381053D02*
Y1381840D01*
G01Y1374754D02*
Y1375541D01*
G01Y1377903D02*
Y1378691D01*
G01Y1371604D02*
Y1372392D01*
G01Y1365305D02*
Y1366092D01*
G01Y1368455D02*
Y1369242D01*
G01Y1362155D02*
Y1362943D01*
G01X2341820Y1419537D02*
Y1422293D01*
G01X2341743Y1362943D02*
Y1362155D01*
G01Y1366092D02*
Y1365305D01*
G01Y1369242D02*
Y1368455D01*
G01Y1372392D02*
Y1371604D01*
G01Y1375541D02*
Y1374754D01*
G01Y1378691D02*
Y1377903D01*
G01Y1381840D02*
Y1381053D01*
G01Y1384990D02*
Y1384203D01*
G01Y1388140D02*
Y1387352D01*
G01Y1391289D02*
Y1390502D01*
G01Y1394439D02*
Y1393651D01*
G01Y1397588D02*
Y1396801D01*
G01Y1400738D02*
Y1399951D01*
G01Y1403888D02*
Y1403100D01*
G01Y1407037D02*
Y1406250D01*
G01Y1410187D02*
Y1409400D01*
G01Y1413337D02*
Y1412549D01*
G01X2338907Y1362943D02*
Y1362155D01*
G01Y1366092D02*
Y1365305D01*
G01Y1369242D02*
Y1368455D01*
G01Y1372392D02*
Y1371604D01*
G01Y1375541D02*
Y1374754D01*
G01Y1378691D02*
Y1377903D01*
G01Y1381840D02*
Y1381053D01*
G01Y1384990D02*
Y1384203D01*
G01Y1388140D02*
Y1387352D01*
G01Y1391289D02*
Y1390502D01*
G01Y1394439D02*
Y1393651D01*
G01Y1397588D02*
Y1396801D01*
G01Y1400738D02*
Y1399951D01*
G01Y1403888D02*
Y1403100D01*
G01Y1407037D02*
Y1406250D01*
G01Y1410187D02*
Y1409400D01*
G01Y1413337D02*
Y1412549D01*
G01X2338718D02*
Y1413337D01*
G01Y1409400D02*
Y1410187D01*
G01Y1403100D02*
Y1403888D01*
G01Y1406250D02*
Y1407037D01*
G01Y1399951D02*
Y1400738D01*
G01Y1393651D02*
Y1394439D01*
G01Y1396801D02*
Y1397588D01*
G01Y1390502D02*
Y1391289D01*
G01Y1384203D02*
Y1384990D01*
G01Y1387352D02*
Y1388140D01*
G01Y1381053D02*
Y1381840D01*
G01Y1374754D02*
Y1375541D01*
G01Y1377903D02*
Y1378691D01*
G01Y1371604D02*
Y1372392D01*
G01Y1365305D02*
Y1366092D01*
G01Y1368455D02*
Y1369242D01*
G01Y1362155D02*
Y1362943D01*
G01X2336945Y1412549D02*
Y1413337D01*
G01Y1409400D02*
Y1410187D01*
G01Y1403100D02*
Y1403888D01*
G01Y1406250D02*
Y1407037D01*
G01Y1399951D02*
Y1400738D01*
G01Y1393651D02*
Y1394439D01*
G01Y1396801D02*
Y1397588D01*
G01Y1390502D02*
Y1391289D01*
G01Y1384203D02*
Y1384990D01*
G01Y1387352D02*
Y1388140D01*
G01Y1381053D02*
Y1381840D01*
G01Y1374754D02*
Y1375541D01*
G01Y1377903D02*
Y1378691D01*
G01Y1371604D02*
Y1372392D01*
G01Y1365305D02*
Y1366092D01*
G01Y1368455D02*
Y1369242D01*
G01Y1362155D02*
Y1362943D01*
G01X2335966Y1419537D02*
Y1416762D01*
G01X2335491Y1422293D02*
Y1416762D01*
G01X2335173Y1430640D02*
Y1416762D01*
G01X2345620Y1423140D02*
X2345603Y1423084D01*
X2345550Y1422919D01*
X2345472Y1422660D01*
X2345376Y1422333D01*
X2345271Y1421959D01*
G01X2349878Y1429754D02*
X2345271D01*
G01X2389110Y1429459D02*
X2362732D01*
G01X2338463Y1429238D02*
X2336914D01*
G01X2341407D02*
X2339999D01*
G01X2348039D02*
X2346579D01*
G01X2355231D02*
X2353838D01*
G01X2358121D02*
X2356661D01*
G01X2360992D02*
X2359551D01*
G01X2358795Y1428671D02*
X2335173D01*
G01X2345620Y1428573D02*
X2349529D01*
G01X2343067Y1428082D02*
X2341564D01*
G01X2338235Y1427082D02*
X2336940Y1425231D01*
G01X2339011Y1426217D02*
X2338322Y1425231D01*
G01X2341407Y1429238D02*
X2339965Y1427091D01*
G01X2350333Y1419931D02*
X2350078Y1419537D01*
G01X2339999Y1429238D02*
X2339208Y1427960D01*
G01X2344433Y1427639D02*
X2341433D01*
G01X2344432Y1426813D02*
X2343007D01*
G01X2338322Y1425231D02*
X2336940D01*
G01X2341233D02*
X2339617D01*
G01X2360992D02*
X2359549D01*
G01X2358795Y1424892D02*
X2335173D01*
G01X2348039Y1423484D02*
X2346579D01*
G01X2349529Y1423140D02*
X2345620D01*
G01X2358795Y1422923D02*
X2335173D01*
G01X2385173Y1422293D02*
X2335173D01*
G01X2345271Y1421959D02*
X2349878D01*
G01X2335173Y1420522D02*
X2358795D01*
G01X2350333Y1419990D02*
X2356433D01*
G01X2350333Y1419931D02*
X2356433D01*
G01X2335966Y1419537D02*
X2356433D01*
G01X2355331Y1418356D02*
X2364701D01*
G01X2387142Y1417766D02*
X2356433D01*
G01X2385173Y1417372D02*
X2366669D01*
G01X2365016Y1417175D02*
X2358480D01*
G01X2335173Y1416762D02*
X2355331D01*
G01Y1416585D02*
X2364701D01*
G01X2352890Y1415128D02*
X2351905D01*
G01X2351315Y1415010D02*
X2342330D01*
G01X2352890Y1414931D02*
X2351905D01*
G01X2352890Y1414537D02*
X2351905D01*
G01X2347772Y1414340D02*
X2354937D01*
G01X2344277Y1413337D02*
X2336945D01*
G01X2356433D02*
X2344424D01*
G01X2347772Y1412766D02*
X2354937D01*
G01X2352890Y1412569D02*
X2351905D01*
G01X2344424Y1412549D02*
X2356433D01*
G01X2336945D02*
X2344277D01*
G01X2352890Y1412175D02*
X2351905D01*
G01X2352890Y1411978D02*
X2351905D01*
G01X2344277Y1410187D02*
X2336945D01*
G01X2356433D02*
X2344424D01*
G01X2352890Y1410128D02*
X2351905D01*
G01X2352890Y1409931D02*
X2351905D01*
G01X2352890Y1409537D02*
X2351905D01*
G01X2344424Y1409400D02*
X2356433D01*
G01X2336945D02*
X2344277D01*
G01X2347772Y1409340D02*
X2354937D01*
G01X2347772Y1407766D02*
X2354937D01*
G01X2352890Y1407569D02*
X2351905D01*
G01X2352890Y1407175D02*
X2351905D01*
G01X2344277Y1407037D02*
X2336945D01*
G01X2356433D02*
X2344424D01*
G01X2352890Y1406978D02*
X2351905D01*
G01X2344424Y1406250D02*
X2356433D01*
G01X2336945D02*
X2344277D01*
G01X2352890Y1405128D02*
X2351905D01*
G01X2352890Y1404931D02*
X2351905D01*
G01X2352890Y1404537D02*
X2351905D01*
G01X2347772Y1404340D02*
X2354937D01*
G01X2344277Y1403888D02*
X2336945D01*
G01X2356433D02*
X2344424D01*
G01Y1403100D02*
X2356433D01*
G01X2336945D02*
X2344277D01*
G01X2347772Y1402766D02*
X2354937D01*
G01X2352890Y1402569D02*
X2351905D01*
G01X2352890Y1402175D02*
X2351905D01*
G01X2352890Y1401978D02*
X2351905D01*
G01X2356433Y1400758D02*
X2355331D01*
G01X2344277Y1400738D02*
X2336945D01*
G01X2356433D02*
X2344424D01*
G01X2354858Y1400128D02*
X2353874D01*
G01X2344424Y1399951D02*
X2356433D01*
G01X2336945D02*
X2344277D01*
G01X2354858Y1399931D02*
X2353874D01*
G01X2385173Y1399655D02*
X2358480D01*
G01X2354858Y1399537D02*
X2353874D01*
G01X2355331Y1399340D02*
X2349740D01*
G01X2355331Y1397766D02*
X2349740D01*
G01X2344277Y1397588D02*
X2336945D01*
G01X2356433D02*
X2344424D01*
G01X2354858Y1397569D02*
X2353874D01*
G01X2385173Y1397293D02*
X2358480D01*
G01X2354858Y1397175D02*
X2353874D01*
G01X2354858Y1396978D02*
X2353874D01*
G01X2344424Y1396801D02*
X2356433D01*
G01X2336945D02*
X2344277D01*
G01X2356433Y1396348D02*
X2355331D01*
G01X2352890Y1395128D02*
X2351905D01*
G01X2352890Y1394931D02*
X2351905D01*
G01X2352890Y1394537D02*
X2351905D01*
G01X2344277Y1394439D02*
X2336945D01*
G01X2356433D02*
X2344424D01*
G01X2347772Y1394340D02*
X2354937D01*
G01X2344424Y1393651D02*
X2356433D01*
G01X2336945D02*
X2344277D01*
G01X2347772Y1392766D02*
X2354937D01*
G01X2352890Y1392569D02*
X2351905D01*
G01X2352890Y1392175D02*
X2351905D01*
G01X2352890Y1391978D02*
X2351905D01*
G01X2344277Y1391289D02*
X2336945D01*
G01X2356433D02*
X2344424D01*
G01Y1390502D02*
X2356433D01*
G01X2336945D02*
X2344277D01*
G01X2352890Y1390128D02*
X2351905D01*
G01X2352890Y1389931D02*
X2351905D01*
G01X2352890Y1389537D02*
X2351905D01*
G01X2347772Y1389340D02*
X2354937D01*
G01X2344277Y1388140D02*
X2336945D01*
G01X2356433D02*
X2344424D01*
G01X2347772Y1387766D02*
X2354937D01*
G01X2352890Y1387569D02*
X2351905D01*
G01X2344424Y1387352D02*
X2356433D01*
G01X2336945D02*
X2344277D01*
G01X2352890Y1387175D02*
X2351905D01*
G01X2352890Y1386978D02*
X2351905D01*
G01X2352890Y1385128D02*
X2351905D01*
G01X2344277Y1384990D02*
X2336945D01*
G01X2356433D02*
X2344424D01*
G01X2352890Y1384931D02*
X2351905D01*
G01X2352890Y1384537D02*
X2351905D01*
G01X2347772Y1384340D02*
X2354937D01*
G01X2344424Y1384203D02*
X2356433D01*
G01X2336945D02*
X2344277D01*
G01X2347772Y1382766D02*
X2354937D01*
G01X2352890Y1382569D02*
X2351905D01*
G01X2352890Y1382175D02*
X2351905D01*
G01X2352890Y1381978D02*
X2351905D01*
G01X2344277Y1381840D02*
X2336945D01*
G01X2356433D02*
X2344424D01*
G01Y1381053D02*
X2356433D01*
G01X2336945D02*
X2344277D01*
G01X2385173Y1380758D02*
X2358480D01*
G01X2352890Y1380128D02*
X2351905D01*
G01X2352890Y1379931D02*
X2351905D01*
G01X2352890Y1379537D02*
X2351905D01*
G01X2347772Y1379340D02*
X2354937D01*
G01X2344277Y1378691D02*
X2336945D01*
G01X2356433D02*
X2344424D01*
G01X2385173Y1378396D02*
X2358480D01*
G01X2344424Y1377903D02*
X2356433D01*
G01X2336945D02*
X2344277D01*
G01X2347772Y1377766D02*
X2354937D01*
G01X2352890Y1377569D02*
X2351905D01*
G01X2352890Y1377175D02*
X2351905D01*
G01X2352890Y1376978D02*
X2351905D01*
G01X2344277Y1375541D02*
X2336945D01*
G01X2356433D02*
X2344424D01*
G01X2352890Y1375128D02*
X2351905D01*
G01X2352890Y1374931D02*
X2351905D01*
G01X2344424Y1374754D02*
X2356433D01*
G01X2336945D02*
X2344277D01*
G01X2352890Y1374537D02*
X2351905D01*
G01X2347772Y1374340D02*
X2354937D01*
G01X2347772Y1372766D02*
X2354937D01*
G01X2352890Y1372569D02*
X2351905D01*
G01X2344277Y1372392D02*
X2336945D01*
G01X2356433D02*
X2344424D01*
G01X2352890Y1372175D02*
X2351905D01*
G01X2352890Y1371978D02*
X2351905D01*
G01X2344424Y1371604D02*
X2356433D01*
G01X2336945D02*
X2344277D01*
G01X2352890Y1370128D02*
X2351905D01*
G01X2352890Y1369931D02*
X2351905D01*
G01X2352890Y1369537D02*
X2351905D01*
G01X2347772Y1369340D02*
X2354937D01*
G01X2344277Y1369242D02*
X2336945D01*
G01X2356433D02*
X2344424D01*
G01Y1368455D02*
X2356433D01*
G01X2336945D02*
X2344277D01*
G01X2347772Y1367766D02*
X2354937D01*
G01X2352890Y1367569D02*
X2351905D01*
G01X2352890Y1367175D02*
X2351905D01*
G01X2352890Y1366978D02*
X2351905D01*
G01X2344277Y1366092D02*
X2336945D01*
G01X2356433D02*
X2344424D01*
G01Y1365305D02*
X2356433D01*
G01X2336945D02*
X2344277D01*
G01X2352890Y1365128D02*
X2351905D01*
G01X2352890Y1364931D02*
X2351905D01*
G01X2352890Y1364537D02*
X2351905D01*
G01X2347772Y1364340D02*
X2354937D01*
G01X2344277Y1362943D02*
X2336945D01*
G01X2356433D02*
X2344424D01*
G01X2347772Y1362766D02*
X2354937D01*
G01X2352890Y1362569D02*
X2351905D01*
G01X2352890Y1362175D02*
X2351905D01*
G01X2344424Y1362155D02*
X2356433D01*
G01X2336945D02*
X2344277D01*
G01X2352890Y1361978D02*
X2351905D01*
G01X2385173Y1361860D02*
X2358480D01*
G01X2355331Y1360758D02*
X2356433D01*
G01X2354858Y1360128D02*
X2353874D01*
G01X2354858Y1359931D02*
X2353874D01*
G01X2348638Y1443573D02*
Y1430640D01*
G01X2335173D02*
X2389110D01*
G01X2358992Y1436092D02*
G03Y1439242I0J1575D01*
G01X2354661D02*
G03Y1436092I0J-1575D01*
G01X2359617Y1436880D02*
Y1438455D01*
G01X2359583D02*
Y1436880D01*
G01X2359558Y1438455D02*
Y1436880D01*
G01X2358235D02*
Y1438455D01*
G01X2357865D02*
Y1436880D01*
G01X2355788D02*
Y1438455D01*
G01X2355418D02*
Y1436880D01*
G01X2354095D02*
Y1438455D01*
G01X2354071Y1436880D02*
Y1438455D01*
G01X2354036D02*
Y1436880D01*
G01X2365016Y1443573D02*
X2348638D01*
G01X2354661Y1439242D02*
X2358992D01*
G01X2354036Y1438455D02*
X2359617D01*
G01Y1436880D02*
X2354036D01*
G01X2358992Y1436092D02*
X2354661D01*
G01X2365016Y1433396D02*
X2348638D01*
G01X2359976Y1651171D02*
G03Y1649990I0J-590D01*
G01X2353677D02*
G03Y1651171I0J591D01*
G01X2353688Y1650919D02*
X2353781D01*
G01Y1650171D02*
X2353688D01*
G01X2358401Y1649695D02*
X2361551D01*
G01X2355252D02*
X2352102D01*
G01X2353677Y1649400D02*
X2359976D01*
G01X2361551Y1649695D02*
Y1651663D01*
G01X2359976Y1651171D02*
Y1652746D01*
G01Y1649400D02*
Y1649990D01*
G01X2358992Y1649400D02*
Y1654518D01*
G01X2358795D02*
Y1649400D01*
G01X2358401Y1651663D02*
Y1649695D01*
G01X2355252Y1651663D02*
Y1649695D01*
G01X2354858Y1654518D02*
Y1649400D01*
G01X2354661D02*
Y1654518D01*
G01X2353781Y1650919D02*
Y1650171D01*
G01X2353688D02*
Y1650792D01*
G01X2353677Y1649990D02*
Y1649400D01*
G01Y1652746D02*
Y1651171D01*
G01X2353594Y1650680D02*
Y1650808D01*
G01X2352102Y1649695D02*
Y1651663D01*
G01X2353688Y1650792D02*
X2353594Y1650680D01*
G01Y1650808D02*
X2353688Y1650919D01*
G01X2359976Y1653927D02*
G03Y1652746I0J-590D01*
G01X2358992Y1668376D02*
G03Y1671525I0J1575D01*
G01X2353234Y1680465D02*
G03X2352164Y1678642I2809J-2874D01*
G01X2360210Y1683366D02*
G03X2357996Y1678199I6938J-6031D01*
G01X2361096Y1683440D02*
G03X2358881Y1678199I7141J-6107D01*
G01X2354937Y1719852D02*
G03X2355331Y1720246I0J394D01*
G01Y1717884D02*
G03X2354937Y1718277I-394J-1D01*
G01Y1714852D02*
G03X2355331Y1715246I0J394D01*
G01Y1712884D02*
G03X2354937Y1713277I-394J-1D01*
G01Y1709852D02*
G03X2355331Y1710246I0J394D01*
G01Y1707884D02*
G03X2354937Y1708277I-394J-1D01*
G01Y1694852D02*
G03X2355331Y1695246I0J394D01*
G01Y1692884D02*
G03X2354937Y1693277I-394J-1D01*
G01Y1704852D02*
G03X2355331Y1705246I0J394D01*
G01Y1702884D02*
G03X2354937Y1703277I-394J-1D01*
G01Y1699852D02*
G03X2355331Y1700246I0J394D01*
G01Y1697884D02*
G03X2354937Y1698277I-394J-1D01*
G01X2353677Y1652746D02*
G03Y1653927I0J591D01*
G01X2354661Y1671525D02*
G03Y1668376I0J-1574D01*
G01X2353739Y1679921D02*
G03X2353197Y1678937I1276J-1344D01*
G01X2349740Y1681762D02*
G03I-2165J0D01*
G01X2350921D02*
G03I-3346J0D01*
G01X2351079D02*
G03I-3504J0D01*
G01X2352102D02*
G03I-4527J0D01*
G01X2339762Y1683366D02*
G03X2337548Y1678199I6938J-6031D01*
G01X2340648Y1683440D02*
G03X2338433Y1678199I7142J-6107D01*
G01X2350078Y1688081D02*
X2350333Y1687687D01*
G01X2360708Y1694039D02*
X2360882Y1693783D01*
G01X2358182Y1692418D02*
X2358007Y1692674D01*
G01X2354796Y1683116D02*
X2354978Y1682852D01*
X2355043Y1682553D01*
X2354978Y1682256D01*
G01X2347792Y1681455D02*
X2347469Y1681875D01*
X2347307Y1682358D01*
X2347328Y1682863D01*
X2347531Y1683340D01*
X2347898Y1683743D01*
X2348404Y1684010D01*
X2348995Y1684104D01*
X2349585Y1684007D01*
X2350087Y1683738D01*
X2350451Y1683334D01*
X2350652Y1682856D01*
X2350672Y1682352D01*
X2350508Y1681870D01*
X2350187Y1681455D01*
G01X2342624D02*
X2342302Y1681875D01*
X2342139Y1682358D01*
X2342161Y1682863D01*
X2342364Y1683340D01*
X2342731Y1683743D01*
X2343237Y1684010D01*
X2343828Y1684104D01*
X2344417Y1684007D01*
X2344920Y1683738D01*
X2345284Y1683334D01*
X2345485Y1682856D01*
X2345504Y1682352D01*
X2345340Y1681870D01*
X2345020Y1681455D01*
G01X2361231Y1694209D02*
X2360882Y1694550D01*
G01X2357659Y1692247D02*
X2358007Y1691906D01*
G01X2350187Y1681455D02*
X2350639Y1681015D01*
X2350909Y1680479D01*
X2350979Y1679909D01*
X2350838Y1679345D01*
X2350491Y1678820D01*
X2349964Y1678427D01*
X2349321Y1678224D01*
X2348642Y1678226D01*
X2348002Y1678434D01*
X2347479Y1678830D01*
X2347137Y1679354D01*
X2346999Y1679915D01*
X2347071Y1680483D01*
X2347341Y1681017D01*
G01X2345020Y1681455D02*
X2345472Y1681015D01*
X2345742Y1680479D01*
X2345812Y1679909D01*
X2345670Y1679345D01*
X2345324Y1678820D01*
X2344796Y1678427D01*
X2344154Y1678224D01*
X2343474Y1678226D01*
X2342834Y1678434D01*
X2342312Y1678830D01*
X2341970Y1679354D01*
X2341832Y1679915D01*
X2341904Y1680483D01*
X2342174Y1681017D01*
G01X2358094Y1695915D02*
X2358704Y1695403D01*
G01X2358007D02*
X2357398Y1695915D01*
G01X2349413Y1681000D02*
X2349773Y1680764D01*
X2350011Y1680414D01*
X2350097Y1680010D01*
X2350014Y1679608D01*
X2349778Y1679256D01*
X2349414Y1679016D01*
X2348990Y1678931D01*
G01X2348567Y1679015D02*
X2348206Y1679251D01*
X2347968Y1679601D01*
X2347882Y1680005D01*
X2347965Y1680407D01*
X2348201Y1680759D01*
X2348565Y1680999D01*
X2348990Y1681084D01*
G01X2344245Y1681000D02*
X2344606Y1680764D01*
X2344844Y1680414D01*
X2344929Y1680010D01*
X2344847Y1679608D01*
X2344610Y1679256D01*
X2344247Y1679016D01*
X2343822Y1678931D01*
G01X2343399Y1679015D02*
X2343039Y1679251D01*
X2342800Y1679601D01*
X2342715Y1680005D01*
X2342798Y1680407D01*
X2343034Y1680759D01*
X2343397Y1680999D01*
X2343822Y1681084D01*
G01X2360447Y1694209D02*
X2360708Y1694039D01*
G01X2354516Y1683297D02*
X2354796Y1683116D01*
G01X2349338Y1683301D02*
X2349621Y1683123D01*
X2349808Y1682858D01*
X2349875Y1682556D01*
X2349811Y1682256D01*
X2349625Y1681989D01*
X2349340Y1681808D01*
X2348990Y1681742D01*
G01X2348641Y1681807D02*
X2348358Y1681985D01*
X2348171Y1682250D01*
X2348104Y1682552D01*
X2348168Y1682852D01*
X2348354Y1683119D01*
X2348639Y1683300D01*
X2348990Y1683366D01*
G01X2344171Y1683301D02*
X2344454Y1683123D01*
X2344641Y1682858D01*
X2344708Y1682556D01*
X2344644Y1682256D01*
X2344458Y1681989D01*
X2344173Y1681808D01*
X2343822Y1681742D01*
G01X2343473Y1681807D02*
X2343191Y1681985D01*
X2343004Y1682250D01*
X2342937Y1682552D01*
X2343001Y1682852D01*
X2343186Y1683119D01*
X2343472Y1683300D01*
X2343822Y1683366D01*
G01X2360882Y1694550D02*
X2360534Y1694721D01*
G01X2360882Y1693783D02*
X2360969Y1693442D01*
G01X2357398Y1692930D02*
X2357485Y1692588D01*
G01X2358007Y1692674D02*
X2357920Y1692930D01*
G01X2361405Y1693868D02*
X2361231Y1694209D01*
G01X2357485Y1692588D02*
X2357659Y1692247D01*
G01X2358443Y1692333D02*
X2358182Y1692418D01*
G01X2358007Y1691906D02*
X2358356Y1691821D01*
G01X2354169Y1683366D02*
X2354517Y1683297D01*
G01X2361492Y1693442D02*
X2361405Y1693868D01*
G01X2352890Y1720640D02*
X2351905D01*
G01X2386130Y1720463D02*
X2366669D01*
G01X2352890Y1720443D02*
X2351905D01*
G01X2344424Y1720423D02*
X2356433D01*
G01X2336945D02*
X2344277D01*
G01X2352890Y1720049D02*
X2351905D01*
G01X2347772Y1719852D02*
X2354937D01*
G01X2347772Y1718277D02*
X2354937D01*
G01X2352890Y1718081D02*
X2351905D01*
G01X2344277Y1718061D02*
X2336945D01*
G01X2356433D02*
X2344424D01*
G01X2352890Y1717687D02*
X2351905D01*
G01X2352890Y1717490D02*
X2351905D01*
G01X2344424Y1717274D02*
X2356433D01*
G01X2336945D02*
X2344277D01*
G01X2352890Y1715640D02*
X2351905D01*
G01X2352890Y1715443D02*
X2351905D01*
G01X2352890Y1715049D02*
X2351905D01*
G01X2344277Y1714911D02*
X2336945D01*
G01X2356433D02*
X2344424D01*
G01X2347772Y1714852D02*
X2354937D01*
G01X2344424Y1714124D02*
X2356433D01*
G01X2336945D02*
X2344277D01*
G01X2347772Y1713277D02*
X2354937D01*
G01X2352890Y1713081D02*
X2351905D01*
G01X2352890Y1712687D02*
X2351905D01*
G01X2352890Y1712490D02*
X2351905D01*
G01X2344277Y1711762D02*
X2336945D01*
G01X2356433D02*
X2344424D01*
G01Y1710974D02*
X2356433D01*
G01X2336945D02*
X2344277D01*
G01X2352890Y1710640D02*
X2351905D01*
G01X2352890Y1710443D02*
X2351905D01*
G01X2352890Y1710049D02*
X2351905D01*
G01X2347772Y1709852D02*
X2354937D01*
G01X2385173Y1709222D02*
X2358480D01*
G01X2344277Y1708612D02*
X2336945D01*
G01X2356433D02*
X2344424D01*
G01X2347772Y1708277D02*
X2354937D01*
G01X2352890Y1708081D02*
X2351905D01*
G01X2344424Y1707825D02*
X2356433D01*
G01X2336945D02*
X2344277D01*
G01X2352890Y1707687D02*
X2351905D01*
G01X2352890Y1707490D02*
X2351905D01*
G01X2385173Y1706860D02*
X2358480D01*
G01X2352890Y1705640D02*
X2351905D01*
G01X2344277Y1705463D02*
X2336945D01*
G01X2356433D02*
X2344424D01*
G01X2352890Y1705443D02*
X2351905D01*
G01X2352890Y1705049D02*
X2351905D01*
G01X2347772Y1704852D02*
X2354937D01*
G01X2344424Y1704675D02*
X2356433D01*
G01X2336945D02*
X2344277D01*
G01X2347772Y1703277D02*
X2354937D01*
G01X2352890Y1703081D02*
X2351905D01*
G01X2352890Y1702687D02*
X2351905D01*
G01X2352890Y1702490D02*
X2351905D01*
G01X2344277Y1702313D02*
X2336945D01*
G01X2356433D02*
X2344424D01*
G01Y1701525D02*
X2356433D01*
G01X2336945D02*
X2344277D01*
G01X2352890Y1700640D02*
X2351905D01*
G01X2352890Y1700443D02*
X2351905D01*
G01X2352890Y1700049D02*
X2351905D01*
G01X2347772Y1699852D02*
X2354937D01*
G01X2344277Y1699163D02*
X2336945D01*
G01X2356433D02*
X2344424D01*
G01Y1698376D02*
X2356433D01*
G01X2336945D02*
X2344277D01*
G01X2347772Y1698277D02*
X2354937D01*
G01X2352890Y1698081D02*
X2351905D01*
G01X2352890Y1697687D02*
X2351905D01*
G01X2352890Y1697490D02*
X2351905D01*
G01X2357398Y1696427D02*
X2361492D01*
G01X2344277Y1696014D02*
X2336945D01*
G01X2356433D02*
X2344424D01*
G01X2361492Y1695915D02*
X2358094D01*
G01X2352890Y1695640D02*
X2351905D01*
G01X2352890Y1695443D02*
X2351905D01*
G01X2358704Y1695403D02*
X2358007D01*
G01X2344424Y1695226D02*
X2356433D01*
G01X2336945D02*
X2344277D01*
G01X2354878Y1695069D02*
X2346807D01*
G01X2352890Y1695049D02*
X2351905D01*
G01X2347772Y1694852D02*
X2354937D01*
G01X2360534Y1694721D02*
X2360098D01*
G01X2360185Y1694209D02*
X2360447D01*
G01X2347772Y1693277D02*
X2354937D01*
G01X2346807Y1693100D02*
X2354878D01*
G01X2352890Y1693081D02*
X2351905D01*
G01X2352890Y1692687D02*
X2351905D01*
G01X2351315Y1692648D02*
X2342330D01*
G01X2352890Y1692490D02*
X2351905D01*
G01X2358617Y1692333D02*
X2358443D01*
G01X2358356Y1691821D02*
X2358704D01*
G01X2355331Y1691033D02*
X2364701D01*
G01X2355331Y1690659D02*
X2335173D01*
G01X2365016Y1690443D02*
X2358480D01*
G01X2385173Y1690246D02*
X2366669D01*
G01X2356433Y1689852D02*
X2387142D01*
G01X2355331Y1689262D02*
X2364701D01*
G01X2335966Y1688081D02*
X2356433D01*
G01X2350333Y1687687D02*
X2356433D01*
G01Y1687628D02*
X2350333D01*
G01X2358795Y1687136D02*
X2335173D01*
G01X2385173Y1685325D02*
X2335173D01*
G01Y1684695D02*
X2358795D01*
G01X2340648Y1684104D02*
X2336809D01*
G01X2361096D02*
X2357257D01*
G01Y1683366D02*
X2360210D01*
G01X2336809D02*
X2339762D01*
G01X2358795Y1682726D02*
X2335173D01*
G01X2352459Y1682406D02*
X2353271D01*
G01X2358795Y1678947D02*
X2335173D01*
G01X2356076Y1678937D02*
X2353197D01*
G01X2357995Y1678199D02*
X2358881D01*
G01X2352164D02*
X2356076D01*
G01X2337548D02*
X2338433D01*
G01X2362732Y1678159D02*
X2389110D01*
G01Y1676978D02*
X2335173D01*
G01X2365016Y1674222D02*
X2348638D01*
G01X2354661Y1671525D02*
X2358992D01*
G01X2354036Y1670738D02*
X2359617D01*
G01Y1669163D02*
X2354036D01*
G01X2358992Y1668376D02*
X2354661D01*
G01X2365016Y1664045D02*
X2348638D01*
G01X2366669Y1822884D02*
Y1690246D01*
G01X2365016Y1664045D02*
Y1690443D01*
G01X2364701Y1691033D02*
Y1689262D01*
G01X2359976Y1654518D02*
X2353677D01*
G01X2358401Y1654222D02*
X2361551D01*
G01X2355252D02*
X2352102D01*
G01Y1652254D02*
X2355252D01*
G01X2361551D02*
X2358401D01*
G01X2352102Y1651663D02*
X2355252D01*
G01X2361551D02*
X2358401D01*
G01X2358704Y1691821D02*
X2359053Y1691906D01*
G01X2360359Y1691565D02*
X2360708Y1691650D01*
G01X2362732Y1676978D02*
Y1685325D01*
G01X2361551Y1654222D02*
Y1652254D01*
G01X2361492Y1692759D02*
Y1693442D01*
G01Y1696427D02*
Y1695915D01*
G01X2361096Y1683440D02*
Y1684104D01*
G01X2360969Y1693442D02*
Y1692759D01*
G01X2360449Y1706860D02*
Y1690443D01*
G01Y1724459D02*
Y1709222D01*
G01X2360359Y1692077D02*
Y1691565D01*
G01X2359976Y1653927D02*
Y1654518D01*
G01X2359663Y1692930D02*
Y1693442D01*
G01X2359617Y1669163D02*
Y1670738D01*
G01X2359583D02*
Y1669163D01*
G01X2359558Y1670738D02*
Y1669163D01*
G01X2359140Y1693442D02*
Y1692930D01*
G01X2358795Y1682726D02*
Y1678947D01*
G01Y1687136D02*
Y1684695D01*
G01X2358480Y1690443D02*
Y1822687D01*
G01X2358401Y1652254D02*
Y1654222D01*
G01X2358356Y1693953D02*
Y1694465D01*
G01X2358235Y1669163D02*
Y1670738D01*
G01X2357920Y1692930D02*
Y1693442D01*
G01X2357865Y1670738D02*
Y1669163D01*
G01X2357398Y1695915D02*
Y1696427D01*
G01Y1693356D02*
Y1692930D01*
G01X2357257Y1684104D02*
Y1683366D01*
G01X2356433Y1825502D02*
Y1687628D01*
G01X2356076Y1678199D02*
Y1678937D01*
G01X2355788Y1669163D02*
Y1670738D01*
G01X2355418D02*
Y1669163D01*
G01X2355331Y1688081D02*
Y1825049D01*
G01X2355252Y1652254D02*
Y1654222D01*
G01X2354878Y1693100D02*
Y1695069D01*
G01X2354491Y1717274D02*
Y1718061D01*
G01Y1720423D02*
Y1721211D01*
G01Y1714124D02*
Y1714911D01*
G01Y1707825D02*
Y1708612D01*
G01Y1710974D02*
Y1711762D01*
G01Y1704675D02*
Y1705463D01*
G01Y1698376D02*
Y1699163D01*
G01Y1701525D02*
Y1702313D01*
G01Y1695226D02*
Y1696014D01*
G01X2354464Y1717274D02*
Y1718061D01*
G01Y1720423D02*
Y1721211D01*
G01Y1714124D02*
Y1714911D01*
G01Y1707825D02*
Y1708612D01*
G01Y1710974D02*
Y1711762D01*
G01Y1704675D02*
Y1705463D01*
G01Y1698376D02*
Y1699163D01*
G01Y1701525D02*
Y1702313D01*
G01Y1695226D02*
Y1696014D01*
G01X2354095Y1669163D02*
Y1670738D01*
G01X2354088Y1717274D02*
Y1718061D01*
G01Y1720423D02*
Y1721211D01*
G01Y1714124D02*
Y1714911D01*
G01Y1707825D02*
Y1708612D01*
G01Y1710974D02*
Y1711762D01*
G01Y1704675D02*
Y1705463D01*
G01Y1698376D02*
Y1699163D01*
G01Y1701525D02*
Y1702313D01*
G01Y1695226D02*
Y1696014D01*
G01X2354071Y1669163D02*
Y1670738D01*
G01X2354036D02*
Y1669163D01*
G01X2353874Y1694852D02*
Y1693277D01*
G01Y1699852D02*
Y1698277D01*
G01Y1704852D02*
Y1703277D01*
G01Y1709852D02*
Y1708277D01*
G01Y1714852D02*
Y1713277D01*
G01Y1719852D02*
Y1718277D01*
G01X2353677Y1654518D02*
Y1653927D01*
G01X2353271Y1682406D02*
Y1682554D01*
G01X2352890Y1687628D02*
Y1685325D01*
G01Y1695640D02*
Y1692490D01*
G01Y1700640D02*
Y1697490D01*
G01Y1705640D02*
Y1702490D01*
G01Y1710640D02*
Y1707490D01*
G01Y1715640D02*
Y1712490D01*
G01Y1720640D02*
Y1717490D01*
G01X2352459Y1682554D02*
Y1682406D01*
G01X2352164Y1678642D02*
Y1678199D01*
G01X2352102Y1654222D02*
Y1652254D01*
G01X2351905Y1695640D02*
Y1692490D01*
G01Y1700640D02*
Y1697490D01*
G01Y1705640D02*
Y1702490D01*
G01Y1710640D02*
Y1707490D01*
G01Y1715640D02*
Y1712490D01*
G01Y1720640D02*
Y1717490D01*
G01X2351315Y1688081D02*
Y1825049D01*
G01X2350921Y1694852D02*
Y1693277D01*
G01Y1699852D02*
Y1698277D01*
G01Y1704852D02*
Y1703277D01*
G01Y1709852D02*
Y1708277D01*
G01Y1714852D02*
Y1713277D01*
G01Y1719852D02*
Y1718277D01*
G01X2350860Y1690659D02*
Y1822274D01*
G01X2350726Y1696014D02*
Y1695226D01*
G01Y1699163D02*
Y1698376D01*
G01Y1702313D02*
Y1701525D01*
G01Y1705463D02*
Y1704675D01*
G01Y1708612D02*
Y1707825D01*
G01Y1711762D02*
Y1710974D01*
G01Y1714911D02*
Y1714124D01*
G01Y1718061D02*
Y1717274D01*
G01Y1721211D02*
Y1720423D01*
G01X2350333Y1687687D02*
Y1687628D01*
G01X2349694Y1685325D02*
Y1688081D01*
G01X2348743Y1696014D02*
Y1695226D01*
G01Y1699163D02*
Y1698376D01*
G01Y1702313D02*
Y1701525D01*
G01Y1705463D02*
Y1704675D01*
G01Y1708612D02*
Y1707825D01*
G01Y1711762D02*
Y1710974D01*
G01Y1714911D02*
Y1714124D01*
G01Y1718061D02*
Y1717274D01*
G01Y1721211D02*
Y1720423D01*
G01X2348638Y1676978D02*
Y1664045D01*
G01X2347772Y1694852D02*
Y1693277D01*
G01Y1699852D02*
Y1698277D01*
G01Y1704852D02*
Y1703277D01*
G01Y1709852D02*
Y1708277D01*
G01Y1714852D02*
Y1713277D01*
G01Y1719852D02*
Y1718277D01*
G01X2347091Y1717274D02*
Y1718061D01*
G01Y1720423D02*
Y1721211D01*
G01Y1714124D02*
Y1714911D01*
G01Y1707825D02*
Y1708612D01*
G01Y1710974D02*
Y1711762D01*
G01Y1704675D02*
Y1705463D01*
G01Y1698376D02*
Y1699163D01*
G01Y1701525D02*
Y1702313D01*
G01Y1695226D02*
Y1696014D01*
G01X2346807Y1695069D02*
Y1693100D01*
G01X2345363Y1695226D02*
Y1692648D01*
G01Y1698376D02*
Y1696014D01*
G01Y1701525D02*
Y1699163D01*
G01Y1704675D02*
Y1702313D01*
G01Y1707825D02*
Y1705463D01*
G01Y1710974D02*
Y1708612D01*
G01Y1714124D02*
Y1711762D01*
G01Y1717274D02*
Y1714911D01*
G01Y1720423D02*
Y1718061D01*
G01X2344424Y1717274D02*
Y1718061D01*
G01Y1720423D02*
Y1721211D01*
G01Y1714124D02*
Y1714911D01*
G01Y1707825D02*
Y1708612D01*
G01Y1710974D02*
Y1711762D01*
G01Y1704675D02*
Y1705463D01*
G01Y1698376D02*
Y1699163D01*
G01Y1701525D02*
Y1702313D01*
G01Y1695226D02*
Y1696014D01*
G01X2344277Y1717274D02*
Y1718061D01*
G01Y1720423D02*
Y1721211D01*
G01Y1714124D02*
Y1714911D01*
G01Y1707825D02*
Y1708612D01*
G01Y1710974D02*
Y1711762D01*
G01Y1704675D02*
Y1705463D01*
G01Y1698376D02*
Y1699163D01*
G01Y1701525D02*
Y1702313D01*
G01Y1695226D02*
Y1696014D01*
G01X2342685Y1717274D02*
Y1718061D01*
G01Y1720423D02*
Y1721211D01*
G01Y1714124D02*
Y1714911D01*
G01Y1707825D02*
Y1708612D01*
G01Y1710974D02*
Y1711762D01*
G01Y1704675D02*
Y1705463D01*
G01Y1698376D02*
Y1699163D01*
G01Y1701525D02*
Y1702313D01*
G01Y1695226D02*
Y1696014D01*
G01X2342330Y1825049D02*
Y1688081D01*
G01X2341820Y1685325D02*
Y1688081D01*
G01X2341743Y1696014D02*
Y1695226D01*
G01Y1699163D02*
Y1698376D01*
G01Y1702313D02*
Y1701525D01*
G01Y1705463D02*
Y1704675D01*
G01Y1708612D02*
Y1707825D01*
G01Y1711762D02*
Y1710974D01*
G01Y1714911D02*
Y1714124D01*
G01Y1718061D02*
Y1717274D01*
G01Y1721211D02*
Y1720423D01*
G01X2340648Y1683440D02*
Y1684104D01*
G01X2338907Y1696014D02*
Y1695226D01*
G01Y1699163D02*
Y1698376D01*
G01Y1702313D02*
Y1701525D01*
G01Y1705463D02*
Y1704675D01*
G01Y1708612D02*
Y1707825D01*
G01Y1711762D02*
Y1710974D01*
G01Y1714911D02*
Y1714124D01*
G01Y1718061D02*
Y1717274D01*
G01Y1721211D02*
Y1720423D01*
G01X2338718Y1717274D02*
Y1718061D01*
G01Y1720423D02*
Y1721211D01*
G01Y1714124D02*
Y1714911D01*
G01Y1707825D02*
Y1708612D01*
G01Y1710974D02*
Y1711762D01*
G01Y1704675D02*
Y1705463D01*
G01Y1698376D02*
Y1699163D01*
G01Y1701525D02*
Y1702313D01*
G01Y1695226D02*
Y1696014D01*
G01X2336945Y1717274D02*
Y1718061D01*
G01Y1720423D02*
Y1721211D01*
G01Y1714124D02*
Y1714911D01*
G01Y1707825D02*
Y1708612D01*
G01Y1710974D02*
Y1711762D01*
G01Y1704675D02*
Y1705463D01*
G01Y1698376D02*
Y1699163D01*
G01Y1701525D02*
Y1702313D01*
G01Y1695226D02*
Y1696014D01*
G01X2336809Y1684104D02*
Y1683366D01*
G01X2335966Y1690659D02*
Y1688081D01*
G01X2335491Y1690659D02*
Y1685325D01*
G01X2335173Y1690659D02*
Y1676978D01*
G01X2360969Y1692759D02*
X2360882Y1692418D01*
G01X2359575Y1692588D02*
X2359663Y1692930D01*
G01Y1693442D02*
X2359750Y1693783D01*
G01X2353338Y1682859D02*
X2353271Y1682554D01*
G01X2361405Y1692333D02*
X2361492Y1692759D01*
G01X2359227Y1693868D02*
X2359140Y1693442D01*
G01X2357485Y1693783D02*
X2357398Y1693356D01*
G01X2352459Y1682554D02*
X2352546Y1683031D01*
X2352793Y1683473D01*
X2353182Y1683825D01*
X2353688Y1684045D01*
X2354266Y1684101D01*
X2354829Y1683979D01*
X2355305Y1683696D01*
X2355644Y1683292D01*
X2355824Y1682835D01*
X2355839Y1682355D01*
X2355682Y1681884D01*
X2355368Y1681467D01*
G01X2359140Y1692930D02*
X2359053Y1692674D01*
G01X2357920Y1693442D02*
X2358007Y1693697D01*
G01X2361144Y1691906D02*
X2361405Y1692333D01*
G01X2359401Y1692247D02*
X2359575Y1692588D01*
G01X2359401Y1694209D02*
X2359227Y1693868D01*
G01X2350187Y1681455D02*
X2350510Y1681875D01*
X2350673Y1682358D01*
X2350651Y1682863D01*
X2350448Y1683340D01*
X2350081Y1683743D01*
X2349575Y1684010D01*
X2348984Y1684104D01*
X2348395Y1684007D01*
X2347892Y1683738D01*
X2347528Y1683334D01*
X2347327Y1682856D01*
X2347308Y1682352D01*
X2347471Y1681870D01*
X2347792Y1681455D01*
G01X2345020D02*
X2345343Y1681875D01*
X2345505Y1682358D01*
X2345484Y1682863D01*
X2345281Y1683340D01*
X2344914Y1683743D01*
X2344408Y1684010D01*
X2343816Y1684104D01*
X2343227Y1684007D01*
X2342725Y1683738D01*
X2342361Y1683334D01*
X2342159Y1682856D01*
X2342140Y1682352D01*
X2342304Y1681870D01*
X2342624Y1681455D01*
G01X2357746Y1694124D02*
X2357485Y1693783D01*
G01X2355368Y1681467D02*
X2355705Y1681929D01*
X2355850Y1682447D01*
X2355790Y1682965D01*
X2355539Y1683449D01*
X2355102Y1683844D01*
X2354529Y1684067D01*
X2353895Y1684086D01*
X2353310Y1683900D01*
X2352855Y1683547D01*
X2352563Y1683075D01*
X2352459Y1682554D01*
G01X2353528Y1683126D02*
X2353338Y1682858D01*
G01X2354796Y1681992D02*
X2354979Y1682258D01*
X2355043Y1682555D01*
X2354978Y1682853D01*
G01X2359053Y1692674D02*
X2358879Y1692418D01*
G01X2359750Y1693783D02*
X2359924Y1694039D01*
G01X2355368Y1681467D02*
X2353739Y1679921D01*
G01X2347792Y1681455D02*
X2347340Y1681015D01*
X2347070Y1680479D01*
X2347000Y1679909D01*
X2347141Y1679345D01*
X2347488Y1678820D01*
X2348015Y1678427D01*
X2348658Y1678224D01*
X2349337Y1678226D01*
X2349977Y1678434D01*
X2350500Y1678830D01*
X2350842Y1679354D01*
X2350980Y1679915D01*
X2350908Y1680483D01*
X2350638Y1681017D01*
G01X2342624Y1681455D02*
X2342173Y1681015D01*
X2341903Y1680479D01*
X2341832Y1679909D01*
X2341974Y1679345D01*
X2342321Y1678820D01*
X2342848Y1678427D01*
X2343491Y1678224D01*
X2344170Y1678226D01*
X2344810Y1678434D01*
X2345333Y1678830D01*
X2345674Y1679354D01*
X2345812Y1679915D01*
X2345741Y1680483D01*
X2345470Y1681017D01*
G01X2354796Y1681992D02*
X2353234Y1680465D01*
G01X2360882Y1692418D02*
X2360621Y1692162D01*
G01X2359053Y1691906D02*
X2359401Y1692247D01*
G01X2359750Y1694550D02*
X2359401Y1694209D01*
G01X2358007Y1693697D02*
X2358182Y1693868D01*
G01X2349413Y1679015D02*
X2349773Y1679251D01*
X2350011Y1679601D01*
X2350097Y1680005D01*
X2350014Y1680407D01*
X2349778Y1680759D01*
X2349414Y1680999D01*
X2348990Y1681084D01*
G01X2348567Y1681000D02*
X2348206Y1680764D01*
X2347968Y1680414D01*
X2347882Y1680010D01*
X2347965Y1679608D01*
X2348201Y1679256D01*
X2348565Y1679016D01*
X2348990Y1678931D01*
G01X2344245Y1679015D02*
X2344606Y1679251D01*
X2344844Y1679601D01*
X2344929Y1680005D01*
X2344847Y1680407D01*
X2344610Y1680759D01*
X2344247Y1680999D01*
X2343822Y1681084D01*
G01X2343399Y1681000D02*
X2343039Y1680764D01*
X2342800Y1680414D01*
X2342715Y1680010D01*
X2342798Y1679608D01*
X2343034Y1679256D01*
X2343397Y1679016D01*
X2343822Y1678931D01*
G01X2358094Y1694380D02*
X2357746Y1694124D01*
G01X2360098Y1694721D02*
X2359750Y1694550D01*
G01X2358182Y1693868D02*
X2358356Y1693953D01*
G01X2360708Y1691650D02*
X2361144Y1691906D01*
G01X2353528Y1683125D02*
X2353815Y1683304D01*
X2354169Y1683366D01*
G01X2349338Y1681807D02*
X2349621Y1681985D01*
X2349808Y1682250D01*
X2349875Y1682552D01*
X2349811Y1682852D01*
X2349625Y1683119D01*
X2349340Y1683300D01*
X2348990Y1683366D01*
G01X2348641Y1683301D02*
X2348358Y1683123D01*
X2348171Y1682858D01*
X2348104Y1682556D01*
X2348168Y1682256D01*
X2348354Y1681989D01*
X2348639Y1681808D01*
X2348990Y1681742D01*
G01X2344171Y1681807D02*
X2344454Y1681985D01*
X2344641Y1682250D01*
X2344708Y1682552D01*
X2344644Y1682852D01*
X2344458Y1683119D01*
X2344173Y1683300D01*
X2343822Y1683366D01*
G01X2343473Y1683301D02*
X2343191Y1683123D01*
X2343004Y1682858D01*
X2342937Y1682556D01*
X2343001Y1682256D01*
X2343186Y1681989D01*
X2343472Y1681808D01*
X2343822Y1681742D01*
G01X2359924Y1694039D02*
X2360185Y1694209D01*
G01X2360621Y1692162D02*
X2360359Y1692077D01*
G01X2358879Y1692418D02*
X2358617Y1692333D01*
G01X2358356Y1694465D02*
X2358094Y1694380D01*
G01X2355331Y1722884D02*
G03X2354937Y1723277I-394J-1D01*
G01X2344424Y1723573D02*
X2356433D01*
G01X2336945D02*
X2344277D01*
G01X2347772Y1723277D02*
X2354937D01*
G01X2352890Y1723081D02*
X2351905D01*
G01X2352890Y1722687D02*
X2351905D01*
G01X2352890Y1722490D02*
X2351905D01*
G01X2344277Y1721211D02*
X2336945D01*
G01X2356433D02*
X2344424D01*
G01X2354491Y1723573D02*
Y1724360D01*
G01X2354464Y1723573D02*
Y1724360D01*
G01X2354088Y1723573D02*
Y1724360D01*
G01X2353874Y1724852D02*
Y1723277D01*
G01X2352890Y1725640D02*
Y1722490D01*
G01X2351905Y1725640D02*
Y1722490D01*
G01X2350921Y1724852D02*
Y1723277D01*
G01X2350726Y1724360D02*
Y1723573D01*
G01X2348743Y1724360D02*
Y1723573D01*
G01X2347772Y1724852D02*
Y1723277D01*
G01X2347091Y1723573D02*
Y1724360D01*
G01X2345363Y1723573D02*
Y1721211D01*
G01X2344424Y1723573D02*
Y1724360D01*
G01X2344277Y1723573D02*
Y1724360D01*
G01X2342685Y1723573D02*
Y1724360D01*
G01X2341743D02*
Y1723573D01*
G01X2338907Y1724360D02*
Y1723573D01*
G01X2338718D02*
Y1724360D01*
G01X2336945Y1723573D02*
Y1724360D01*
G01X2354937Y1769852D02*
G03X2355331Y1770246I0J394D01*
G01Y1767884D02*
G03X2354937Y1768277I-394J-1D01*
G01Y1779852D02*
G03X2355331Y1780246I0J394D01*
G01Y1777884D02*
G03X2354937Y1778277I-394J-1D01*
G01Y1784852D02*
G03X2355331Y1785246I0J394D01*
G01Y1782884D02*
G03X2354937Y1783277I-394J-1D01*
G01X2355331Y1792884D02*
G03X2354937Y1793277I-394J-1D01*
G01Y1789852D02*
G03X2355331Y1790246I0J394D01*
G01Y1787884D02*
G03X2354937Y1788277I-394J-1D01*
G01Y1774852D02*
G03X2355331Y1775246I0J394D01*
G01Y1772884D02*
G03X2354937Y1773277I-394J-1D01*
G01Y1754852D02*
G03X2355331Y1755246I0J394D01*
G01Y1752884D02*
G03X2354937Y1753277I-394J-1D01*
G01Y1759852D02*
G03X2355331Y1760246I0J394D01*
G01Y1757884D02*
G03X2354937Y1758277I-394J-1D01*
G01Y1724852D02*
G03X2355331Y1725246I0J394D01*
G01X2354937Y1749852D02*
G03X2355331Y1750246I0J394D01*
G01Y1747884D02*
G03X2354937Y1748277I-394J-1D01*
G01X2344277Y1793651D02*
X2336945D01*
G01X2356433D02*
X2344424D01*
G01X2347772Y1793277D02*
X2354937D01*
G01X2352890Y1793081D02*
X2351905D01*
G01X2344424Y1792864D02*
X2356433D01*
G01X2336945D02*
X2344277D01*
G01X2352890Y1792687D02*
X2351905D01*
G01X2352890Y1792490D02*
X2351905D01*
G01X2352890Y1790640D02*
X2351905D01*
G01X2344277Y1790502D02*
X2336945D01*
G01X2356433D02*
X2344424D01*
G01X2352890Y1790443D02*
X2351905D01*
G01X2352890Y1790049D02*
X2351905D01*
G01X2347772Y1789852D02*
X2354937D01*
G01X2344424Y1789714D02*
X2356433D01*
G01X2336945D02*
X2344277D01*
G01X2347772Y1788277D02*
X2354937D01*
G01X2352890Y1788081D02*
X2351905D01*
G01X2352890Y1787687D02*
X2351905D01*
G01X2352890Y1787490D02*
X2351905D01*
G01X2344277Y1787352D02*
X2336945D01*
G01X2356433D02*
X2344424D01*
G01Y1786565D02*
X2356433D01*
G01X2336945D02*
X2344277D01*
G01X2385173Y1786270D02*
X2358480D01*
G01X2352890Y1785640D02*
X2351905D01*
G01X2352890Y1785443D02*
X2351905D01*
G01X2352890Y1785049D02*
X2351905D01*
G01X2347772Y1784852D02*
X2354937D01*
G01X2344277Y1784203D02*
X2336945D01*
G01X2356433D02*
X2344424D01*
G01X2385173Y1783907D02*
X2358480D01*
G01X2344424Y1783415D02*
X2356433D01*
G01X2336945D02*
X2344277D01*
G01X2347772Y1783277D02*
X2354937D01*
G01X2352890Y1783081D02*
X2351905D01*
G01X2352890Y1782687D02*
X2351905D01*
G01X2352890Y1782490D02*
X2351905D01*
G01X2344277Y1781053D02*
X2336945D01*
G01X2356433D02*
X2344424D01*
G01X2352890Y1780640D02*
X2351905D01*
G01X2352890Y1780443D02*
X2351905D01*
G01X2344424Y1780266D02*
X2356433D01*
G01X2336945D02*
X2344277D01*
G01X2352890Y1780049D02*
X2351905D01*
G01X2347772Y1779852D02*
X2354937D01*
G01X2347772Y1778277D02*
X2354937D01*
G01X2352890Y1778081D02*
X2351905D01*
G01X2344277Y1777903D02*
X2336945D01*
G01X2356433D02*
X2344424D01*
G01X2352890Y1777687D02*
X2351905D01*
G01X2352890Y1777490D02*
X2351905D01*
G01X2344424Y1777116D02*
X2356433D01*
G01X2336945D02*
X2344277D01*
G01X2352890Y1775640D02*
X2351905D01*
G01X2352890Y1775443D02*
X2351905D01*
G01X2352890Y1775049D02*
X2351905D01*
G01X2347772Y1774852D02*
X2354937D01*
G01X2344277Y1774754D02*
X2336945D01*
G01X2356433D02*
X2344424D01*
G01Y1773966D02*
X2356433D01*
G01X2336945D02*
X2344277D01*
G01X2347772Y1773277D02*
X2354937D01*
G01X2352890Y1773081D02*
X2351905D01*
G01X2352890Y1772687D02*
X2351905D01*
G01X2352890Y1772490D02*
X2351905D01*
G01X2344277Y1771604D02*
X2336945D01*
G01X2356433D02*
X2344424D01*
G01Y1770817D02*
X2356433D01*
G01X2336945D02*
X2344277D01*
G01X2352890Y1770640D02*
X2351905D01*
G01X2352890Y1770443D02*
X2351905D01*
G01X2352890Y1770049D02*
X2351905D01*
G01X2347772Y1769852D02*
X2354937D01*
G01X2344277Y1768455D02*
X2336945D01*
G01X2356433D02*
X2344424D01*
G01X2347772Y1768277D02*
X2354937D01*
G01X2352890Y1768081D02*
X2351905D01*
G01X2352890Y1767687D02*
X2351905D01*
G01X2344424Y1767667D02*
X2356433D01*
G01X2336945D02*
X2344277D01*
G01X2352890Y1767490D02*
X2351905D01*
G01X2385173Y1767372D02*
X2358480D01*
G01X2355331Y1766270D02*
X2356433D01*
G01X2354858Y1765640D02*
X2353874D01*
G01X2354858Y1765443D02*
X2353874D01*
G01X2344277Y1765305D02*
X2336945D01*
G01X2356433D02*
X2344424D01*
G01X2354858Y1765049D02*
X2353874D01*
G01X2385173Y1765010D02*
X2358480D01*
G01X2355331Y1764852D02*
X2349740D01*
G01X2344424Y1764518D02*
X2356433D01*
G01X2336945D02*
X2344277D01*
G01X2355331Y1763277D02*
X2349740D01*
G01X2354858Y1763081D02*
X2353874D01*
G01X2354858Y1762687D02*
X2353874D01*
G01X2354858Y1762490D02*
X2353874D01*
G01X2344277Y1762155D02*
X2336945D01*
G01X2356433D02*
X2344424D01*
G01X2356433Y1761860D02*
X2355331D01*
G01X2344424Y1761368D02*
X2356433D01*
G01X2336945D02*
X2344277D01*
G01X2352890Y1760640D02*
X2351905D01*
G01X2352890Y1760443D02*
X2351905D01*
G01X2352890Y1760049D02*
X2351905D01*
G01X2347772Y1759852D02*
X2354937D01*
G01X2344277Y1759006D02*
X2336945D01*
G01X2356433D02*
X2344424D01*
G01X2347772Y1758277D02*
X2354937D01*
G01X2344424Y1758218D02*
X2356433D01*
G01X2336945D02*
X2344277D01*
G01X2352890Y1758081D02*
X2351905D01*
G01X2352890Y1757687D02*
X2351905D01*
G01X2352890Y1757490D02*
X2351905D01*
G01X2344277Y1755856D02*
X2336945D01*
G01X2356433D02*
X2344424D01*
G01X2352890Y1755640D02*
X2351905D01*
G01X2352890Y1755443D02*
X2351905D01*
G01X2344424Y1755069D02*
X2356433D01*
G01X2336945D02*
X2344277D01*
G01X2352890Y1755049D02*
X2351905D01*
G01X2347772Y1754852D02*
X2354937D01*
G01X2347772Y1753277D02*
X2354937D01*
G01X2352890Y1753081D02*
X2351905D01*
G01X2386130Y1752766D02*
X2366669D01*
G01X2344277Y1752707D02*
X2336945D01*
G01X2356433D02*
X2344424D01*
G01X2352890Y1752687D02*
X2351905D01*
G01X2352890Y1752490D02*
X2351905D01*
G01X2344424Y1751919D02*
X2356433D01*
G01X2336945D02*
X2344277D01*
G01X2352890Y1750640D02*
X2351905D01*
G01X2352890Y1750443D02*
X2351905D01*
G01X2352890Y1750049D02*
X2351905D01*
G01X2347772Y1749852D02*
X2354937D01*
G01X2344277Y1749557D02*
X2336945D01*
G01X2356433D02*
X2344424D01*
G01Y1748770D02*
X2356433D01*
G01X2336945D02*
X2344277D01*
G01X2385173Y1748671D02*
X2358480D01*
G01X2347772Y1748277D02*
X2354937D01*
G01X2352890Y1748081D02*
X2351905D01*
G01X2352890Y1747687D02*
X2351905D01*
G01X2352890Y1747490D02*
X2351905D01*
G01X2344277Y1746407D02*
X2336945D01*
G01X2356433D02*
X2344424D01*
G01X2366669Y1746329D02*
X2385173D01*
G01X2356433D02*
X2355331D01*
G01X2380673Y1746309D02*
X2358480D01*
G01X2356433Y1746211D02*
X2348898D01*
G01X2353439Y1745718D02*
X2351315D01*
G01X2344424Y1745620D02*
X2356433D01*
G01X2336945D02*
X2344277D01*
G01X2354424Y1745423D02*
X2353439D01*
G01X2354424Y1745226D02*
X2353439D01*
G01X2355331Y1745029D02*
X2349305D01*
G01X2355331Y1743848D02*
X2349305D01*
G01X2354424Y1743651D02*
X2353439D01*
G01X2354424Y1743455D02*
X2353439D01*
G01X2344277Y1743258D02*
X2336945D01*
G01X2356433D02*
X2344424D01*
G01Y1742470D02*
X2356433D01*
G01X2336945D02*
X2344277D01*
G01X2349324Y1742392D02*
X2347441D01*
G01X2354424Y1742274D02*
X2353439D01*
G01X2354424Y1742077D02*
X2353439D01*
G01X2355331Y1741880D02*
X2349305D01*
G01X2355331Y1740699D02*
X2349305D01*
G01X2354424Y1740502D02*
X2353439D01*
G01X2354424Y1740305D02*
X2353439D01*
G01X2347441Y1740187D02*
X2349324D01*
G01X2344277Y1740108D02*
X2336945D01*
G01X2356433D02*
X2344424D01*
G01Y1739321D02*
X2356433D01*
G01X2336945D02*
X2344277D01*
G01X2354424Y1739124D02*
X2353439D01*
G01X2354424Y1738927D02*
X2353439D01*
G01X2355331Y1738730D02*
X2349305D01*
G01X2355331Y1737549D02*
X2349305D01*
G01X2354424Y1737352D02*
X2353439D01*
G01X2354424Y1737155D02*
X2353439D01*
G01X2344277Y1736959D02*
X2336945D01*
G01X2356433D02*
X2344424D01*
G01Y1736171D02*
X2356433D01*
G01X2336945D02*
X2344277D01*
G01X2354424Y1735974D02*
X2353439D01*
G01X2354424Y1735777D02*
X2353439D01*
G01X2355331Y1735581D02*
X2349305D01*
G01X2355331Y1734400D02*
X2349305D01*
G01X2354424Y1734203D02*
X2353439D01*
G01X2354424Y1734006D02*
X2353439D01*
G01X2344277Y1733809D02*
X2336945D01*
G01X2356433D02*
X2344424D01*
G01Y1733022D02*
X2356433D01*
G01X2336945D02*
X2344277D01*
G01X2349324Y1732943D02*
X2347441D01*
G01X2354424Y1732825D02*
X2353439D01*
G01X2354424Y1732628D02*
X2353439D01*
G01X2355331Y1732431D02*
X2349305D01*
G01X2355331Y1731250D02*
X2349305D01*
G01X2354424Y1731053D02*
X2353439D01*
G01X2354424Y1730856D02*
X2353439D01*
G01X2347441Y1730738D02*
X2349324D01*
G01X2344277Y1730659D02*
X2336945D01*
G01X2356433D02*
X2344424D01*
G01Y1729872D02*
X2356433D01*
G01X2336945D02*
X2344277D01*
G01X2354424Y1729675D02*
X2353439D01*
G01X2354424Y1729478D02*
X2353439D01*
G01X2355331Y1729281D02*
X2349305D01*
G01X2355331Y1728100D02*
X2349305D01*
G01X2354424Y1727903D02*
X2353439D01*
G01X2354424Y1727707D02*
X2353439D01*
G01X2344277Y1727510D02*
X2336945D01*
G01X2356433D02*
X2344424D01*
G01X2353439Y1727411D02*
X2351315D01*
G01X2348898Y1726919D02*
X2356433D01*
G01X2380673Y1726821D02*
X2358480D01*
G01X2356433Y1726801D02*
X2355331D01*
G01X2385173D02*
X2366669D01*
G01X2344424Y1726722D02*
X2356433D01*
G01X2336945D02*
X2344277D01*
G01X2352890Y1725640D02*
X2351905D01*
G01X2352890Y1725443D02*
X2351905D01*
G01X2352890Y1725049D02*
X2351905D01*
G01X2347772Y1724852D02*
X2354937D01*
G01X2385173Y1724459D02*
X2358480D01*
G01X2344277Y1724360D02*
X2336945D01*
G01X2356433D02*
X2344424D01*
G01X2360449Y1786270D02*
Y1802805D01*
G01Y1767372D02*
Y1783907D01*
G01Y1748671D02*
Y1765010D01*
G01Y1746309D02*
Y1726821D01*
G01X2355252Y1746211D02*
Y1726919D01*
G01X2354937D02*
Y1746211D01*
G01X2354858Y1765640D02*
Y1762490D01*
G01X2354491Y1792864D02*
Y1793651D01*
G01Y1786565D02*
Y1787352D01*
G01Y1789714D02*
Y1790502D01*
G01Y1783415D02*
Y1784203D01*
G01Y1777116D02*
Y1777903D01*
G01Y1780266D02*
Y1781053D01*
G01Y1773966D02*
Y1774754D01*
G01Y1767667D02*
Y1768455D01*
G01Y1770817D02*
Y1771604D01*
G01Y1764518D02*
Y1765305D01*
G01Y1758218D02*
Y1759006D01*
G01Y1761368D02*
Y1762155D01*
G01Y1755069D02*
Y1755856D01*
G01Y1748770D02*
Y1749557D01*
G01Y1751919D02*
Y1752707D01*
G01Y1745620D02*
Y1746407D01*
G01Y1742470D02*
Y1743258D01*
G01Y1736171D02*
Y1736959D01*
G01Y1739321D02*
Y1740108D01*
G01Y1733022D02*
Y1733809D01*
G01Y1726722D02*
Y1727510D01*
G01Y1729872D02*
Y1730659D01*
G01X2354464Y1792864D02*
Y1793651D01*
G01Y1786565D02*
Y1787352D01*
G01Y1789714D02*
Y1790502D01*
G01Y1783415D02*
Y1784203D01*
G01Y1777116D02*
Y1777903D01*
G01Y1780266D02*
Y1781053D01*
G01Y1773966D02*
Y1774754D01*
G01Y1767667D02*
Y1768455D01*
G01Y1770817D02*
Y1771604D01*
G01Y1764518D02*
Y1765305D01*
G01Y1758218D02*
Y1759006D01*
G01Y1761368D02*
Y1762155D01*
G01Y1755069D02*
Y1755856D01*
G01Y1748770D02*
Y1749557D01*
G01Y1751919D02*
Y1752707D01*
G01Y1745620D02*
Y1746407D01*
G01Y1742470D02*
Y1743258D01*
G01Y1736171D02*
Y1736959D01*
G01Y1739321D02*
Y1740108D01*
G01Y1733022D02*
Y1733809D01*
G01Y1726722D02*
Y1727510D01*
G01Y1729872D02*
Y1730659D01*
G01X2354424Y1729872D02*
Y1727510D01*
G01Y1733022D02*
Y1730659D01*
G01Y1736171D02*
Y1733809D01*
G01Y1739321D02*
Y1736959D01*
G01Y1742470D02*
Y1740108D01*
G01Y1745620D02*
Y1743258D01*
G01X2354149Y1746211D02*
Y1726919D01*
G01X2354088Y1792864D02*
Y1793651D01*
G01Y1786565D02*
Y1787352D01*
G01Y1789714D02*
Y1790502D01*
G01Y1783415D02*
Y1784203D01*
G01Y1777116D02*
Y1777903D01*
G01Y1780266D02*
Y1781053D01*
G01Y1773966D02*
Y1774754D01*
G01Y1767667D02*
Y1768455D01*
G01Y1770817D02*
Y1771604D01*
G01Y1764518D02*
Y1765305D01*
G01Y1758218D02*
Y1759006D01*
G01Y1761368D02*
Y1762155D01*
G01Y1755069D02*
Y1755856D01*
G01Y1748770D02*
Y1749557D01*
G01Y1751919D02*
Y1752707D01*
G01Y1745620D02*
Y1746407D01*
G01Y1742470D02*
Y1743258D01*
G01Y1736171D02*
Y1736959D01*
G01Y1739321D02*
Y1740108D01*
G01Y1733022D02*
Y1733809D01*
G01Y1726722D02*
Y1727510D01*
G01Y1729872D02*
Y1730659D01*
G01X2353874Y1749852D02*
Y1748277D01*
G01Y1754852D02*
Y1753277D01*
G01Y1759852D02*
Y1758277D01*
G01Y1765640D02*
Y1762490D01*
G01Y1769852D02*
Y1768277D01*
G01Y1774852D02*
Y1773277D01*
G01Y1779852D02*
Y1778277D01*
G01Y1784852D02*
Y1783277D01*
G01Y1789852D02*
Y1788277D01*
G01Y1794852D02*
Y1793277D01*
G01X2353649Y1746211D02*
Y1726919D01*
G01X2353439Y1727411D02*
Y1745718D01*
G01X2352890Y1750640D02*
Y1747490D01*
G01Y1755640D02*
Y1752490D01*
G01Y1760640D02*
Y1757490D01*
G01Y1764852D02*
Y1763277D01*
G01Y1770640D02*
Y1767490D01*
G01Y1775640D02*
Y1772490D01*
G01Y1780640D02*
Y1777490D01*
G01Y1785640D02*
Y1782490D01*
G01Y1790640D02*
Y1787490D01*
G01Y1795640D02*
Y1792490D01*
G01X2352732Y1726919D02*
Y1746211D01*
G01X2352455Y1729281D02*
Y1728100D01*
G01Y1732431D02*
Y1731250D01*
G01Y1735581D02*
Y1734400D01*
G01Y1738730D02*
Y1737549D01*
G01Y1741880D02*
Y1740699D01*
G01Y1745029D02*
Y1743848D01*
G01X2351905Y1750640D02*
Y1747490D01*
G01Y1755640D02*
Y1752490D01*
G01Y1760640D02*
Y1757490D01*
G01Y1770640D02*
Y1767490D01*
G01Y1775640D02*
Y1772490D01*
G01Y1780640D02*
Y1777490D01*
G01Y1785640D02*
Y1782490D01*
G01Y1790640D02*
Y1787490D01*
G01Y1795640D02*
Y1792490D01*
G01X2350921Y1749852D02*
Y1748277D01*
G01Y1754852D02*
Y1753277D01*
G01Y1759852D02*
Y1758277D01*
G01Y1769852D02*
Y1768277D01*
G01Y1774852D02*
Y1773277D01*
G01Y1779852D02*
Y1778277D01*
G01Y1784852D02*
Y1783277D01*
G01Y1789852D02*
Y1788277D01*
G01Y1794852D02*
Y1793277D01*
G01X2350726Y1727510D02*
Y1726722D01*
G01Y1730659D02*
Y1729872D01*
G01Y1733809D02*
Y1733022D01*
G01Y1736959D02*
Y1736171D01*
G01Y1740108D02*
Y1739321D01*
G01Y1743258D02*
Y1742470D01*
G01Y1746407D02*
Y1745620D01*
G01Y1749557D02*
Y1748770D01*
G01Y1752707D02*
Y1751919D01*
G01Y1755856D02*
Y1755069D01*
G01Y1759006D02*
Y1758218D01*
G01Y1762155D02*
Y1761368D01*
G01Y1765305D02*
Y1764518D01*
G01Y1768455D02*
Y1767667D01*
G01Y1771604D02*
Y1770817D01*
G01Y1774754D02*
Y1773966D01*
G01Y1777903D02*
Y1777116D01*
G01Y1781053D02*
Y1780266D01*
G01Y1784203D02*
Y1783415D01*
G01Y1787352D02*
Y1786565D01*
G01Y1790502D02*
Y1789714D01*
G01Y1793651D02*
Y1792864D01*
G01X2349740Y1764852D02*
Y1763277D01*
G01X2349376Y1726919D02*
Y1746211D01*
G01X2349324Y1732943D02*
Y1730738D01*
G01Y1742392D02*
Y1740187D01*
G01X2349305Y1729281D02*
Y1728100D01*
G01Y1732431D02*
Y1731250D01*
G01Y1735581D02*
Y1734400D01*
G01Y1738730D02*
Y1737549D01*
G01Y1741880D02*
Y1740699D01*
G01Y1745029D02*
Y1743848D01*
G01X2348898Y1742392D02*
Y1746211D01*
G01Y1732943D02*
Y1740187D01*
G01Y1726919D02*
Y1730738D01*
G01X2348743Y1727510D02*
Y1726722D01*
G01Y1730659D02*
Y1729872D01*
G01Y1733809D02*
Y1733022D01*
G01Y1736959D02*
Y1736171D01*
G01Y1740108D02*
Y1739321D01*
G01Y1743258D02*
Y1742470D01*
G01Y1746407D02*
Y1745620D01*
G01Y1749557D02*
Y1748770D01*
G01Y1752707D02*
Y1751919D01*
G01Y1755856D02*
Y1755069D01*
G01Y1759006D02*
Y1758218D01*
G01Y1762155D02*
Y1761368D01*
G01Y1765305D02*
Y1764518D01*
G01Y1768455D02*
Y1767667D01*
G01Y1771604D02*
Y1770817D01*
G01Y1774754D02*
Y1773966D01*
G01Y1777903D02*
Y1777116D01*
G01Y1781053D02*
Y1780266D01*
G01Y1784203D02*
Y1783415D01*
G01Y1787352D02*
Y1786565D01*
G01Y1790502D02*
Y1789714D01*
G01Y1793651D02*
Y1792864D01*
G01X2347772Y1749852D02*
Y1748277D01*
G01Y1754852D02*
Y1753277D01*
G01Y1759852D02*
Y1758277D01*
G01Y1769852D02*
Y1768277D01*
G01Y1774852D02*
Y1773277D01*
G01Y1779852D02*
Y1778277D01*
G01Y1784852D02*
Y1783277D01*
G01Y1789852D02*
Y1788277D01*
G01Y1794852D02*
Y1793277D01*
G01X2347441Y1740187D02*
Y1742392D01*
G01Y1730738D02*
Y1732943D01*
G01X2347091Y1792864D02*
Y1793651D01*
G01Y1786565D02*
Y1787352D01*
G01Y1789714D02*
Y1790502D01*
G01Y1783415D02*
Y1784203D01*
G01Y1777116D02*
Y1777903D01*
G01Y1780266D02*
Y1781053D01*
G01Y1773966D02*
Y1774754D01*
G01Y1767667D02*
Y1768455D01*
G01Y1770817D02*
Y1771604D01*
G01Y1764518D02*
Y1765305D01*
G01Y1758218D02*
Y1759006D01*
G01Y1761368D02*
Y1762155D01*
G01Y1755069D02*
Y1755856D01*
G01Y1748770D02*
Y1749557D01*
G01Y1751919D02*
Y1752707D01*
G01Y1745620D02*
Y1746407D01*
G01Y1742470D02*
Y1743258D01*
G01Y1736171D02*
Y1736959D01*
G01Y1739321D02*
Y1740108D01*
G01Y1733022D02*
Y1733809D01*
G01Y1726722D02*
Y1727510D01*
G01Y1729872D02*
Y1730659D01*
G01X2345363Y1726722D02*
Y1724360D01*
G01Y1729872D02*
Y1727510D01*
G01Y1733022D02*
Y1730659D01*
G01Y1736171D02*
Y1733809D01*
G01Y1739321D02*
Y1736959D01*
G01Y1742470D02*
Y1740108D01*
G01Y1745620D02*
Y1743258D01*
G01Y1748770D02*
Y1746407D01*
G01Y1751919D02*
Y1749557D01*
G01Y1755069D02*
Y1752707D01*
G01Y1758218D02*
Y1755856D01*
G01Y1761368D02*
Y1759006D01*
G01Y1764518D02*
Y1762155D01*
G01Y1767667D02*
Y1765305D01*
G01Y1770817D02*
Y1768455D01*
G01Y1773966D02*
Y1771604D01*
G01Y1777116D02*
Y1774754D01*
G01Y1780266D02*
Y1777903D01*
G01Y1783415D02*
Y1781053D01*
G01Y1786565D02*
Y1784203D01*
G01Y1789714D02*
Y1787352D01*
G01Y1792864D02*
Y1790502D01*
G01Y1796014D02*
Y1793651D01*
G01X2344424Y1792864D02*
Y1793651D01*
G01Y1786565D02*
Y1787352D01*
G01Y1789714D02*
Y1790502D01*
G01Y1783415D02*
Y1784203D01*
G01Y1777116D02*
Y1777903D01*
G01Y1780266D02*
Y1781053D01*
G01Y1773966D02*
Y1774754D01*
G01Y1767667D02*
Y1768455D01*
G01Y1770817D02*
Y1771604D01*
G01Y1764518D02*
Y1765305D01*
G01Y1758218D02*
Y1759006D01*
G01Y1761368D02*
Y1762155D01*
G01Y1755069D02*
Y1755856D01*
G01Y1748770D02*
Y1749557D01*
G01Y1751919D02*
Y1752707D01*
G01Y1745620D02*
Y1746407D01*
G01Y1742470D02*
Y1743258D01*
G01Y1736171D02*
Y1736959D01*
G01Y1739321D02*
Y1740108D01*
G01Y1733022D02*
Y1733809D01*
G01Y1726722D02*
Y1727510D01*
G01Y1729872D02*
Y1730659D01*
G01X2344277Y1792864D02*
Y1793651D01*
G01Y1786565D02*
Y1787352D01*
G01Y1789714D02*
Y1790502D01*
G01Y1783415D02*
Y1784203D01*
G01Y1777116D02*
Y1777903D01*
G01Y1780266D02*
Y1781053D01*
G01Y1773966D02*
Y1774754D01*
G01Y1767667D02*
Y1768455D01*
G01Y1770817D02*
Y1771604D01*
G01Y1764518D02*
Y1765305D01*
G01Y1758218D02*
Y1759006D01*
G01Y1761368D02*
Y1762155D01*
G01Y1755069D02*
Y1755856D01*
G01Y1748770D02*
Y1749557D01*
G01Y1751919D02*
Y1752707D01*
G01Y1745620D02*
Y1746407D01*
G01Y1742470D02*
Y1743258D01*
G01Y1736171D02*
Y1736959D01*
G01Y1739321D02*
Y1740108D01*
G01Y1733022D02*
Y1733809D01*
G01Y1726722D02*
Y1727510D01*
G01Y1729872D02*
Y1730659D01*
G01X2342685Y1792864D02*
Y1793651D01*
G01Y1786565D02*
Y1787352D01*
G01Y1789714D02*
Y1790502D01*
G01Y1783415D02*
Y1784203D01*
G01Y1777116D02*
Y1777903D01*
G01Y1780266D02*
Y1781053D01*
G01Y1773966D02*
Y1774754D01*
G01Y1767667D02*
Y1768455D01*
G01Y1770817D02*
Y1771604D01*
G01Y1764518D02*
Y1765305D01*
G01Y1758218D02*
Y1759006D01*
G01Y1761368D02*
Y1762155D01*
G01Y1755069D02*
Y1755856D01*
G01Y1748770D02*
Y1749557D01*
G01Y1751919D02*
Y1752707D01*
G01Y1745620D02*
Y1746407D01*
G01Y1742470D02*
Y1743258D01*
G01Y1736171D02*
Y1736959D01*
G01Y1739321D02*
Y1740108D01*
G01Y1733022D02*
Y1733809D01*
G01Y1726722D02*
Y1727510D01*
G01Y1729872D02*
Y1730659D01*
G01X2341743Y1727510D02*
Y1726722D01*
G01Y1730659D02*
Y1729872D01*
G01Y1733809D02*
Y1733022D01*
G01Y1736959D02*
Y1736171D01*
G01Y1740108D02*
Y1739321D01*
G01Y1743258D02*
Y1742470D01*
G01Y1746407D02*
Y1745620D01*
G01Y1749557D02*
Y1748770D01*
G01Y1752707D02*
Y1751919D01*
G01Y1755856D02*
Y1755069D01*
G01Y1759006D02*
Y1758218D01*
G01Y1762155D02*
Y1761368D01*
G01Y1765305D02*
Y1764518D01*
G01Y1768455D02*
Y1767667D01*
G01Y1771604D02*
Y1770817D01*
G01Y1774754D02*
Y1773966D01*
G01Y1777903D02*
Y1777116D01*
G01Y1781053D02*
Y1780266D01*
G01Y1784203D02*
Y1783415D01*
G01Y1787352D02*
Y1786565D01*
G01Y1790502D02*
Y1789714D01*
G01Y1793651D02*
Y1792864D01*
G01X2338907Y1727510D02*
Y1726722D01*
G01Y1730659D02*
Y1729872D01*
G01Y1733809D02*
Y1733022D01*
G01Y1736959D02*
Y1736171D01*
G01Y1740108D02*
Y1739321D01*
G01Y1743258D02*
Y1742470D01*
G01Y1746407D02*
Y1745620D01*
G01Y1749557D02*
Y1748770D01*
G01Y1752707D02*
Y1751919D01*
G01Y1755856D02*
Y1755069D01*
G01Y1759006D02*
Y1758218D01*
G01Y1762155D02*
Y1761368D01*
G01Y1765305D02*
Y1764518D01*
G01Y1768455D02*
Y1767667D01*
G01Y1771604D02*
Y1770817D01*
G01Y1774754D02*
Y1773966D01*
G01Y1777903D02*
Y1777116D01*
G01Y1781053D02*
Y1780266D01*
G01Y1784203D02*
Y1783415D01*
G01Y1787352D02*
Y1786565D01*
G01Y1790502D02*
Y1789714D01*
G01Y1793651D02*
Y1792864D01*
G01X2338718D02*
Y1793651D01*
G01Y1786565D02*
Y1787352D01*
G01Y1789714D02*
Y1790502D01*
G01Y1783415D02*
Y1784203D01*
G01Y1777116D02*
Y1777903D01*
G01Y1780266D02*
Y1781053D01*
G01Y1773966D02*
Y1774754D01*
G01Y1767667D02*
Y1768455D01*
G01Y1770817D02*
Y1771604D01*
G01Y1764518D02*
Y1765305D01*
G01Y1758218D02*
Y1759006D01*
G01Y1761368D02*
Y1762155D01*
G01Y1755069D02*
Y1755856D01*
G01Y1748770D02*
Y1749557D01*
G01Y1751919D02*
Y1752707D01*
G01Y1745620D02*
Y1746407D01*
G01Y1742470D02*
Y1743258D01*
G01Y1736171D02*
Y1736959D01*
G01Y1739321D02*
Y1740108D01*
G01Y1733022D02*
Y1733809D01*
G01Y1726722D02*
Y1727510D01*
G01Y1729872D02*
Y1730659D01*
G01X2336945Y1792864D02*
Y1793651D01*
G01Y1786565D02*
Y1787352D01*
G01Y1789714D02*
Y1790502D01*
G01Y1783415D02*
Y1784203D01*
G01Y1777116D02*
Y1777903D01*
G01Y1780266D02*
Y1781053D01*
G01Y1773966D02*
Y1774754D01*
G01Y1767667D02*
Y1768455D01*
G01Y1770817D02*
Y1771604D01*
G01Y1764518D02*
Y1765305D01*
G01Y1758218D02*
Y1759006D01*
G01Y1761368D02*
Y1762155D01*
G01Y1755069D02*
Y1755856D01*
G01Y1748770D02*
Y1749557D01*
G01Y1751919D02*
Y1752707D01*
G01Y1745620D02*
Y1746407D01*
G01Y1742470D02*
Y1743258D01*
G01Y1736171D02*
Y1736959D01*
G01Y1739321D02*
Y1740108D01*
G01Y1733022D02*
Y1733809D01*
G01Y1726722D02*
Y1727510D01*
G01Y1729872D02*
Y1730659D01*
G01X2354937Y1794852D02*
G03X2355331Y1795246I0J394D01*
G01X2344277Y1796801D02*
X2336945D01*
G01X2356433D02*
X2344424D01*
G01Y1796014D02*
X2356433D01*
G01X2336945D02*
X2344277D01*
G01X2352890Y1795640D02*
X2351905D01*
G01X2352890Y1795443D02*
X2351905D01*
G01X2352890Y1795049D02*
X2351905D01*
G01X2347772Y1794852D02*
X2354937D01*
G01X2354491Y1796014D02*
Y1796801D01*
G01X2354464Y1796014D02*
Y1796801D01*
G01X2354088Y1796014D02*
Y1796801D01*
G01X2350726D02*
Y1796014D01*
G01X2348743Y1796801D02*
Y1796014D01*
G01X2347091D02*
Y1796801D01*
G01X2345363Y1799163D02*
Y1796801D01*
G01X2344424Y1796014D02*
Y1796801D01*
G01X2344277Y1796014D02*
Y1796801D01*
G01X2342685Y1796014D02*
Y1796801D01*
G01X2341743D02*
Y1796014D01*
G01X2338907Y1796801D02*
Y1796014D01*
G01X2338718D02*
Y1796801D01*
G01X2336945Y1796014D02*
Y1796801D01*
G01X2358121Y1832225D02*
G03X2359551I715J0D01*
G01X2355231D02*
G03X2356661I715J0D01*
G01X2358992Y1841604D02*
G03Y1844754I0J1575D01*
G01X2354132Y1831150D02*
G03X2356768Y1831294I1248J1351D01*
G01D02*
G03X2359549Y1831300I1388J1207D01*
G01X2354937Y1819852D02*
G03X2355331Y1820246I0J394D01*
G01Y1817884D02*
G03X2354937Y1818277I-394J-1D01*
G01Y1809852D02*
G03X2355331Y1810246I0J394D01*
G01Y1807884D02*
G03X2354937Y1808277I-394J-1D01*
G01Y1814852D02*
G03X2355331Y1815246I0J394D01*
G01Y1812884D02*
G03X2354937Y1813277I-394J-1D01*
G01X2351632Y1833641D02*
G03X2350159I-736J-278D01*
G01Y1831956D02*
G03X2351632I737J278D01*
G01X2353838Y1831821D02*
G03X2354132Y1831149I914J-1D01*
G01X2352904Y1833976D02*
G03X2352383Y1834541I-1351J-723D01*
G01X2352384Y1831097D02*
G03X2352905Y1831662I-830J1288D01*
G01X2354661Y1844754D02*
G03Y1841604I0J-1575D01*
G01X2350159Y1833641D02*
G03Y1831956I2236J-842D01*
G01X2352905Y1831662D02*
G03X2352904Y1833976I-2163J1156D01*
G01X2348816Y1833974D02*
G03X2348817Y1831662I2163J-1155D01*
G01X2352383Y1834541D02*
G03X2349337Y1834539I-1521J-2363D01*
G01X2349338Y1831096D02*
G03X2352384Y1831097I1522J2362D01*
G01X2354937Y1799852D02*
G03X2355331Y1800246I0J394D01*
G01Y1797884D02*
G03X2354937Y1798277I-394J-1D01*
G01X2349337Y1834539D02*
G03X2348816Y1833974I830J-1288D01*
G01X2348817Y1831662D02*
G03X2349338Y1831096I1352J722D01*
G01X2351632Y1831956D02*
G03Y1833641I-2237J842D01*
G01X2349740Y1831368D02*
G03I-2165J0D01*
G01X2345620Y1834085D02*
G03Y1828651I1954J-2717D01*
G01X2349529D02*
G03Y1834085I-1954J2717D01*
G01X2351079Y1831368D02*
G03I-3504J0D01*
G01X2349878Y1827470D02*
G03Y1835266I-2303J3898D01*
G01X2345271D02*
G03Y1827470I2304J-3898D01*
G01X2343658Y1833959D02*
G03X2343068Y1833594I-8J-646D01*
G01X2344432Y1833151D02*
G03X2343658Y1833959I-792J16D01*
G01X2342407Y1834663D02*
G03X2341564Y1833594I704J-1422D01*
G01X2341772Y1831708D02*
G03X2343007Y1830734I1735J930D01*
G01X2344649Y1830778D02*
G03X2345814Y1831916I-728J1911D01*
G01X2345727Y1833932D02*
G03X2343989Y1834950I-1807J-1093D01*
G01X2343007Y1830734D02*
G03X2344649Y1830778I755J2476D01*
G01X2345988Y1833072D02*
G03X2345726Y1833935I-2971J-431D01*
G01X2341433Y1833150D02*
G03X2341772Y1831708I3015J-52D01*
G01X2345988Y1832577D02*
G03Y1833074I-3524J249D01*
G01X2345814Y1831916D02*
G03X2345988Y1832577I-4018J1411D01*
G01X2343007Y1832325D02*
G03X2344432I712J-83D01*
G01X2343992Y1834949D02*
G03X2342407Y1834663I-264J-3073D01*
G01X2339965Y1832603D02*
X2341233Y1830743D01*
G01X2338463Y1834750D02*
X2339208Y1833472D01*
G01X2336914Y1834750D02*
X2338235Y1832594D01*
G01X2339011Y1831729D02*
X2339617Y1830743D01*
G01X2365016Y1849085D02*
X2348638D01*
G01X2354661Y1844754D02*
X2358992D01*
G01X2354036Y1843966D02*
X2359617D01*
G01Y1842392D02*
X2354036D01*
G01X2358992Y1841604D02*
X2354661D01*
G01X2365016Y1838907D02*
X2348638D01*
G01X2335173Y1836151D02*
X2389110D01*
G01X2349878Y1835266D02*
X2345271D01*
G01X2389110Y1834970D02*
X2362732D01*
G01X2338463Y1834750D02*
X2336914D01*
G01X2341407D02*
X2339999D01*
G01X2348039D02*
X2346579D01*
G01X2355231D02*
X2353838D01*
G01X2358121D02*
X2356661D01*
G01X2360992D02*
X2359551D01*
G01X2358795Y1834183D02*
X2335173D01*
G01X2345620Y1834085D02*
X2349529D01*
G01X2343067Y1833594D02*
X2341564D01*
G01X2344433Y1833150D02*
X2341433D01*
G01X2344432Y1832325D02*
X2343007D01*
G01X2338322Y1830743D02*
X2336940D01*
G01X2341233D02*
X2339617D01*
G01X2360992D02*
X2359549D01*
G01X2358795Y1830403D02*
X2335173D01*
G01X2348039Y1828996D02*
X2346579D01*
G01X2349529Y1828651D02*
X2345620D01*
G01X2358795Y1828435D02*
X2335173D01*
G01X2385173Y1827805D02*
X2335173D01*
G01X2345271Y1827470D02*
X2349878D01*
G01X2335173Y1826033D02*
X2358795D01*
G01X2350333Y1825502D02*
X2356433D01*
G01X2350333Y1825443D02*
X2356433D01*
G01X2335966Y1825049D02*
X2356433D01*
G01X2355331Y1823868D02*
X2364701D01*
G01X2387142Y1823277D02*
X2356433D01*
G01X2385173Y1822884D02*
X2366669D01*
G01X2365016Y1822687D02*
X2358480D01*
G01X2335173Y1822274D02*
X2355331D01*
G01Y1822096D02*
X2364701D01*
G01X2352890Y1820640D02*
X2351905D01*
G01X2351315Y1820522D02*
X2342330D01*
G01X2352890Y1820443D02*
X2351905D01*
G01X2352890Y1820049D02*
X2351905D01*
G01X2347772Y1819852D02*
X2354937D01*
G01X2344277Y1818848D02*
X2336945D01*
G01X2356433D02*
X2344424D01*
G01X2347772Y1818277D02*
X2354937D01*
G01X2352890Y1818081D02*
X2351905D01*
G01X2344424Y1818061D02*
X2356433D01*
G01X2336945D02*
X2344277D01*
G01X2352890Y1817687D02*
X2351905D01*
G01X2352890Y1817490D02*
X2351905D01*
G01X2344277Y1815699D02*
X2336945D01*
G01X2356433D02*
X2344424D01*
G01X2352890Y1815640D02*
X2351905D01*
G01X2352890Y1815443D02*
X2351905D01*
G01X2352890Y1815049D02*
X2351905D01*
G01X2344424Y1814911D02*
X2356433D01*
G01X2336945D02*
X2344277D01*
G01X2347772Y1814852D02*
X2354937D01*
G01X2347772Y1813277D02*
X2354937D01*
G01X2352890Y1813081D02*
X2351905D01*
G01X2352890Y1812687D02*
X2351905D01*
G01X2349529Y1828651D02*
X2349547Y1828596D01*
X2349599Y1828430D01*
X2349678Y1828171D01*
X2349774Y1827844D01*
X2349878Y1827470D01*
G01X2345620Y1834085D02*
X2345602Y1834140D01*
X2345550Y1834306D01*
X2345471Y1834565D01*
X2345376Y1834892D01*
X2345271Y1835266D01*
G01X2344277Y1812549D02*
X2336945D01*
G01X2356433D02*
X2344424D01*
G01X2352890Y1812490D02*
X2351905D01*
G01X2344424Y1811762D02*
X2356433D01*
G01X2336945D02*
X2344277D01*
G01X2352890Y1810640D02*
X2351905D01*
G01X2352890Y1810443D02*
X2351905D01*
G01X2352890Y1810049D02*
X2351905D01*
G01X2347772Y1809852D02*
X2354937D01*
G01X2344277Y1809400D02*
X2336945D01*
G01X2356433D02*
X2344424D01*
G01Y1808612D02*
X2356433D01*
G01X2336945D02*
X2344277D01*
G01X2347772Y1808277D02*
X2354937D01*
G01X2352890Y1808081D02*
X2351905D01*
G01X2352890Y1807687D02*
X2351905D01*
G01X2352890Y1807490D02*
X2351905D01*
G01X2356433Y1806270D02*
X2355331D01*
G01X2344277Y1806250D02*
X2336945D01*
G01X2356433D02*
X2344424D01*
G01X2354858Y1805640D02*
X2353874D01*
G01X2344424Y1805463D02*
X2356433D01*
G01X2336945D02*
X2344277D01*
G01X2354858Y1805443D02*
X2353874D01*
G01X2385173Y1805167D02*
X2358480D01*
G01X2354858Y1805049D02*
X2353874D01*
G01X2355331Y1804852D02*
X2349740D01*
G01X2355331Y1803277D02*
X2349740D01*
G01X2344277Y1803100D02*
X2336945D01*
G01X2356433D02*
X2344424D01*
G01X2354858Y1803081D02*
X2353874D01*
G01X2385173Y1802805D02*
X2358480D01*
G01X2354858Y1802687D02*
X2353874D01*
G01X2354858Y1802490D02*
X2353874D01*
G01X2344424Y1802313D02*
X2356433D01*
G01X2336945D02*
X2344277D01*
G01X2356433Y1801860D02*
X2355331D01*
G01X2352890Y1800640D02*
X2351905D01*
G01X2352890Y1800443D02*
X2351905D01*
G01X2352890Y1800049D02*
X2351905D01*
G01X2344277Y1799951D02*
X2336945D01*
G01X2356433D02*
X2344424D01*
G01X2347772Y1799852D02*
X2354937D01*
G01X2344424Y1799163D02*
X2356433D01*
G01X2336945D02*
X2344277D01*
G01X2347772Y1798277D02*
X2354937D01*
G01X2352890Y1798081D02*
X2351905D01*
G01X2352890Y1797687D02*
X2351905D01*
G01X2352890Y1797490D02*
X2351905D01*
G01X2365016Y1822687D02*
Y1849085D01*
G01X2364701Y1823868D02*
Y1822096D01*
G01X2362732Y1836151D02*
Y1827805D01*
G01X2360992Y1834750D02*
Y1830743D01*
G01X2360449Y1805167D02*
Y1822687D01*
G01X2359617Y1842392D02*
Y1843966D01*
G01X2359583D02*
Y1842392D01*
G01X2359558Y1843966D02*
Y1842392D01*
G01X2359551Y1832225D02*
Y1834750D01*
G01X2359549Y1831300D02*
Y1830743D01*
G01X2358795Y1828435D02*
Y1826033D01*
G01Y1834183D02*
Y1830403D01*
G01X2358235Y1842392D02*
Y1843966D01*
G01X2358121Y1834750D02*
Y1832225D01*
G01X2357865Y1843966D02*
Y1842392D01*
G01X2356661Y1832225D02*
Y1834750D01*
G01X2355788Y1842392D02*
Y1843966D01*
G01X2355418D02*
Y1842392D01*
G01X2355231Y1834750D02*
Y1832225D01*
G01X2354858Y1805640D02*
Y1802490D01*
G01X2354491Y1814911D02*
Y1815699D01*
G01Y1818061D02*
Y1818848D01*
G01Y1811762D02*
Y1812549D01*
G01Y1805463D02*
Y1806250D01*
G01Y1808612D02*
Y1809400D01*
G01Y1802313D02*
Y1803100D01*
G01Y1799163D02*
Y1799951D01*
G01X2354464Y1814911D02*
Y1815699D01*
G01Y1818061D02*
Y1818848D01*
G01Y1811762D02*
Y1812549D01*
G01Y1805463D02*
Y1806250D01*
G01Y1808612D02*
Y1809400D01*
G01Y1802313D02*
Y1803100D01*
G01Y1799163D02*
Y1799951D01*
G01X2354095Y1842392D02*
Y1843966D01*
G01X2354088Y1814911D02*
Y1815699D01*
G01Y1818061D02*
Y1818848D01*
G01Y1811762D02*
Y1812549D01*
G01Y1805463D02*
Y1806250D01*
G01Y1808612D02*
Y1809400D01*
G01Y1802313D02*
Y1803100D01*
G01Y1799163D02*
Y1799951D01*
G01X2354071Y1842392D02*
Y1843966D01*
G01X2354036D02*
Y1842392D01*
G01X2353874Y1799852D02*
Y1798277D01*
G01Y1805640D02*
Y1802490D01*
G01Y1809852D02*
Y1808277D01*
G01Y1814852D02*
Y1813277D01*
G01Y1819852D02*
Y1818277D01*
G01X2353838Y1834750D02*
Y1831821D01*
G01X2352890Y1800640D02*
Y1797490D01*
G01Y1804852D02*
Y1803277D01*
G01Y1810640D02*
Y1807490D01*
G01Y1815640D02*
Y1812490D01*
G01Y1820640D02*
Y1817490D01*
G01Y1827805D02*
Y1825502D01*
G01X2351905Y1800640D02*
Y1797490D01*
G01Y1810640D02*
Y1807490D01*
G01Y1815640D02*
Y1812490D01*
G01Y1820640D02*
Y1817490D01*
G01X2350921Y1799852D02*
Y1798277D01*
G01Y1809852D02*
Y1808277D01*
G01Y1814852D02*
Y1813277D01*
G01Y1819852D02*
Y1818277D01*
G01X2350726Y1799951D02*
Y1799163D01*
G01Y1803100D02*
Y1802313D01*
G01Y1806250D02*
Y1805463D01*
G01Y1809400D02*
Y1808612D01*
G01Y1812549D02*
Y1811762D01*
G01Y1815699D02*
Y1814911D01*
G01Y1818848D02*
Y1818061D01*
G01X2350333Y1825502D02*
Y1825443D01*
G01X2349740Y1804852D02*
Y1803277D01*
G01X2349694Y1825049D02*
Y1827805D01*
G01X2348743Y1799951D02*
Y1799163D01*
G01Y1803100D02*
Y1802313D01*
G01Y1806250D02*
Y1805463D01*
G01Y1809400D02*
Y1808612D01*
G01Y1812549D02*
Y1811762D01*
G01Y1815699D02*
Y1814911D01*
G01Y1818848D02*
Y1818061D01*
G01X2348638Y1849085D02*
Y1836151D01*
G01X2348039Y1834750D02*
Y1828996D01*
G01X2347772Y1799852D02*
Y1798277D01*
G01Y1809852D02*
Y1808277D01*
G01Y1814852D02*
Y1813277D01*
G01Y1819852D02*
Y1818277D01*
G01X2347091Y1814911D02*
Y1815699D01*
G01Y1818061D02*
Y1818848D01*
G01Y1811762D02*
Y1812549D01*
G01Y1805463D02*
Y1806250D01*
G01Y1808612D02*
Y1809400D01*
G01Y1802313D02*
Y1803100D01*
G01Y1799163D02*
Y1799951D01*
G01X2346579Y1834750D02*
Y1828996D01*
G01X2345363Y1802313D02*
Y1799951D01*
G01Y1805463D02*
Y1803100D01*
G01Y1808612D02*
Y1806250D01*
G01Y1811762D02*
Y1809400D01*
G01Y1814911D02*
Y1812549D01*
G01Y1818061D02*
Y1815699D01*
G01Y1820522D02*
Y1818848D01*
G01X2344424Y1814911D02*
Y1815699D01*
G01Y1818061D02*
Y1818848D01*
G01Y1811762D02*
Y1812549D01*
G01Y1805463D02*
Y1806250D01*
G01Y1808612D02*
Y1809400D01*
G01Y1802313D02*
Y1803100D01*
G01Y1799163D02*
Y1799951D01*
G01X2344277Y1814911D02*
Y1815699D01*
G01Y1818061D02*
Y1818848D01*
G01Y1811762D02*
Y1812549D01*
G01Y1805463D02*
Y1806250D01*
G01Y1808612D02*
Y1809400D01*
G01Y1802313D02*
Y1803100D01*
G01Y1799163D02*
Y1799951D01*
G01X2342685Y1814911D02*
Y1815699D01*
G01Y1818061D02*
Y1818848D01*
G01Y1811762D02*
Y1812549D01*
G01Y1805463D02*
Y1806250D01*
G01Y1808612D02*
Y1809400D01*
G01Y1802313D02*
Y1803100D01*
G01Y1799163D02*
Y1799951D01*
G01X2341820Y1825049D02*
Y1827805D01*
G01X2341743Y1799951D02*
Y1799163D01*
G01Y1803100D02*
Y1802313D01*
G01Y1806250D02*
Y1805463D01*
G01Y1809400D02*
Y1808612D01*
G01Y1812549D02*
Y1811762D01*
G01Y1815699D02*
Y1814911D01*
G01Y1818848D02*
Y1818061D01*
G01X2338907Y1799951D02*
Y1799163D01*
G01Y1803100D02*
Y1802313D01*
G01Y1806250D02*
Y1805463D01*
G01Y1809400D02*
Y1808612D01*
G01Y1812549D02*
Y1811762D01*
G01Y1815699D02*
Y1814911D01*
G01Y1818848D02*
Y1818061D01*
G01X2338718Y1814911D02*
Y1815699D01*
G01Y1818061D02*
Y1818848D01*
G01Y1811762D02*
Y1812549D01*
G01Y1805463D02*
Y1806250D01*
G01Y1808612D02*
Y1809400D01*
G01Y1802313D02*
Y1803100D01*
G01Y1799163D02*
Y1799951D01*
G01X2336945Y1814911D02*
Y1815699D01*
G01Y1818061D02*
Y1818848D01*
G01Y1811762D02*
Y1812549D01*
G01Y1805463D02*
Y1806250D01*
G01Y1808612D02*
Y1809400D01*
G01Y1802313D02*
Y1803100D01*
G01Y1799163D02*
Y1799951D01*
G01X2335966Y1825049D02*
Y1822274D01*
G01X2335491Y1827805D02*
Y1822274D01*
G01X2335173Y1836151D02*
Y1822274D01*
G01X2345620Y1828651D02*
X2345603Y1828596D01*
X2345550Y1828431D01*
X2345472Y1828172D01*
X2345376Y1827845D01*
X2345271Y1827470D01*
G01X2349878Y1835266D02*
X2349775Y1834897D01*
X2349679Y1834567D01*
X2349599Y1834305D01*
X2349546Y1834139D01*
X2349529Y1834085D01*
G01X2350333Y1825443D02*
X2350078Y1825049D01*
G01X2339999Y1834750D02*
X2339208Y1833472D01*
G01X2338235Y1832594D02*
X2336940Y1830743D01*
G01X2339011Y1831729D02*
X2338322Y1830743D01*
G01X2341407Y1834750D02*
X2339965Y1832603D01*
G01X2296157Y1971132D02*
Y1938626D01*
G01X2326144Y1898666D02*
X2325422Y1899153D01*
X2324701Y1900127D01*
Y1901102D01*
X2325422Y1902076D01*
X2326144Y1902563D01*
X2327588D01*
X2328310Y1902076D01*
G01X2326144Y1890871D02*
X2325422Y1891358D01*
X2324701Y1892332D01*
Y1893307D01*
X2325422Y1894281D01*
X2326144Y1894768D01*
X2327588D01*
X2328310Y1894281D01*
X2329031Y1893307D01*
X2329753Y1892332D01*
X2331197Y1891358D01*
X2333362Y1890871D01*
Y1894768D01*
G01X2327588Y1933745D02*
X2329031Y1933257D01*
X2329753Y1931796D01*
X2329031Y1930334D01*
X2327588Y1929847D01*
X2326144Y1930334D01*
X2325422Y1930822D01*
X2324701Y1931796D01*
X2325422Y1932770D01*
X2326144Y1933257D01*
X2327588Y1933745D01*
X2330475D01*
X2331919Y1933257D01*
X2332640Y1932770D01*
X2333362Y1931796D01*
X2332640Y1930822D01*
X2331919Y1930334D01*
G01X2325422Y1906948D02*
X2324701Y1907923D01*
Y1908897D01*
X2325422Y1909872D01*
X2326144Y1910359D01*
X2326866D01*
X2327588Y1909872D01*
X2328310Y1908897D01*
X2329031Y1909872D01*
G01X2328310Y1902076D02*
X2329753Y1900127D01*
X2331197Y1899153D01*
X2333362Y1898666D01*
Y1902563D01*
G01Y1916205D02*
Y1915718D01*
X2332640D01*
X2333362Y1916205D01*
G01X2328310Y1907923D02*
Y1908897D01*
G01X2333362Y1924001D02*
X2332640Y1923026D01*
X2331919Y1922539D01*
X2330475Y1922052D01*
X2327588D01*
X2326144Y1922539D01*
X2325422Y1923026D01*
X2324701Y1924001D01*
X2325422Y1924975D01*
X2326144Y1925462D01*
X2327588Y1925949D01*
X2330475D01*
X2331919Y1925462D01*
X2332640Y1924975D01*
X2333362Y1924001D01*
G01X2329031Y1909872D02*
X2330475Y1910846D01*
X2331197D01*
X2331919Y1910359D01*
X2332640Y1909872D01*
X2333362Y1908897D01*
Y1907923D01*
X2332640Y1906948D01*
X2331919Y1906461D01*
G01X2335527Y1975069D02*
X2296157D01*
G01D02*
Y2014439D01*
G01X2335527Y1971132D02*
Y1940024D01*
G01X2319909Y1993789D02*
X2320412Y1993420D01*
G01X2321543Y1998587D02*
X2321166Y1998834D01*
G01X2320789Y1993912D02*
X2320412Y1994158D01*
G01X2322674Y1989483D02*
X2322422Y1989606D01*
G01X2322674Y1983947D02*
X2322422Y1984070D01*
G01X2320412Y1993420D02*
X2321040Y1993174D01*
G01X2321166Y1993789D02*
X2320789Y1993912D01*
G01X2322045Y1996742D02*
X2322422Y1996250D01*
G01X2323051Y1991575D02*
X2323302Y1991329D01*
G01X2322799D02*
X2322548Y1991575D01*
G01X2322925Y1989729D02*
X2323302Y1989360D01*
G01X2322799D02*
X2322674Y1989483D01*
G01X2323051Y1986038D02*
X2323302Y1985792D01*
G01X2322799D02*
X2322548Y1986038D01*
G01X2322925Y1984193D02*
X2323302Y1983824D01*
G01X2322799D02*
X2322674Y1983947D01*
G01X2319407Y2007077D02*
X2325312D01*
G01X2322171Y2006338D02*
X2319407D01*
G01X2325312D02*
X2322925D01*
G01Y2002894D02*
X2325312D01*
G01X2319407D02*
X2322171D01*
G01X2325312Y2002155D02*
X2319407D01*
G01X2325312Y1997603D02*
X2322045D01*
G01X2322674Y1996988D02*
X2324684D01*
G01X2321417Y1993789D02*
X2321166D01*
G01X2324684Y1993420D02*
X2325312D01*
G01X2321040Y1993174D02*
X2321543D01*
G01X2319407Y1992190D02*
X2323428D01*
G01X2322548Y1991575D02*
X2319407D01*
G01X2323428D02*
X2323051D01*
G01X2319407Y1990221D02*
X2322422D01*
G01Y1989606D02*
X2319407D01*
G01Y1988253D02*
X2322422D01*
G01Y1987638D02*
X2319407D01*
G01Y1986653D02*
X2323428D01*
G01X2322548Y1986038D02*
X2319407D01*
G01X2323428D02*
X2323051D01*
G01X2319407Y1984685D02*
X2322422D01*
G01Y1984070D02*
X2319407D01*
G01Y1982716D02*
X2322422D01*
G01Y1982101D02*
X2319407D01*
G01X2323302Y1998587D02*
X2322422Y2000310D01*
G01X2322925Y1989114D02*
X2322799Y1989360D01*
G01X2322925Y1983578D02*
X2322799Y1983824D01*
G01X2322422Y2001171D02*
X2323679Y1998834D01*
G01X2323051Y1996373D02*
X2322674Y1996988D01*
G01X2319532Y1994404D02*
X2319909Y1993789D01*
G01X2320412Y1994158D02*
X2320161Y1994527D01*
G01X2323302Y1991329D02*
X2323428Y1990960D01*
G01X2322925D02*
X2322799Y1991329D01*
G01X2323302Y1989360D02*
X2323428Y1988991D01*
G01X2323302Y1985792D02*
X2323428Y1985423D01*
G01X2322925D02*
X2322799Y1985792D01*
G01X2323302Y1983824D02*
X2323428Y1983455D01*
G01X2323176Y1995758D02*
X2323051Y1996373D01*
G01X2319407Y1995020D02*
X2319532Y1994404D01*
G01X2322422Y1996250D02*
X2322548Y1995758D01*
G01X2320161Y1994527D02*
X2320035Y1995020D01*
G01X2335527Y1975069D02*
Y2014439D01*
G01X2325312Y1993420D02*
Y1997603D01*
G01Y2002894D02*
Y2002155D01*
G01Y2007077D02*
Y2006338D01*
G01X2324684Y1996988D02*
Y1993420D01*
G01X2323428Y1983455D02*
Y1982963D01*
G01Y1985423D02*
Y1984931D01*
G01Y1986653D02*
Y1986038D01*
G01Y1988991D02*
Y1988499D01*
G01Y1990960D02*
Y1990467D01*
G01Y1992190D02*
Y1991575D01*
G01X2323176Y1995020D02*
Y1995758D01*
G01X2322925Y1990713D02*
Y1990960D01*
G01Y1988745D02*
Y1989114D01*
G01Y1985177D02*
Y1985423D01*
G01Y1983209D02*
Y1983578D01*
G01Y2006338D02*
Y2002894D01*
G01X2322548Y1995758D02*
Y1995020D01*
G01X2322171Y2002894D02*
Y2006338D01*
G01X2322045Y1997603D02*
Y1996742D01*
G01X2320915Y1996865D02*
Y1997603D01*
G01X2320035Y1995020D02*
Y1995758D01*
G01X2319407Y2006338D02*
Y2007077D01*
G01Y2002155D02*
Y2002894D01*
G01Y1989606D02*
Y1990221D01*
G01Y1991575D02*
Y1992190D01*
G01Y1984070D02*
Y1984685D01*
G01Y1986038D02*
Y1986653D01*
G01Y1987638D02*
Y1988253D01*
G01Y1982101D02*
Y1982716D01*
G01Y1995758D02*
Y1995020D01*
G01X2323051Y1994404D02*
X2323176Y1995020D01*
G01X2319532Y1996373D02*
X2319407Y1995758D01*
G01X2323428Y1982963D02*
X2323302Y1982593D01*
G01X2323428Y1984931D02*
X2323302Y1984562D01*
G01X2323428Y1988499D02*
X2323302Y1988130D01*
G01X2323428Y1990467D02*
X2323302Y1990098D01*
G01X2322548Y1995020D02*
X2322422Y1994527D01*
G01X2320035Y1995758D02*
X2320161Y1996250D01*
G01X2321166Y1998834D02*
X2322422Y2001171D01*
G01X2322799Y1982963D02*
X2322925Y1983209D01*
G01X2322799Y1984931D02*
X2322925Y1985177D01*
G01X2322799Y1988499D02*
X2322925Y1988745D01*
G01X2322799Y1990467D02*
X2322925Y1990713D01*
G01X2322422Y2000310D02*
X2321543Y1998587D01*
G01X2322422Y1994527D02*
X2322171Y1994158D01*
G01X2320161Y1996250D02*
X2320412Y1996619D01*
G01X2322674Y1993789D02*
X2323051Y1994404D01*
G01X2319909Y1996988D02*
X2319532Y1996373D01*
G01X2323302Y1982593D02*
X2323051Y1982347D01*
G01X2322674Y1982839D02*
X2322799Y1982963D01*
G01X2323302Y1984562D02*
X2322925Y1984193D01*
G01X2322674Y1984808D02*
X2322799Y1984931D01*
G01X2323302Y1988130D02*
X2323051Y1987884D01*
G01X2322674Y1988376D02*
X2322799Y1988499D01*
G01X2323302Y1990098D02*
X2322925Y1989729D01*
G01X2322674Y1990344D02*
X2322799Y1990467D01*
G01X2322171Y1994158D02*
X2321794Y1993912D01*
G01X2323679Y1998834D02*
X2323302Y1998587D01*
G01X2322171Y1993420D02*
X2322674Y1993789D01*
G01X2320412Y1997357D02*
X2319909Y1996988D01*
G01X2322422Y1982716D02*
X2322674Y1982839D01*
G01X2322422Y1984685D02*
X2322674Y1984808D01*
G01X2322422Y1988253D02*
X2322674Y1988376D01*
G01X2322422Y1990221D02*
X2322674Y1990344D01*
G01X2320412Y1996619D02*
X2320915Y1996865D01*
G01Y1997603D02*
X2320412Y1997357D01*
G01X2321794Y1993912D02*
X2321417Y1993789D01*
G01X2323051Y1982347D02*
X2322422Y1982101D01*
G01X2323051Y1987884D02*
X2322422Y1987638D01*
G01X2321543Y1993174D02*
X2322171Y1993420D01*
G01X2339464Y1975069D02*
X2372036D01*
G01X2296157Y2014439D02*
X2335527D01*
G01X2299248Y2090738D02*
Y2070659D01*
G01X2295311Y2077352D02*
Y2076368D01*
G01Y2079911D02*
Y2078927D01*
G01Y2082470D02*
Y2081486D01*
G01Y2085029D02*
Y2084045D01*
G01X2339464Y2014439D02*
X2368337D01*
G01X2359976Y2056683D02*
G03Y2055502I0J-591D01*
G01Y2059439D02*
G03Y2058258I0J-590D01*
G01X2358992Y2073888D02*
G03Y2077037I0J1574D01*
G01X2353234Y2085977D02*
G03X2352164Y2084153I2810J-2874D01*
G01X2360210Y2088878D02*
G03X2357996Y2083711I6938J-6031D01*
G01X2361096Y2088952D02*
G03X2358881Y2083711I7142J-6107D01*
G01X2353677Y2055502D02*
G03Y2056683I0J590D01*
G01Y2058258D02*
G03Y2059439I0J590D01*
G01X2354661Y2077037D02*
G03Y2073888I0J-1574D01*
G01X2353739Y2085433D02*
G03X2353197Y2084449I1276J-1344D01*
G01X2350921Y2087274D02*
G03I-3346J0D01*
G01X2351079D02*
G03I-3504J0D01*
G01X2352102D02*
G03I-4527J0D01*
G01X2339762Y2088878D02*
G03X2337548Y2083711I6938J-6031D01*
G01X2340648Y2088952D02*
G03X2338433Y2083711I7142J-6107D01*
G01X2349413Y2086512D02*
X2349773Y2086276D01*
X2350011Y2085925D01*
X2350097Y2085522D01*
X2350014Y2085120D01*
X2349778Y2084767D01*
X2349414Y2084527D01*
X2348990Y2084443D01*
G01X2348567Y2084527D02*
X2348206Y2084763D01*
X2347968Y2085113D01*
X2347882Y2085516D01*
X2347965Y2085919D01*
X2348201Y2086271D01*
X2348565Y2086511D01*
X2348990Y2086596D01*
G01X2344245Y2086512D02*
X2344606Y2086276D01*
X2344844Y2085925D01*
X2344929Y2085522D01*
X2344847Y2085120D01*
X2344610Y2084767D01*
X2344247Y2084527D01*
X2343822Y2084443D01*
G01X2343399Y2084527D02*
X2343039Y2084763D01*
X2342800Y2085113D01*
X2342715Y2085516D01*
X2342798Y2085919D01*
X2343034Y2086271D01*
X2343397Y2086511D01*
X2343822Y2086596D01*
G01X2350187Y2086967D02*
X2350639Y2086527D01*
X2350909Y2085991D01*
X2350979Y2085421D01*
X2350838Y2084857D01*
X2350491Y2084332D01*
X2349964Y2083939D01*
X2349321Y2083735D01*
X2348642Y2083738D01*
X2348002Y2083946D01*
X2347479Y2084342D01*
X2347137Y2084866D01*
X2346999Y2085427D01*
X2347071Y2085994D01*
X2347341Y2086528D01*
G01X2345020Y2086967D02*
X2345472Y2086527D01*
X2345742Y2085991D01*
X2345812Y2085421D01*
X2345670Y2084857D01*
X2345324Y2084332D01*
X2344796Y2083939D01*
X2344154Y2083735D01*
X2343474Y2083738D01*
X2342834Y2083946D01*
X2342312Y2084342D01*
X2341970Y2084866D01*
X2341832Y2085427D01*
X2341904Y2085994D01*
X2342174Y2086528D01*
G01X2358795Y2084459D02*
X2335173D01*
G01X2356076Y2084449D02*
X2353197D01*
G01X2357995Y2083711D02*
X2358881D01*
G01X2352164D02*
X2356076D01*
G01X2337548D02*
X2338433D01*
G01X2362732Y2083671D02*
X2389110D01*
G01Y2082490D02*
X2335173D01*
G01X2365016Y2079734D02*
X2348638D01*
G01X2354661Y2077037D02*
X2358992D01*
G01X2354036Y2076250D02*
X2359617D01*
G01Y2074675D02*
X2354036D01*
G01X2358992Y2073888D02*
X2354661D01*
G01X2365016Y2069557D02*
X2348638D01*
G01X2359976Y2060029D02*
X2353677D01*
G01X2358401Y2059734D02*
X2361551D01*
G01X2355252D02*
X2352102D01*
G01Y2057766D02*
X2355252D01*
G01X2361551D02*
X2358401D01*
G01X2352102Y2057175D02*
X2355252D01*
G01X2361551D02*
X2358401D01*
G01X2353688Y2056431D02*
X2353781D01*
G01Y2055683D02*
X2353688D01*
G01X2358401Y2055207D02*
X2361551D01*
G01X2355252D02*
X2352102D01*
G01X2353677Y2054911D02*
X2359976D01*
G01X2365016Y2069557D02*
Y2095955D01*
G01X2362732Y2082490D02*
Y2090837D01*
G01X2361551Y2055207D02*
Y2057175D01*
G01Y2059734D02*
Y2057766D01*
G01X2359976Y2059439D02*
Y2060029D01*
G01Y2056683D02*
Y2058258D01*
G01Y2054911D02*
Y2055502D01*
G01X2359617Y2074675D02*
Y2076250D01*
G01X2359583D02*
Y2074675D01*
G01X2359558Y2076250D02*
Y2074675D01*
G01X2358992Y2054911D02*
Y2060029D01*
G01X2358795D02*
Y2054911D01*
G01Y2088238D02*
Y2084459D01*
G01X2358401Y2057766D02*
Y2059734D01*
G01Y2057175D02*
Y2055207D01*
G01X2358235Y2074675D02*
Y2076250D01*
G01X2357865D02*
Y2074675D01*
G01X2356076Y2083711D02*
Y2084449D01*
G01X2355788Y2074675D02*
Y2076250D01*
G01X2355418D02*
Y2074675D01*
G01X2355252Y2057766D02*
Y2059734D01*
G01Y2057175D02*
Y2055207D01*
G01X2354858Y2060029D02*
Y2054911D01*
G01X2354661D02*
Y2060029D01*
G01X2354095Y2074675D02*
Y2076250D01*
G01X2354071Y2074675D02*
Y2076250D01*
G01X2354036D02*
Y2074675D01*
G01X2353781Y2056431D02*
Y2055683D01*
G01X2353688D02*
Y2056304D01*
G01X2353677Y2055502D02*
Y2054911D01*
G01Y2058258D02*
Y2056683D01*
G01Y2060029D02*
Y2059439D01*
G01X2353594Y2056192D02*
Y2056320D01*
G01X2352164Y2084153D02*
Y2083711D01*
G01X2352102Y2055207D02*
Y2057175D01*
G01Y2059734D02*
Y2057766D01*
G01X2348638Y2082490D02*
Y2069557D01*
G01X2335173Y2096171D02*
Y2082490D01*
G01X2353688Y2056304D02*
X2353594Y2056192D01*
G01Y2056320D02*
X2353688Y2056431D01*
G01X2347792Y2086967D02*
X2347340Y2086527D01*
X2347070Y2085991D01*
X2347000Y2085421D01*
X2347141Y2084857D01*
X2347488Y2084332D01*
X2348015Y2083939D01*
X2348658Y2083735D01*
X2349337Y2083738D01*
X2349977Y2083946D01*
X2350500Y2084342D01*
X2350842Y2084866D01*
X2350980Y2085427D01*
X2350908Y2085994D01*
X2350638Y2086528D01*
G01X2342624Y2086967D02*
X2342173Y2086527D01*
X2341903Y2085991D01*
X2341832Y2085421D01*
X2341974Y2084857D01*
X2342321Y2084332D01*
X2342848Y2083939D01*
X2343491Y2083735D01*
X2344170Y2083738D01*
X2344810Y2083946D01*
X2345333Y2084342D01*
X2345674Y2084866D01*
X2345812Y2085427D01*
X2345741Y2085994D01*
X2345470Y2086528D01*
G01X2349413Y2084527D02*
X2349773Y2084763D01*
X2350011Y2085113D01*
X2350097Y2085516D01*
X2350014Y2085919D01*
X2349778Y2086271D01*
X2349414Y2086511D01*
X2348990Y2086596D01*
G01X2348567Y2086512D02*
X2348206Y2086276D01*
X2347968Y2085925D01*
X2347882Y2085522D01*
X2347965Y2085120D01*
X2348201Y2084767D01*
X2348565Y2084527D01*
X2348990Y2084443D01*
G01X2344245Y2084527D02*
X2344606Y2084763D01*
X2344844Y2085113D01*
X2344929Y2085516D01*
X2344847Y2085919D01*
X2344610Y2086271D01*
X2344247Y2086511D01*
X2343822Y2086596D01*
G01X2343399Y2086512D02*
X2343039Y2086276D01*
X2342800Y2085925D01*
X2342715Y2085522D01*
X2342798Y2085120D01*
X2343034Y2084767D01*
X2343397Y2084527D01*
X2343822Y2084443D01*
G01X2349740Y2087274D02*
G03I-2165J0D01*
G01X2349338Y2088813D02*
X2349621Y2088635D01*
X2349808Y2088370D01*
X2349875Y2088068D01*
X2349811Y2087768D01*
X2349625Y2087501D01*
X2349340Y2087319D01*
X2348990Y2087254D01*
G01X2348641Y2087319D02*
X2348358Y2087497D01*
X2348171Y2087762D01*
X2348104Y2088064D01*
X2348168Y2088364D01*
X2348354Y2088631D01*
X2348639Y2088812D01*
X2348990Y2088878D01*
G01X2344171Y2088813D02*
X2344454Y2088635D01*
X2344641Y2088370D01*
X2344708Y2088068D01*
X2344644Y2087768D01*
X2344458Y2087501D01*
X2344173Y2087319D01*
X2343822Y2087254D01*
G01X2343473Y2087319D02*
X2343191Y2087497D01*
X2343004Y2087762D01*
X2342937Y2088064D01*
X2343001Y2088364D01*
X2343186Y2088631D01*
X2343472Y2088812D01*
X2343822Y2088878D01*
G01X2354796Y2088628D02*
X2354978Y2088363D01*
X2355043Y2088064D01*
X2354978Y2087768D01*
G01X2347792Y2086967D02*
X2347469Y2087386D01*
X2347307Y2087870D01*
X2347328Y2088375D01*
X2347531Y2088851D01*
X2347898Y2089255D01*
X2348404Y2089522D01*
X2348995Y2089616D01*
X2349585Y2089519D01*
X2350087Y2089250D01*
X2350451Y2088846D01*
X2350652Y2088368D01*
X2350672Y2087863D01*
X2350508Y2087382D01*
X2350187Y2086967D01*
G01X2342624D02*
X2342302Y2087386D01*
X2342139Y2087870D01*
X2342161Y2088375D01*
X2342364Y2088851D01*
X2342731Y2089255D01*
X2343237Y2089522D01*
X2343828Y2089616D01*
X2344417Y2089519D01*
X2344920Y2089250D01*
X2345284Y2088846D01*
X2345485Y2088368D01*
X2345504Y2087863D01*
X2345340Y2087382D01*
X2345020Y2086967D01*
G01X2358795Y2088238D02*
X2335173D01*
G01X2352459Y2087918D02*
X2353271D01*
G01D02*
Y2088066D01*
G01X2352459D02*
Y2087918D01*
G01X2353338Y2088370D02*
X2353271Y2088066D01*
G01X2352459D02*
X2352546Y2088543D01*
X2352793Y2088985D01*
X2353182Y2089337D01*
X2353688Y2089557D01*
X2354266Y2089613D01*
X2354829Y2089491D01*
X2355305Y2089208D01*
X2355644Y2088804D01*
X2355824Y2088347D01*
X2355839Y2087867D01*
X2355682Y2087396D01*
X2355368Y2086979D01*
G01X2350187Y2086967D02*
X2350510Y2087386D01*
X2350673Y2087870D01*
X2350651Y2088375D01*
X2350448Y2088851D01*
X2350081Y2089255D01*
X2349575Y2089522D01*
X2348984Y2089616D01*
X2348395Y2089519D01*
X2347892Y2089250D01*
X2347528Y2088846D01*
X2347327Y2088368D01*
X2347308Y2087863D01*
X2347471Y2087382D01*
X2347792Y2086967D01*
G01X2345020D02*
X2345343Y2087386D01*
X2345505Y2087870D01*
X2345484Y2088375D01*
X2345281Y2088851D01*
X2344914Y2089255D01*
X2344408Y2089522D01*
X2343816Y2089616D01*
X2343227Y2089519D01*
X2342725Y2089250D01*
X2342361Y2088846D01*
X2342159Y2088368D01*
X2342140Y2087863D01*
X2342304Y2087382D01*
X2342624Y2086967D01*
G01X2355368Y2086979D02*
X2355705Y2087441D01*
X2355850Y2087959D01*
X2355790Y2088477D01*
X2355539Y2088961D01*
X2355102Y2089356D01*
X2354529Y2089579D01*
X2353895Y2089598D01*
X2353310Y2089412D01*
X2352855Y2089059D01*
X2352563Y2088587D01*
X2352459Y2088066D01*
G01X2353528Y2088638D02*
X2353338Y2088370D01*
G01X2354796Y2087504D02*
X2354979Y2087770D01*
X2355043Y2088067D01*
X2354978Y2088365D01*
G01X2355368Y2086979D02*
X2353739Y2085433D01*
G01X2354796Y2087504D02*
X2353234Y2085977D01*
G01X2349338Y2087319D02*
X2349621Y2087497D01*
X2349808Y2087762D01*
X2349875Y2088064D01*
X2349811Y2088364D01*
X2349625Y2088631D01*
X2349340Y2088812D01*
X2348990Y2088878D01*
G01X2348641Y2088813D02*
X2348358Y2088635D01*
X2348171Y2088370D01*
X2348104Y2088068D01*
X2348168Y2087768D01*
X2348354Y2087501D01*
X2348639Y2087319D01*
X2348990Y2087254D01*
G01X2344171Y2087319D02*
X2344454Y2087497D01*
X2344641Y2087762D01*
X2344708Y2088064D01*
X2344644Y2088364D01*
X2344458Y2088631D01*
X2344173Y2088812D01*
X2343822Y2088878D01*
G01X2343473Y2088813D02*
X2343191Y2088635D01*
X2343004Y2088370D01*
X2342937Y2088068D01*
X2343001Y2087768D01*
X2343186Y2087501D01*
X2343472Y2087319D01*
X2343822Y2087254D01*
G01X2354937Y2155364D02*
G03X2355331Y2155758I0J394D01*
G01Y2153396D02*
G03X2354937Y2153789I-394J-1D01*
G01Y2100364D02*
G03X2355331Y2100758I0J394D01*
G01Y2098396D02*
G03X2354937Y2098789I-394J-1D01*
G01Y2130364D02*
G03X2355331Y2130758I0J394D01*
G01Y2128396D02*
G03X2354937Y2128789I-394J-1D01*
G01Y2125364D02*
G03X2355331Y2125758I0J394D01*
G01Y2123396D02*
G03X2354937Y2123789I-394J-1D01*
G01Y2120364D02*
G03X2355331Y2120758I0J394D01*
G01Y2118396D02*
G03X2354937Y2118789I-394J-1D01*
G01Y2110364D02*
G03X2355331Y2110758I0J394D01*
G01Y2108396D02*
G03X2354937Y2108789I-394J-1D01*
G01Y2115364D02*
G03X2355331Y2115758I0J394D01*
G01Y2113396D02*
G03X2354937Y2113789I-394J-1D01*
G01Y2105364D02*
G03X2355331Y2105758I0J394D01*
G01Y2103396D02*
G03X2354937Y2103789I-394J-1D01*
G01X2361231Y2099721D02*
X2360882Y2100062D01*
G01X2357659Y2097759D02*
X2358007Y2097418D01*
G01X2358094Y2101427D02*
X2358704Y2100915D01*
G01X2358007D02*
X2357398Y2101427D01*
G01X2360447Y2099721D02*
X2360708Y2099550D01*
G01X2354516Y2088809D02*
X2354796Y2088628D01*
G01X2360882Y2100062D02*
X2360534Y2100233D01*
G01X2358443Y2097844D02*
X2358182Y2097930D01*
G01X2358007Y2097418D02*
X2358356Y2097333D01*
G01X2354169Y2088878D02*
X2354517Y2088809D01*
G01X2344424Y2157431D02*
X2356433D01*
G01X2336945D02*
X2344277D01*
G01X2352890Y2156151D02*
X2351905D01*
G01X2352890Y2155955D02*
X2351905D01*
G01X2352890Y2155561D02*
X2351905D01*
G01X2347772Y2155364D02*
X2354937D01*
G01X2344277Y2155069D02*
X2336945D01*
G01X2356433D02*
X2344424D01*
G01Y2154281D02*
X2356433D01*
G01X2336945D02*
X2344277D01*
G01X2385173Y2154183D02*
X2358480D01*
G01X2347772Y2153789D02*
X2354937D01*
G01X2352890Y2153592D02*
X2351905D01*
G01X2352890Y2153199D02*
X2351905D01*
G01X2352890Y2153002D02*
X2351905D01*
G01X2344277Y2151919D02*
X2336945D01*
G01X2356433D02*
X2344424D01*
G01X2366669Y2151840D02*
X2385173D01*
G01X2356433D02*
X2355331D01*
G01X2380673Y2151821D02*
X2358480D01*
G01X2356433Y2151722D02*
X2348898D01*
G01X2353439Y2151230D02*
X2351315D01*
G01X2344424Y2151132D02*
X2356433D01*
G01X2336945D02*
X2344277D01*
G01X2354424Y2150935D02*
X2353439D01*
G01X2354424Y2150738D02*
X2353439D01*
G01X2355331Y2150541D02*
X2349305D01*
G01X2355331Y2149360D02*
X2349305D01*
G01X2354424Y2149163D02*
X2353439D01*
G01X2354424Y2148966D02*
X2353439D01*
G01X2344277Y2148770D02*
X2336945D01*
G01X2356433D02*
X2344424D01*
G01Y2147982D02*
X2356433D01*
G01X2336945D02*
X2344277D01*
G01X2349324Y2147903D02*
X2347441D01*
G01X2354424Y2147785D02*
X2353439D01*
G01X2354424Y2147588D02*
X2353439D01*
G01X2355331Y2147392D02*
X2349305D01*
G01X2355331Y2146211D02*
X2349305D01*
G01X2354424Y2146014D02*
X2353439D01*
G01X2354424Y2145817D02*
X2353439D01*
G01X2347441Y2145699D02*
X2349324D01*
G01X2344277Y2145620D02*
X2336945D01*
G01X2356433D02*
X2344424D01*
G01Y2144833D02*
X2356433D01*
G01X2336945D02*
X2344277D01*
G01X2354424Y2144636D02*
X2353439D01*
G01X2354424Y2144439D02*
X2353439D01*
G01X2355331Y2144242D02*
X2349305D01*
G01X2355331Y2143061D02*
X2349305D01*
G01X2354424Y2142864D02*
X2353439D01*
G01X2354424Y2142667D02*
X2353439D01*
G01X2344277Y2142470D02*
X2336945D01*
G01X2356433D02*
X2344424D01*
G01Y2141683D02*
X2356433D01*
G01X2336945D02*
X2344277D01*
G01X2354424Y2141486D02*
X2353439D01*
G01X2354424Y2141289D02*
X2353439D01*
G01X2355331Y2141092D02*
X2349305D01*
G01X2355331Y2139911D02*
X2349305D01*
G01X2354424Y2139714D02*
X2353439D01*
G01X2354424Y2139518D02*
X2353439D01*
G01X2344277Y2139321D02*
X2336945D01*
G01X2356433D02*
X2344424D01*
G01Y2138533D02*
X2356433D01*
G01X2336945D02*
X2344277D01*
G01X2349324Y2138455D02*
X2347441D01*
G01X2354424Y2138337D02*
X2353439D01*
G01X2354424Y2138140D02*
X2353439D01*
G01X2355331Y2137943D02*
X2349305D01*
G01X2355331Y2136762D02*
X2349305D01*
G01X2354424Y2136565D02*
X2353439D01*
G01X2354424Y2136368D02*
X2353439D01*
G01X2347441Y2136250D02*
X2349324D01*
G01X2344277Y2136171D02*
X2336945D01*
G01X2356433D02*
X2344424D01*
G01Y2135384D02*
X2356433D01*
G01X2336945D02*
X2344277D01*
G01X2354424Y2135187D02*
X2353439D01*
G01X2354424Y2134990D02*
X2353439D01*
G01X2355331Y2134793D02*
X2349305D01*
G01X2355331Y2133612D02*
X2349305D01*
G01X2354424Y2133415D02*
X2353439D01*
G01X2354424Y2133218D02*
X2353439D01*
G01X2344277Y2133022D02*
X2336945D01*
G01X2356433D02*
X2344424D01*
G01X2353439Y2132923D02*
X2351315D01*
G01X2348898Y2132431D02*
X2356433D01*
G01X2380673Y2132333D02*
X2358480D01*
G01X2356433Y2132313D02*
X2355331D01*
G01X2385173D02*
X2366669D01*
G01X2344424Y2132234D02*
X2356433D01*
G01X2336945D02*
X2344277D01*
G01X2352890Y2131151D02*
X2351905D01*
G01X2352890Y2130955D02*
X2351905D01*
G01X2352890Y2130561D02*
X2351905D01*
G01X2347772Y2130364D02*
X2354937D01*
G01X2385173Y2129970D02*
X2358480D01*
G01X2344277Y2129872D02*
X2336945D01*
G01X2356433D02*
X2344424D01*
G01Y2129085D02*
X2356433D01*
G01X2336945D02*
X2344277D01*
G01X2347772Y2128789D02*
X2354937D01*
G01X2352890Y2128592D02*
X2351905D01*
G01X2352890Y2128199D02*
X2351905D01*
G01X2352890Y2128002D02*
X2351905D01*
G01X2344277Y2126722D02*
X2336945D01*
G01X2356433D02*
X2344424D01*
G01X2352890Y2126151D02*
X2351905D01*
G01X2386130Y2125974D02*
X2366669D01*
G01X2352890Y2125955D02*
X2351905D01*
G01X2344424Y2125935D02*
X2356433D01*
G01X2336945D02*
X2344277D01*
G01X2352890Y2125561D02*
X2351905D01*
G01X2347772Y2125364D02*
X2354937D01*
G01X2347772Y2123789D02*
X2354937D01*
G01X2352890Y2123592D02*
X2351905D01*
G01X2344277Y2123573D02*
X2336945D01*
G01X2356433D02*
X2344424D01*
G01X2352890Y2123199D02*
X2351905D01*
G01X2352890Y2123002D02*
X2351905D01*
G01X2344424Y2122785D02*
X2356433D01*
G01X2336945D02*
X2344277D01*
G01X2352890Y2121151D02*
X2351905D01*
G01X2352890Y2120955D02*
X2351905D01*
G01X2352890Y2120561D02*
X2351905D01*
G01X2360708Y2099550D02*
X2360882Y2099295D01*
G01X2358182Y2097930D02*
X2358007Y2098186D01*
G01X2344277Y2120423D02*
X2336945D01*
G01X2356433D02*
X2344424D01*
G01X2347772Y2120364D02*
X2354937D01*
G01X2344424Y2119636D02*
X2356433D01*
G01X2336945D02*
X2344277D01*
G01X2347772Y2118789D02*
X2354937D01*
G01X2352890Y2118592D02*
X2351905D01*
G01X2352890Y2118199D02*
X2351905D01*
G01X2352890Y2118002D02*
X2351905D01*
G01X2344277Y2117274D02*
X2336945D01*
G01X2356433D02*
X2344424D01*
G01Y2116486D02*
X2356433D01*
G01X2336945D02*
X2344277D01*
G01X2352890Y2116151D02*
X2351905D01*
G01X2352890Y2115955D02*
X2351905D01*
G01X2352890Y2115561D02*
X2351905D01*
G01X2347772Y2115364D02*
X2354937D01*
G01X2385173Y2114734D02*
X2358480D01*
G01X2344277Y2114124D02*
X2336945D01*
G01X2356433D02*
X2344424D01*
G01X2347772Y2113789D02*
X2354937D01*
G01X2352890Y2113592D02*
X2351905D01*
G01X2344424Y2113337D02*
X2356433D01*
G01X2336945D02*
X2344277D01*
G01X2352890Y2113199D02*
X2351905D01*
G01X2352890Y2113002D02*
X2351905D01*
G01X2385173Y2112372D02*
X2358480D01*
G01X2352890Y2111151D02*
X2351905D01*
G01X2344277Y2110974D02*
X2336945D01*
G01X2356433D02*
X2344424D01*
G01X2352890Y2110955D02*
X2351905D01*
G01X2352890Y2110561D02*
X2351905D01*
G01X2347772Y2110364D02*
X2354937D01*
G01X2344424Y2110187D02*
X2356433D01*
G01X2336945D02*
X2344277D01*
G01X2347772Y2108789D02*
X2354937D01*
G01X2352890Y2108592D02*
X2351905D01*
G01X2352890Y2108199D02*
X2351905D01*
G01X2352890Y2108002D02*
X2351905D01*
G01X2344277Y2107825D02*
X2336945D01*
G01X2356433D02*
X2344424D01*
G01Y2107037D02*
X2356433D01*
G01X2336945D02*
X2344277D01*
G01X2352890Y2106151D02*
X2351905D01*
G01X2352890Y2105955D02*
X2351905D01*
G01X2352890Y2105561D02*
X2351905D01*
G01X2347772Y2105364D02*
X2354937D01*
G01X2344277Y2104675D02*
X2336945D01*
G01X2356433D02*
X2344424D01*
G01Y2103888D02*
X2356433D01*
G01X2336945D02*
X2344277D01*
G01X2347772Y2103789D02*
X2354937D01*
G01X2352890Y2103592D02*
X2351905D01*
G01X2352890Y2103199D02*
X2351905D01*
G01X2352890Y2103002D02*
X2351905D01*
G01X2357398Y2101939D02*
X2361492D01*
G01X2344277Y2101525D02*
X2336945D01*
G01X2356433D02*
X2344424D01*
G01X2361492Y2101427D02*
X2358094D01*
G01X2352890Y2101151D02*
X2351905D01*
G01X2352890Y2100955D02*
X2351905D01*
G01X2358704Y2100915D02*
X2358007D01*
G01X2344424Y2100738D02*
X2356433D01*
G01X2336945D02*
X2344277D01*
G01X2354878Y2100581D02*
X2346807D01*
G01X2352890Y2100561D02*
X2351905D01*
G01X2347772Y2100364D02*
X2354937D01*
G01X2360534Y2100233D02*
X2360098D01*
G01X2360185Y2099721D02*
X2360447D01*
G01X2347772Y2098789D02*
X2354937D01*
G01X2346807Y2098612D02*
X2354878D01*
G01X2352890Y2098592D02*
X2351905D01*
G01X2352890Y2098199D02*
X2351905D01*
G01X2351315Y2098159D02*
X2342330D01*
G01X2352890Y2098002D02*
X2351905D01*
G01X2358617Y2097844D02*
X2358443D01*
G01X2358356Y2097333D02*
X2358704D01*
G01X2355331Y2096545D02*
X2364701D01*
G01X2355331Y2096171D02*
X2335173D01*
G01X2365016Y2095955D02*
X2358480D01*
G01X2385173Y2095758D02*
X2366669D01*
G01X2356433Y2095364D02*
X2387142D01*
G01X2355331Y2094774D02*
X2364701D01*
G01X2335966Y2093592D02*
X2356433D01*
G01X2350333Y2093199D02*
X2356433D01*
G01Y2093140D02*
X2350333D01*
G01X2358795Y2092648D02*
X2335173D01*
G01X2385173Y2090837D02*
X2335173D01*
G01Y2090207D02*
X2358795D01*
G01X2340648Y2089616D02*
X2336809D01*
G01X2361096D02*
X2357257D01*
G01Y2088878D02*
X2360210D01*
G01X2336809D02*
X2339762D01*
G01X2361405Y2099380D02*
X2361231Y2099721D01*
G01X2357485Y2098100D02*
X2357659Y2097759D01*
G01X2350078Y2093592D02*
X2350333Y2093199D01*
G01X2358704Y2097333D02*
X2359053Y2097418D01*
G01X2360359Y2097077D02*
X2360708Y2097162D01*
G01X2358007Y2098186D02*
X2357920Y2098442D01*
G01X2361492Y2098953D02*
X2361405Y2099380D01*
G01X2360882Y2099295D02*
X2360969Y2098953D01*
G01X2357398Y2098442D02*
X2357485Y2098100D01*
G01X2366669Y2228396D02*
Y2095758D01*
G01X2364701Y2096545D02*
Y2094774D01*
G01X2361492Y2098271D02*
Y2098953D01*
G01Y2101939D02*
Y2101427D01*
G01X2361096Y2088952D02*
Y2089616D01*
G01X2360969Y2098953D02*
Y2098271D01*
G01X2360449Y2154183D02*
Y2170522D01*
G01Y2112372D02*
Y2095955D01*
G01Y2129970D02*
Y2114734D01*
G01Y2151821D02*
Y2132333D01*
G01X2360359Y2097588D02*
Y2097077D01*
G01X2359663Y2098442D02*
Y2098953D01*
G01X2359140D02*
Y2098442D01*
G01X2358795Y2092648D02*
Y2090207D01*
G01X2358480Y2095955D02*
Y2228199D01*
G01X2358356Y2099465D02*
Y2099977D01*
G01X2357920Y2098442D02*
Y2098953D01*
G01X2357398Y2101427D02*
Y2101939D01*
G01Y2098868D02*
Y2098442D01*
G01X2357257Y2089616D02*
Y2088878D01*
G01X2356433Y2231014D02*
Y2093140D01*
G01X2355331Y2093592D02*
Y2230561D01*
G01X2355252Y2151722D02*
Y2132431D01*
G01X2354937D02*
Y2151722D01*
G01X2354878Y2098612D02*
Y2100581D01*
G01X2354491Y2157431D02*
Y2158218D01*
G01Y2154281D02*
Y2155069D01*
G01Y2147982D02*
Y2148770D01*
G01Y2151132D02*
Y2151919D01*
G01Y2144833D02*
Y2145620D01*
G01Y2138533D02*
Y2139321D01*
G01Y2141683D02*
Y2142470D01*
G01Y2135384D02*
Y2136171D01*
G01Y2129085D02*
Y2129872D01*
G01Y2132234D02*
Y2133022D01*
G01Y2125935D02*
Y2126722D01*
G01Y2119636D02*
Y2120423D01*
G01Y2122785D02*
Y2123573D01*
G01Y2116486D02*
Y2117274D01*
G01Y2110187D02*
Y2110974D01*
G01Y2113337D02*
Y2114124D01*
G01Y2107037D02*
Y2107825D01*
G01Y2100738D02*
Y2101525D01*
G01Y2103888D02*
Y2104675D01*
G01X2354464Y2157431D02*
Y2158218D01*
G01Y2154281D02*
Y2155069D01*
G01Y2147982D02*
Y2148770D01*
G01Y2151132D02*
Y2151919D01*
G01Y2144833D02*
Y2145620D01*
G01Y2138533D02*
Y2139321D01*
G01Y2141683D02*
Y2142470D01*
G01Y2135384D02*
Y2136171D01*
G01Y2129085D02*
Y2129872D01*
G01Y2132234D02*
Y2133022D01*
G01Y2125935D02*
Y2126722D01*
G01Y2119636D02*
Y2120423D01*
G01Y2122785D02*
Y2123573D01*
G01Y2116486D02*
Y2117274D01*
G01Y2110187D02*
Y2110974D01*
G01Y2113337D02*
Y2114124D01*
G01Y2107037D02*
Y2107825D01*
G01Y2100738D02*
Y2101525D01*
G01Y2103888D02*
Y2104675D01*
G01X2354424Y2135384D02*
Y2133022D01*
G01Y2138533D02*
Y2136171D01*
G01Y2141683D02*
Y2139321D01*
G01Y2144833D02*
Y2142470D01*
G01Y2147982D02*
Y2145620D01*
G01Y2151132D02*
Y2148770D01*
G01X2354149Y2151722D02*
Y2132431D01*
G01X2354088Y2157431D02*
Y2158218D01*
G01Y2154281D02*
Y2155069D01*
G01Y2147982D02*
Y2148770D01*
G01Y2151132D02*
Y2151919D01*
G01Y2144833D02*
Y2145620D01*
G01Y2138533D02*
Y2139321D01*
G01Y2141683D02*
Y2142470D01*
G01Y2135384D02*
Y2136171D01*
G01Y2129085D02*
Y2129872D01*
G01Y2132234D02*
Y2133022D01*
G01Y2125935D02*
Y2126722D01*
G01Y2119636D02*
Y2120423D01*
G01Y2122785D02*
Y2123573D01*
G01Y2116486D02*
Y2117274D01*
G01Y2110187D02*
Y2110974D01*
G01Y2113337D02*
Y2114124D01*
G01Y2107037D02*
Y2107825D01*
G01Y2100738D02*
Y2101525D01*
G01Y2103888D02*
Y2104675D01*
G01X2353874Y2100364D02*
Y2098789D01*
G01Y2105364D02*
Y2103789D01*
G01Y2110364D02*
Y2108789D01*
G01Y2115364D02*
Y2113789D01*
G01Y2120364D02*
Y2118789D01*
G01Y2125364D02*
Y2123789D01*
G01Y2130364D02*
Y2128789D01*
G01Y2155364D02*
Y2153789D01*
G01X2353649Y2151722D02*
Y2132431D01*
G01X2353439Y2132923D02*
Y2151230D01*
G01X2352890Y2093140D02*
Y2090837D01*
G01Y2101151D02*
Y2098002D01*
G01Y2106151D02*
Y2103002D01*
G01Y2111151D02*
Y2108002D01*
G01Y2116151D02*
Y2113002D01*
G01Y2121151D02*
Y2118002D01*
G01Y2126151D02*
Y2123002D01*
G01Y2131151D02*
Y2128002D01*
G01Y2156151D02*
Y2153002D01*
G01X2352732Y2132431D02*
Y2151722D01*
G01X2352455Y2134793D02*
Y2133612D01*
G01Y2137943D02*
Y2136762D01*
G01Y2141092D02*
Y2139911D01*
G01Y2144242D02*
Y2143061D01*
G01Y2147392D02*
Y2146211D01*
G01Y2150541D02*
Y2149360D01*
G01X2351905Y2101151D02*
Y2098002D01*
G01Y2106151D02*
Y2103002D01*
G01Y2111151D02*
Y2108002D01*
G01Y2116151D02*
Y2113002D01*
G01Y2121151D02*
Y2118002D01*
G01Y2126151D02*
Y2123002D01*
G01Y2131151D02*
Y2128002D01*
G01Y2156151D02*
Y2153002D01*
G01X2351315Y2093592D02*
Y2230561D01*
G01X2350921Y2100364D02*
Y2098789D01*
G01Y2105364D02*
Y2103789D01*
G01Y2110364D02*
Y2108789D01*
G01Y2115364D02*
Y2113789D01*
G01Y2120364D02*
Y2118789D01*
G01Y2125364D02*
Y2123789D01*
G01Y2130364D02*
Y2128789D01*
G01Y2155364D02*
Y2153789D01*
G01X2350860Y2096171D02*
Y2227785D01*
G01X2350726Y2101525D02*
Y2100738D01*
G01Y2104675D02*
Y2103888D01*
G01Y2107825D02*
Y2107037D01*
G01Y2110974D02*
Y2110187D01*
G01Y2114124D02*
Y2113337D01*
G01Y2117274D02*
Y2116486D01*
G01Y2120423D02*
Y2119636D01*
G01Y2123573D02*
Y2122785D01*
G01Y2126722D02*
Y2125935D01*
G01Y2129872D02*
Y2129085D01*
G01Y2133022D02*
Y2132234D01*
G01Y2136171D02*
Y2135384D01*
G01Y2139321D02*
Y2138533D01*
G01Y2142470D02*
Y2141683D01*
G01Y2145620D02*
Y2144833D01*
G01Y2148770D02*
Y2147982D01*
G01Y2151919D02*
Y2151132D01*
G01Y2155069D02*
Y2154281D01*
G01Y2158218D02*
Y2157431D01*
G01X2350333Y2093199D02*
Y2093140D01*
G01X2349694Y2090837D02*
Y2093592D01*
G01X2349376Y2132431D02*
Y2151722D01*
G01X2349324Y2138455D02*
Y2136250D01*
G01Y2147903D02*
Y2145699D01*
G01X2349305Y2134793D02*
Y2133612D01*
G01Y2137943D02*
Y2136762D01*
G01Y2141092D02*
Y2139911D01*
G01Y2144242D02*
Y2143061D01*
G01Y2147392D02*
Y2146211D01*
G01Y2150541D02*
Y2149360D01*
G01X2348898Y2147903D02*
Y2151722D01*
G01Y2138455D02*
Y2145699D01*
G01Y2132431D02*
Y2136250D01*
G01X2348743Y2101525D02*
Y2100738D01*
G01Y2104675D02*
Y2103888D01*
G01Y2107825D02*
Y2107037D01*
G01Y2110974D02*
Y2110187D01*
G01Y2114124D02*
Y2113337D01*
G01Y2117274D02*
Y2116486D01*
G01Y2120423D02*
Y2119636D01*
G01Y2123573D02*
Y2122785D01*
G01Y2126722D02*
Y2125935D01*
G01Y2129872D02*
Y2129085D01*
G01Y2133022D02*
Y2132234D01*
G01Y2136171D02*
Y2135384D01*
G01Y2139321D02*
Y2138533D01*
G01Y2142470D02*
Y2141683D01*
G01Y2145620D02*
Y2144833D01*
G01Y2148770D02*
Y2147982D01*
G01Y2151919D02*
Y2151132D01*
G01Y2155069D02*
Y2154281D01*
G01Y2158218D02*
Y2157431D01*
G01X2347772Y2100364D02*
Y2098789D01*
G01Y2105364D02*
Y2103789D01*
G01Y2110364D02*
Y2108789D01*
G01Y2115364D02*
Y2113789D01*
G01Y2120364D02*
Y2118789D01*
G01Y2125364D02*
Y2123789D01*
G01Y2130364D02*
Y2128789D01*
G01Y2155364D02*
Y2153789D01*
G01X2347441Y2145699D02*
Y2147903D01*
G01Y2136250D02*
Y2138455D01*
G01X2347091Y2157431D02*
Y2158218D01*
G01Y2154281D02*
Y2155069D01*
G01Y2147982D02*
Y2148770D01*
G01Y2151132D02*
Y2151919D01*
G01Y2144833D02*
Y2145620D01*
G01Y2138533D02*
Y2139321D01*
G01Y2141683D02*
Y2142470D01*
G01Y2135384D02*
Y2136171D01*
G01Y2129085D02*
Y2129872D01*
G01Y2132234D02*
Y2133022D01*
G01Y2125935D02*
Y2126722D01*
G01Y2119636D02*
Y2120423D01*
G01Y2122785D02*
Y2123573D01*
G01Y2116486D02*
Y2117274D01*
G01Y2110187D02*
Y2110974D01*
G01Y2113337D02*
Y2114124D01*
G01Y2107037D02*
Y2107825D01*
G01Y2100738D02*
Y2101525D01*
G01Y2103888D02*
Y2104675D01*
G01X2346807Y2100581D02*
Y2098612D01*
G01X2345363Y2103888D02*
Y2101525D01*
G01Y2100738D02*
Y2098159D01*
G01Y2107037D02*
Y2104675D01*
G01Y2110187D02*
Y2107825D01*
G01Y2113337D02*
Y2110974D01*
G01Y2116486D02*
Y2114124D01*
G01Y2119636D02*
Y2117274D01*
G01Y2122785D02*
Y2120423D01*
G01Y2125935D02*
Y2123573D01*
G01Y2129085D02*
Y2126722D01*
G01Y2132234D02*
Y2129872D01*
G01Y2135384D02*
Y2133022D01*
G01Y2138533D02*
Y2136171D01*
G01Y2141683D02*
Y2139321D01*
G01Y2144833D02*
Y2142470D01*
G01Y2147982D02*
Y2145620D01*
G01Y2151132D02*
Y2148770D01*
G01Y2154281D02*
Y2151919D01*
G01Y2157431D02*
Y2155069D01*
G01X2344424Y2157431D02*
Y2158218D01*
G01Y2154281D02*
Y2155069D01*
G01Y2147982D02*
Y2148770D01*
G01Y2151132D02*
Y2151919D01*
G01Y2144833D02*
Y2145620D01*
G01Y2138533D02*
Y2139321D01*
G01Y2141683D02*
Y2142470D01*
G01Y2135384D02*
Y2136171D01*
G01Y2129085D02*
Y2129872D01*
G01Y2132234D02*
Y2133022D01*
G01Y2125935D02*
Y2126722D01*
G01Y2119636D02*
Y2120423D01*
G01Y2122785D02*
Y2123573D01*
G01Y2116486D02*
Y2117274D01*
G01Y2110187D02*
Y2110974D01*
G01Y2113337D02*
Y2114124D01*
G01Y2107037D02*
Y2107825D01*
G01Y2100738D02*
Y2101525D01*
G01Y2103888D02*
Y2104675D01*
G01X2344277Y2157431D02*
Y2158218D01*
G01Y2154281D02*
Y2155069D01*
G01Y2147982D02*
Y2148770D01*
G01Y2151132D02*
Y2151919D01*
G01Y2144833D02*
Y2145620D01*
G01Y2138533D02*
Y2139321D01*
G01Y2141683D02*
Y2142470D01*
G01Y2135384D02*
Y2136171D01*
G01Y2129085D02*
Y2129872D01*
G01Y2132234D02*
Y2133022D01*
G01Y2125935D02*
Y2126722D01*
G01Y2119636D02*
Y2120423D01*
G01Y2122785D02*
Y2123573D01*
G01Y2116486D02*
Y2117274D01*
G01Y2110187D02*
Y2110974D01*
G01Y2113337D02*
Y2114124D01*
G01Y2107037D02*
Y2107825D01*
G01Y2100738D02*
Y2101525D01*
G01Y2103888D02*
Y2104675D01*
G01X2342685Y2157431D02*
Y2158218D01*
G01Y2154281D02*
Y2155069D01*
G01Y2147982D02*
Y2148770D01*
G01Y2151132D02*
Y2151919D01*
G01Y2144833D02*
Y2145620D01*
G01Y2138533D02*
Y2139321D01*
G01Y2141683D02*
Y2142470D01*
G01Y2135384D02*
Y2136171D01*
G01Y2129085D02*
Y2129872D01*
G01Y2132234D02*
Y2133022D01*
G01Y2125935D02*
Y2126722D01*
G01Y2119636D02*
Y2120423D01*
G01Y2122785D02*
Y2123573D01*
G01Y2116486D02*
Y2117274D01*
G01Y2110187D02*
Y2110974D01*
G01Y2113337D02*
Y2114124D01*
G01Y2107037D02*
Y2107825D01*
G01Y2100738D02*
Y2101525D01*
G01Y2103888D02*
Y2104675D01*
G01X2342330Y2230561D02*
Y2093592D01*
G01X2341820Y2090837D02*
Y2093592D01*
G01X2341743Y2101525D02*
Y2100738D01*
G01Y2104675D02*
Y2103888D01*
G01Y2107825D02*
Y2107037D01*
G01Y2110974D02*
Y2110187D01*
G01Y2114124D02*
Y2113337D01*
G01Y2117274D02*
Y2116486D01*
G01Y2120423D02*
Y2119636D01*
G01Y2123573D02*
Y2122785D01*
G01Y2126722D02*
Y2125935D01*
G01Y2129872D02*
Y2129085D01*
G01Y2133022D02*
Y2132234D01*
G01Y2136171D02*
Y2135384D01*
G01Y2139321D02*
Y2138533D01*
G01Y2142470D02*
Y2141683D01*
G01Y2145620D02*
Y2144833D01*
G01Y2148770D02*
Y2147982D01*
G01Y2151919D02*
Y2151132D01*
G01Y2155069D02*
Y2154281D01*
G01Y2158218D02*
Y2157431D01*
G01X2340648Y2088952D02*
Y2089616D01*
G01X2338907Y2101525D02*
Y2100738D01*
G01Y2104675D02*
Y2103888D01*
G01Y2107825D02*
Y2107037D01*
G01Y2110974D02*
Y2110187D01*
G01Y2114124D02*
Y2113337D01*
G01Y2117274D02*
Y2116486D01*
G01Y2120423D02*
Y2119636D01*
G01Y2123573D02*
Y2122785D01*
G01Y2126722D02*
Y2125935D01*
G01Y2129872D02*
Y2129085D01*
G01Y2133022D02*
Y2132234D01*
G01Y2136171D02*
Y2135384D01*
G01Y2139321D02*
Y2138533D01*
G01Y2142470D02*
Y2141683D01*
G01Y2145620D02*
Y2144833D01*
G01Y2148770D02*
Y2147982D01*
G01Y2151919D02*
Y2151132D01*
G01Y2155069D02*
Y2154281D01*
G01Y2158218D02*
Y2157431D01*
G01X2338718D02*
Y2158218D01*
G01Y2154281D02*
Y2155069D01*
G01Y2147982D02*
Y2148770D01*
G01Y2151132D02*
Y2151919D01*
G01Y2144833D02*
Y2145620D01*
G01Y2138533D02*
Y2139321D01*
G01Y2141683D02*
Y2142470D01*
G01Y2135384D02*
Y2136171D01*
G01Y2129085D02*
Y2129872D01*
G01Y2132234D02*
Y2133022D01*
G01Y2125935D02*
Y2126722D01*
G01Y2119636D02*
Y2120423D01*
G01Y2122785D02*
Y2123573D01*
G01Y2116486D02*
Y2117274D01*
G01Y2110187D02*
Y2110974D01*
G01Y2113337D02*
Y2114124D01*
G01Y2107037D02*
Y2107825D01*
G01Y2100738D02*
Y2101525D01*
G01Y2103888D02*
Y2104675D01*
G01X2336945Y2157431D02*
Y2158218D01*
G01Y2154281D02*
Y2155069D01*
G01Y2147982D02*
Y2148770D01*
G01Y2151132D02*
Y2151919D01*
G01Y2144833D02*
Y2145620D01*
G01Y2138533D02*
Y2139321D01*
G01Y2141683D02*
Y2142470D01*
G01Y2135384D02*
Y2136171D01*
G01Y2129085D02*
Y2129872D01*
G01Y2132234D02*
Y2133022D01*
G01Y2125935D02*
Y2126722D01*
G01Y2119636D02*
Y2120423D01*
G01Y2122785D02*
Y2123573D01*
G01Y2116486D02*
Y2117274D01*
G01Y2110187D02*
Y2110974D01*
G01Y2113337D02*
Y2114124D01*
G01Y2107037D02*
Y2107825D01*
G01Y2100738D02*
Y2101525D01*
G01Y2103888D02*
Y2104675D01*
G01X2336809Y2089616D02*
Y2088878D01*
G01X2335966Y2096171D02*
Y2093592D01*
G01X2335491Y2096171D02*
Y2090837D01*
G01X2360969Y2098271D02*
X2360882Y2097930D01*
G01X2359575Y2098100D02*
X2359663Y2098442D01*
G01Y2098953D02*
X2359750Y2099295D01*
G01X2361405Y2097844D02*
X2361492Y2098271D01*
G01X2359227Y2099380D02*
X2359140Y2098953D01*
G01X2357485Y2099295D02*
X2357398Y2098868D01*
G01X2359140Y2098442D02*
X2359053Y2098186D01*
G01X2357920Y2098953D02*
X2358007Y2099209D01*
G01X2359401Y2097759D02*
X2359575Y2098100D01*
G01X2359401Y2099721D02*
X2359227Y2099380D01*
G01X2361144Y2097418D02*
X2361405Y2097844D01*
G01X2357746Y2099636D02*
X2357485Y2099295D01*
G01X2359053Y2098186D02*
X2358879Y2097930D01*
G01X2359750Y2099295D02*
X2359924Y2099550D01*
G01X2360882Y2097930D02*
X2360621Y2097674D01*
G01X2359053Y2097418D02*
X2359401Y2097759D01*
G01X2359750Y2100062D02*
X2359401Y2099721D01*
G01X2358007Y2099209D02*
X2358182Y2099380D01*
G01X2358094Y2099892D02*
X2357746Y2099636D01*
G01X2360708Y2097162D02*
X2361144Y2097418D01*
G01X2353528Y2088637D02*
X2353815Y2088816D01*
X2354169Y2088878D01*
G01X2359924Y2099550D02*
X2360185Y2099721D01*
G01X2360098Y2100233D02*
X2359750Y2100062D01*
G01X2358182Y2099380D02*
X2358356Y2099465D01*
G01X2360621Y2097674D02*
X2360359Y2097588D01*
G01X2358879Y2097930D02*
X2358617Y2097844D01*
G01X2358356Y2099977D02*
X2358094Y2099892D01*
G01X2354937Y2160364D02*
G03X2355331Y2160758I0J394D01*
G01Y2158396D02*
G03X2354937Y2158789I-394J-1D01*
G01X2344277Y2161368D02*
X2336945D01*
G01X2356433D02*
X2344424D01*
G01X2352890Y2161151D02*
X2351905D01*
G01X2352890Y2160955D02*
X2351905D01*
G01X2344424Y2160581D02*
X2356433D01*
G01X2336945D02*
X2344277D01*
G01X2352890Y2160561D02*
X2351905D01*
G01X2347772Y2160364D02*
X2354937D01*
G01X2347772Y2158789D02*
X2354937D01*
G01X2352890Y2158592D02*
X2351905D01*
G01X2386130Y2158277D02*
X2366669D01*
G01X2344277Y2158218D02*
X2336945D01*
G01X2356433D02*
X2344424D01*
G01X2352890Y2158199D02*
X2351905D01*
G01X2352890Y2158002D02*
X2351905D01*
G01X2354491Y2160581D02*
Y2161368D01*
G01X2354464Y2160581D02*
Y2161368D01*
G01X2354088Y2160581D02*
Y2161368D01*
G01X2353874Y2160364D02*
Y2158789D01*
G01X2352890Y2161151D02*
Y2158002D01*
G01X2351905Y2161151D02*
Y2158002D01*
G01X2350921Y2160364D02*
Y2158789D01*
G01X2350726Y2161368D02*
Y2160581D01*
G01X2348743Y2161368D02*
Y2160581D01*
G01X2347772Y2160364D02*
Y2158789D01*
G01X2347091Y2160581D02*
Y2161368D01*
G01X2345363Y2160581D02*
Y2158218D01*
G01Y2163730D02*
Y2161368D01*
G01X2344424Y2160581D02*
Y2161368D01*
G01X2344277Y2160581D02*
Y2161368D01*
G01X2342685Y2160581D02*
Y2161368D01*
G01X2341743D02*
Y2160581D01*
G01X2338907Y2161368D02*
Y2160581D01*
G01X2338718D02*
Y2161368D01*
G01X2336945Y2160581D02*
Y2161368D01*
G01X2354937Y2205364D02*
G03X2355331Y2205758I0J394D01*
G01Y2203396D02*
G03X2354937Y2203789I-394J-1D01*
G01Y2225364D02*
G03X2355331Y2225758I0J394D01*
G01Y2223396D02*
G03X2354937Y2223789I-394J-1D01*
G01Y2215364D02*
G03X2355331Y2215758I0J394D01*
G01Y2213396D02*
G03X2354937Y2213789I-394J-1D01*
G01Y2220364D02*
G03X2355331Y2220758I0J394D01*
G01Y2218396D02*
G03X2354937Y2218789I-394J-1D01*
G01Y2175364D02*
G03X2355331Y2175758I0J394D01*
G01Y2173396D02*
G03X2354937Y2173789I-394J-1D01*
G01Y2165364D02*
G03X2355331Y2165758I0J394D01*
G01Y2163396D02*
G03X2354937Y2163789I-394J-1D01*
G01Y2185364D02*
G03X2355331Y2185758I0J394D01*
G01Y2183396D02*
G03X2354937Y2183789I-394J-1D01*
G01Y2190364D02*
G03X2355331Y2190758I0J394D01*
G01Y2188396D02*
G03X2354937Y2188789I-394J-1D01*
G01Y2200364D02*
G03X2355331Y2200758I0J394D01*
G01Y2198396D02*
G03X2354937Y2198789I-394J-1D01*
G01Y2195364D02*
G03X2355331Y2195758I0J394D01*
G01Y2193396D02*
G03X2354937Y2193789I-394J-1D01*
G01Y2180364D02*
G03X2355331Y2180758I0J394D01*
G01Y2178396D02*
G03X2354937Y2178789I-394J-1D01*
G01X2355331Y2229380D02*
X2364701D01*
G01X2387142Y2228789D02*
X2356433D01*
G01X2385173Y2228396D02*
X2366669D01*
G01X2365016Y2228199D02*
X2358480D01*
G01X2335173Y2227785D02*
X2355331D01*
G01Y2227608D02*
X2364701D01*
G01X2352890Y2226151D02*
X2351905D01*
G01X2351315Y2226033D02*
X2342330D01*
G01X2352890Y2225955D02*
X2351905D01*
G01X2352890Y2225561D02*
X2351905D01*
G01X2347772Y2225364D02*
X2354937D01*
G01X2344277Y2224360D02*
X2336945D01*
G01X2356433D02*
X2344424D01*
G01X2347772Y2223789D02*
X2354937D01*
G01X2352890Y2223592D02*
X2351905D01*
G01X2344424Y2223573D02*
X2356433D01*
G01X2336945D02*
X2344277D01*
G01X2352890Y2223199D02*
X2351905D01*
G01X2352890Y2223002D02*
X2351905D01*
G01X2344277Y2221211D02*
X2336945D01*
G01X2356433D02*
X2344424D01*
G01X2352890Y2221151D02*
X2351905D01*
G01X2352890Y2220955D02*
X2351905D01*
G01X2352890Y2220561D02*
X2351905D01*
G01X2344424Y2220423D02*
X2356433D01*
G01X2336945D02*
X2344277D01*
G01X2347772Y2220364D02*
X2354937D01*
G01X2347772Y2218789D02*
X2354937D01*
G01X2352890Y2218592D02*
X2351905D01*
G01X2352890Y2218199D02*
X2351905D01*
G01X2344277Y2218061D02*
X2336945D01*
G01X2356433D02*
X2344424D01*
G01X2352890Y2218002D02*
X2351905D01*
G01X2344424Y2217274D02*
X2356433D01*
G01X2336945D02*
X2344277D01*
G01X2352890Y2216151D02*
X2351905D01*
G01X2352890Y2215955D02*
X2351905D01*
G01X2352890Y2215561D02*
X2351905D01*
G01X2347772Y2215364D02*
X2354937D01*
G01X2344277Y2214911D02*
X2336945D01*
G01X2356433D02*
X2344424D01*
G01Y2214124D02*
X2356433D01*
G01X2336945D02*
X2344277D01*
G01X2347772Y2213789D02*
X2354937D01*
G01X2352890Y2213592D02*
X2351905D01*
G01X2352890Y2213199D02*
X2351905D01*
G01X2352890Y2213002D02*
X2351905D01*
G01X2356433Y2211781D02*
X2355331D01*
G01X2344277Y2211762D02*
X2336945D01*
G01X2356433D02*
X2344424D01*
G01X2354858Y2211151D02*
X2353874D01*
G01X2344424Y2210974D02*
X2356433D01*
G01X2336945D02*
X2344277D01*
G01X2354858Y2210955D02*
X2353874D01*
G01X2385173Y2210679D02*
X2358480D01*
G01X2354858Y2210561D02*
X2353874D01*
G01X2355331Y2210364D02*
X2349740D01*
G01X2355331Y2208789D02*
X2349740D01*
G01X2344277Y2208612D02*
X2336945D01*
G01X2356433D02*
X2344424D01*
G01X2354858Y2208592D02*
X2353874D01*
G01X2385173Y2208317D02*
X2358480D01*
G01X2354858Y2208199D02*
X2353874D01*
G01X2354858Y2208002D02*
X2353874D01*
G01X2344424Y2207825D02*
X2356433D01*
G01X2336945D02*
X2344277D01*
G01X2356433Y2207372D02*
X2355331D01*
G01X2352890Y2206151D02*
X2351905D01*
G01X2352890Y2205955D02*
X2351905D01*
G01X2352890Y2205561D02*
X2351905D01*
G01X2344277Y2205463D02*
X2336945D01*
G01X2356433D02*
X2344424D01*
G01X2347772Y2205364D02*
X2354937D01*
G01X2344424Y2204675D02*
X2356433D01*
G01X2336945D02*
X2344277D01*
G01X2347772Y2203789D02*
X2354937D01*
G01X2352890Y2203592D02*
X2351905D01*
G01X2352890Y2203199D02*
X2351905D01*
G01X2352890Y2203002D02*
X2351905D01*
G01X2344277Y2202313D02*
X2336945D01*
G01X2356433D02*
X2344424D01*
G01Y2201525D02*
X2356433D01*
G01X2336945D02*
X2344277D01*
G01X2352890Y2201151D02*
X2351905D01*
G01X2352890Y2200955D02*
X2351905D01*
G01X2352890Y2200561D02*
X2351905D01*
G01X2347772Y2200364D02*
X2354937D01*
G01X2344277Y2199163D02*
X2336945D01*
G01X2356433D02*
X2344424D01*
G01X2347772Y2198789D02*
X2354937D01*
G01X2352890Y2198592D02*
X2351905D01*
G01X2344424Y2198376D02*
X2356433D01*
G01X2336945D02*
X2344277D01*
G01X2352890Y2198199D02*
X2351905D01*
G01X2352890Y2198002D02*
X2351905D01*
G01X2352890Y2196151D02*
X2351905D01*
G01X2344277Y2196014D02*
X2336945D01*
G01X2356433D02*
X2344424D01*
G01X2352890Y2195955D02*
X2351905D01*
G01X2352890Y2195561D02*
X2351905D01*
G01X2347772Y2195364D02*
X2354937D01*
G01X2344424Y2195226D02*
X2356433D01*
G01X2336945D02*
X2344277D01*
G01X2347772Y2193789D02*
X2354937D01*
G01X2352890Y2193592D02*
X2351905D01*
G01X2352890Y2193199D02*
X2351905D01*
G01X2352890Y2193002D02*
X2351905D01*
G01X2344277Y2192864D02*
X2336945D01*
G01X2356433D02*
X2344424D01*
G01Y2192077D02*
X2356433D01*
G01X2336945D02*
X2344277D01*
G01X2385173Y2191781D02*
X2358480D01*
G01X2352890Y2191151D02*
X2351905D01*
G01X2352890Y2190955D02*
X2351905D01*
G01X2352890Y2190561D02*
X2351905D01*
G01X2347772Y2190364D02*
X2354937D01*
G01X2344277Y2189714D02*
X2336945D01*
G01X2356433D02*
X2344424D01*
G01X2385173Y2189419D02*
X2358480D01*
G01X2344424Y2188927D02*
X2356433D01*
G01X2336945D02*
X2344277D01*
G01X2347772Y2188789D02*
X2354937D01*
G01X2352890Y2188592D02*
X2351905D01*
G01X2352890Y2188199D02*
X2351905D01*
G01X2352890Y2188002D02*
X2351905D01*
G01X2344277Y2186565D02*
X2336945D01*
G01X2356433D02*
X2344424D01*
G01X2352890Y2186151D02*
X2351905D01*
G01X2352890Y2185955D02*
X2351905D01*
G01X2344424Y2185777D02*
X2356433D01*
G01X2336945D02*
X2344277D01*
G01X2352890Y2185561D02*
X2351905D01*
G01X2347772Y2185364D02*
X2354937D01*
G01X2347772Y2183789D02*
X2354937D01*
G01X2352890Y2183592D02*
X2351905D01*
G01X2344277Y2183415D02*
X2336945D01*
G01X2356433D02*
X2344424D01*
G01X2352890Y2183199D02*
X2351905D01*
G01X2352890Y2183002D02*
X2351905D01*
G01X2344424Y2182628D02*
X2356433D01*
G01X2336945D02*
X2344277D01*
G01X2352890Y2181151D02*
X2351905D01*
G01X2352890Y2180955D02*
X2351905D01*
G01X2352890Y2180561D02*
X2351905D01*
G01X2347772Y2180364D02*
X2354937D01*
G01X2344277Y2180266D02*
X2336945D01*
G01X2356433D02*
X2344424D01*
G01Y2179478D02*
X2356433D01*
G01X2336945D02*
X2344277D01*
G01X2347772Y2178789D02*
X2354937D01*
G01X2352890Y2178592D02*
X2351905D01*
G01X2352890Y2178199D02*
X2351905D01*
G01X2352890Y2178002D02*
X2351905D01*
G01X2344277Y2177116D02*
X2336945D01*
G01X2356433D02*
X2344424D01*
G01Y2176329D02*
X2356433D01*
G01X2336945D02*
X2344277D01*
G01X2352890Y2176151D02*
X2351905D01*
G01X2352890Y2175955D02*
X2351905D01*
G01X2352890Y2175561D02*
X2351905D01*
G01X2347772Y2175364D02*
X2354937D01*
G01X2344277Y2173966D02*
X2336945D01*
G01X2356433D02*
X2344424D01*
G01X2347772Y2173789D02*
X2354937D01*
G01X2352890Y2173592D02*
X2351905D01*
G01X2352890Y2173199D02*
X2351905D01*
G01X2344424Y2173179D02*
X2356433D01*
G01X2336945D02*
X2344277D01*
G01X2352890Y2173002D02*
X2351905D01*
G01X2385173Y2172884D02*
X2358480D01*
G01X2355331Y2171781D02*
X2356433D01*
G01X2354858Y2171151D02*
X2353874D01*
G01X2354858Y2170955D02*
X2353874D01*
G01X2344277Y2170817D02*
X2336945D01*
G01X2356433D02*
X2344424D01*
G01X2354858Y2170561D02*
X2353874D01*
G01X2385173Y2170522D02*
X2358480D01*
G01X2355331Y2170364D02*
X2349740D01*
G01X2344424Y2170029D02*
X2356433D01*
G01X2336945D02*
X2344277D01*
G01X2355331Y2168789D02*
X2349740D01*
G01X2354858Y2168592D02*
X2353874D01*
G01X2354858Y2168199D02*
X2353874D01*
G01X2354858Y2168002D02*
X2353874D01*
G01X2344277Y2167667D02*
X2336945D01*
G01X2356433D02*
X2344424D01*
G01X2356433Y2167372D02*
X2355331D01*
G01X2344424Y2166880D02*
X2356433D01*
G01X2336945D02*
X2344277D01*
G01X2352890Y2166151D02*
X2351905D01*
G01X2352890Y2165955D02*
X2351905D01*
G01X2352890Y2165561D02*
X2351905D01*
G01X2347772Y2165364D02*
X2354937D01*
G01X2344277Y2164518D02*
X2336945D01*
G01X2356433D02*
X2344424D01*
G01X2347772Y2163789D02*
X2354937D01*
G01X2344424Y2163730D02*
X2356433D01*
G01X2336945D02*
X2344277D01*
G01X2352890Y2163592D02*
X2351905D01*
G01X2352890Y2163199D02*
X2351905D01*
G01X2352890Y2163002D02*
X2351905D01*
G01X2365016Y2228199D02*
Y2254596D01*
G01X2364701Y2229380D02*
Y2227608D01*
G01X2360449Y2210679D02*
Y2228199D01*
G01Y2191781D02*
Y2208317D01*
G01Y2172884D02*
Y2189419D01*
G01X2354858Y2171151D02*
Y2168002D01*
G01Y2211151D02*
Y2208002D01*
G01X2354491Y2223573D02*
Y2224360D01*
G01Y2217274D02*
Y2218061D01*
G01Y2220423D02*
Y2221211D01*
G01Y2214124D02*
Y2214911D01*
G01Y2207825D02*
Y2208612D01*
G01Y2210974D02*
Y2211762D01*
G01Y2204675D02*
Y2205463D01*
G01Y2198376D02*
Y2199163D01*
G01Y2201525D02*
Y2202313D01*
G01Y2195226D02*
Y2196014D01*
G01Y2188927D02*
Y2189714D01*
G01Y2192077D02*
Y2192864D01*
G01Y2185777D02*
Y2186565D01*
G01Y2179478D02*
Y2180266D01*
G01Y2182628D02*
Y2183415D01*
G01Y2176329D02*
Y2177116D01*
G01Y2173179D02*
Y2173966D01*
G01Y2166880D02*
Y2167667D01*
G01Y2170029D02*
Y2170817D01*
G01Y2163730D02*
Y2164518D01*
G01X2354464Y2223573D02*
Y2224360D01*
G01Y2217274D02*
Y2218061D01*
G01Y2220423D02*
Y2221211D01*
G01Y2214124D02*
Y2214911D01*
G01Y2207825D02*
Y2208612D01*
G01Y2210974D02*
Y2211762D01*
G01Y2204675D02*
Y2205463D01*
G01Y2198376D02*
Y2199163D01*
G01Y2201525D02*
Y2202313D01*
G01Y2195226D02*
Y2196014D01*
G01Y2188927D02*
Y2189714D01*
G01Y2192077D02*
Y2192864D01*
G01Y2185777D02*
Y2186565D01*
G01Y2179478D02*
Y2180266D01*
G01Y2182628D02*
Y2183415D01*
G01Y2176329D02*
Y2177116D01*
G01Y2173179D02*
Y2173966D01*
G01Y2166880D02*
Y2167667D01*
G01Y2170029D02*
Y2170817D01*
G01Y2163730D02*
Y2164518D01*
G01X2354088Y2223573D02*
Y2224360D01*
G01Y2217274D02*
Y2218061D01*
G01Y2220423D02*
Y2221211D01*
G01Y2214124D02*
Y2214911D01*
G01Y2207825D02*
Y2208612D01*
G01Y2210974D02*
Y2211762D01*
G01Y2204675D02*
Y2205463D01*
G01Y2198376D02*
Y2199163D01*
G01Y2201525D02*
Y2202313D01*
G01Y2195226D02*
Y2196014D01*
G01Y2188927D02*
Y2189714D01*
G01Y2192077D02*
Y2192864D01*
G01Y2185777D02*
Y2186565D01*
G01Y2179478D02*
Y2180266D01*
G01Y2182628D02*
Y2183415D01*
G01Y2176329D02*
Y2177116D01*
G01Y2173179D02*
Y2173966D01*
G01Y2166880D02*
Y2167667D01*
G01Y2170029D02*
Y2170817D01*
G01Y2163730D02*
Y2164518D01*
G01X2353874Y2165364D02*
Y2163789D01*
G01Y2175364D02*
Y2173789D01*
G01Y2171151D02*
Y2168002D01*
G01Y2180364D02*
Y2178789D01*
G01Y2185364D02*
Y2183789D01*
G01Y2190364D02*
Y2188789D01*
G01Y2195364D02*
Y2193789D01*
G01Y2200364D02*
Y2198789D01*
G01Y2205364D02*
Y2203789D01*
G01Y2211151D02*
Y2208002D01*
G01Y2215364D02*
Y2213789D01*
G01Y2220364D02*
Y2218789D01*
G01Y2225364D02*
Y2223789D01*
G01X2352890Y2166151D02*
Y2163002D01*
G01Y2170364D02*
Y2168789D01*
G01Y2176151D02*
Y2173002D01*
G01Y2181151D02*
Y2178002D01*
G01Y2186151D02*
Y2183002D01*
G01Y2191151D02*
Y2188002D01*
G01Y2196151D02*
Y2193002D01*
G01Y2201151D02*
Y2198002D01*
G01Y2206151D02*
Y2203002D01*
G01Y2210364D02*
Y2208789D01*
G01Y2216151D02*
Y2213002D01*
G01Y2221151D02*
Y2218002D01*
G01Y2226151D02*
Y2223002D01*
G01X2351905Y2166151D02*
Y2163002D01*
G01Y2176151D02*
Y2173002D01*
G01Y2181151D02*
Y2178002D01*
G01Y2186151D02*
Y2183002D01*
G01Y2191151D02*
Y2188002D01*
G01Y2196151D02*
Y2193002D01*
G01Y2201151D02*
Y2198002D01*
G01Y2206151D02*
Y2203002D01*
G01Y2216151D02*
Y2213002D01*
G01Y2221151D02*
Y2218002D01*
G01Y2226151D02*
Y2223002D01*
G01X2350921Y2165364D02*
Y2163789D01*
G01Y2175364D02*
Y2173789D01*
G01Y2180364D02*
Y2178789D01*
G01Y2185364D02*
Y2183789D01*
G01Y2190364D02*
Y2188789D01*
G01Y2195364D02*
Y2193789D01*
G01Y2200364D02*
Y2198789D01*
G01Y2205364D02*
Y2203789D01*
G01Y2215364D02*
Y2213789D01*
G01Y2220364D02*
Y2218789D01*
G01Y2225364D02*
Y2223789D01*
G01X2350726Y2164518D02*
Y2163730D01*
G01Y2167667D02*
Y2166880D01*
G01Y2170817D02*
Y2170029D01*
G01Y2173966D02*
Y2173179D01*
G01Y2177116D02*
Y2176329D01*
G01Y2180266D02*
Y2179478D01*
G01Y2183415D02*
Y2182628D01*
G01Y2186565D02*
Y2185777D01*
G01Y2189714D02*
Y2188927D01*
G01Y2192864D02*
Y2192077D01*
G01Y2196014D02*
Y2195226D01*
G01Y2199163D02*
Y2198376D01*
G01Y2202313D02*
Y2201525D01*
G01Y2205463D02*
Y2204675D01*
G01Y2208612D02*
Y2207825D01*
G01Y2211762D02*
Y2210974D01*
G01Y2214911D02*
Y2214124D01*
G01Y2218061D02*
Y2217274D01*
G01Y2221211D02*
Y2220423D01*
G01Y2224360D02*
Y2223573D01*
G01X2349740Y2170364D02*
Y2168789D01*
G01Y2210364D02*
Y2208789D01*
G01X2348743Y2164518D02*
Y2163730D01*
G01Y2167667D02*
Y2166880D01*
G01Y2170817D02*
Y2170029D01*
G01Y2173966D02*
Y2173179D01*
G01Y2177116D02*
Y2176329D01*
G01Y2180266D02*
Y2179478D01*
G01Y2183415D02*
Y2182628D01*
G01Y2186565D02*
Y2185777D01*
G01Y2189714D02*
Y2188927D01*
G01Y2192864D02*
Y2192077D01*
G01Y2196014D02*
Y2195226D01*
G01Y2199163D02*
Y2198376D01*
G01Y2202313D02*
Y2201525D01*
G01Y2205463D02*
Y2204675D01*
G01Y2208612D02*
Y2207825D01*
G01Y2211762D02*
Y2210974D01*
G01Y2214911D02*
Y2214124D01*
G01Y2218061D02*
Y2217274D01*
G01Y2221211D02*
Y2220423D01*
G01Y2224360D02*
Y2223573D01*
G01X2347772Y2165364D02*
Y2163789D01*
G01Y2175364D02*
Y2173789D01*
G01Y2180364D02*
Y2178789D01*
G01Y2185364D02*
Y2183789D01*
G01Y2190364D02*
Y2188789D01*
G01Y2195364D02*
Y2193789D01*
G01Y2200364D02*
Y2198789D01*
G01Y2205364D02*
Y2203789D01*
G01Y2215364D02*
Y2213789D01*
G01Y2220364D02*
Y2218789D01*
G01Y2225364D02*
Y2223789D01*
G01X2347091Y2223573D02*
Y2224360D01*
G01Y2217274D02*
Y2218061D01*
G01Y2220423D02*
Y2221211D01*
G01Y2214124D02*
Y2214911D01*
G01Y2207825D02*
Y2208612D01*
G01Y2210974D02*
Y2211762D01*
G01Y2204675D02*
Y2205463D01*
G01Y2198376D02*
Y2199163D01*
G01Y2201525D02*
Y2202313D01*
G01Y2195226D02*
Y2196014D01*
G01Y2188927D02*
Y2189714D01*
G01Y2192077D02*
Y2192864D01*
G01Y2185777D02*
Y2186565D01*
G01Y2179478D02*
Y2180266D01*
G01Y2182628D02*
Y2183415D01*
G01Y2176329D02*
Y2177116D01*
G01Y2173179D02*
Y2173966D01*
G01Y2166880D02*
Y2167667D01*
G01Y2170029D02*
Y2170817D01*
G01Y2163730D02*
Y2164518D01*
G01X2345363Y2166880D02*
Y2164518D01*
G01Y2170029D02*
Y2167667D01*
G01Y2173179D02*
Y2170817D01*
G01Y2176329D02*
Y2173966D01*
G01Y2179478D02*
Y2177116D01*
G01Y2182628D02*
Y2180266D01*
G01Y2185777D02*
Y2183415D01*
G01Y2188927D02*
Y2186565D01*
G01Y2192077D02*
Y2189714D01*
G01Y2195226D02*
Y2192864D01*
G01Y2198376D02*
Y2196014D01*
G01Y2201525D02*
Y2199163D01*
G01Y2204675D02*
Y2202313D01*
G01Y2207825D02*
Y2205463D01*
G01Y2210974D02*
Y2208612D01*
G01Y2214124D02*
Y2211762D01*
G01Y2217274D02*
Y2214911D01*
G01Y2220423D02*
Y2218061D01*
G01Y2223573D02*
Y2221211D01*
G01Y2226033D02*
Y2224360D01*
G01X2344424Y2223573D02*
Y2224360D01*
G01Y2217274D02*
Y2218061D01*
G01Y2220423D02*
Y2221211D01*
G01Y2214124D02*
Y2214911D01*
G01Y2207825D02*
Y2208612D01*
G01Y2210974D02*
Y2211762D01*
G01Y2204675D02*
Y2205463D01*
G01Y2198376D02*
Y2199163D01*
G01Y2201525D02*
Y2202313D01*
G01Y2195226D02*
Y2196014D01*
G01Y2188927D02*
Y2189714D01*
G01Y2192077D02*
Y2192864D01*
G01Y2185777D02*
Y2186565D01*
G01Y2179478D02*
Y2180266D01*
G01Y2182628D02*
Y2183415D01*
G01Y2176329D02*
Y2177116D01*
G01Y2173179D02*
Y2173966D01*
G01Y2166880D02*
Y2167667D01*
G01Y2170029D02*
Y2170817D01*
G01Y2163730D02*
Y2164518D01*
G01X2344277Y2223573D02*
Y2224360D01*
G01Y2217274D02*
Y2218061D01*
G01Y2220423D02*
Y2221211D01*
G01Y2214124D02*
Y2214911D01*
G01Y2207825D02*
Y2208612D01*
G01Y2210974D02*
Y2211762D01*
G01Y2204675D02*
Y2205463D01*
G01Y2198376D02*
Y2199163D01*
G01Y2201525D02*
Y2202313D01*
G01Y2195226D02*
Y2196014D01*
G01Y2188927D02*
Y2189714D01*
G01Y2192077D02*
Y2192864D01*
G01Y2185777D02*
Y2186565D01*
G01Y2179478D02*
Y2180266D01*
G01Y2182628D02*
Y2183415D01*
G01Y2176329D02*
Y2177116D01*
G01Y2173179D02*
Y2173966D01*
G01Y2166880D02*
Y2167667D01*
G01Y2170029D02*
Y2170817D01*
G01Y2163730D02*
Y2164518D01*
G01X2342685Y2223573D02*
Y2224360D01*
G01Y2217274D02*
Y2218061D01*
G01Y2220423D02*
Y2221211D01*
G01Y2214124D02*
Y2214911D01*
G01Y2207825D02*
Y2208612D01*
G01Y2210974D02*
Y2211762D01*
G01Y2204675D02*
Y2205463D01*
G01Y2198376D02*
Y2199163D01*
G01Y2201525D02*
Y2202313D01*
G01Y2195226D02*
Y2196014D01*
G01Y2188927D02*
Y2189714D01*
G01Y2192077D02*
Y2192864D01*
G01Y2185777D02*
Y2186565D01*
G01Y2179478D02*
Y2180266D01*
G01Y2182628D02*
Y2183415D01*
G01Y2176329D02*
Y2177116D01*
G01Y2173179D02*
Y2173966D01*
G01Y2166880D02*
Y2167667D01*
G01Y2170029D02*
Y2170817D01*
G01Y2163730D02*
Y2164518D01*
G01X2341743D02*
Y2163730D01*
G01Y2167667D02*
Y2166880D01*
G01Y2170817D02*
Y2170029D01*
G01Y2173966D02*
Y2173179D01*
G01Y2177116D02*
Y2176329D01*
G01Y2180266D02*
Y2179478D01*
G01Y2183415D02*
Y2182628D01*
G01Y2186565D02*
Y2185777D01*
G01Y2189714D02*
Y2188927D01*
G01Y2192864D02*
Y2192077D01*
G01Y2196014D02*
Y2195226D01*
G01Y2199163D02*
Y2198376D01*
G01Y2202313D02*
Y2201525D01*
G01Y2205463D02*
Y2204675D01*
G01Y2208612D02*
Y2207825D01*
G01Y2211762D02*
Y2210974D01*
G01Y2214911D02*
Y2214124D01*
G01Y2218061D02*
Y2217274D01*
G01Y2221211D02*
Y2220423D01*
G01Y2224360D02*
Y2223573D01*
G01X2338907Y2164518D02*
Y2163730D01*
G01Y2167667D02*
Y2166880D01*
G01Y2170817D02*
Y2170029D01*
G01Y2173966D02*
Y2173179D01*
G01Y2177116D02*
Y2176329D01*
G01Y2180266D02*
Y2179478D01*
G01Y2183415D02*
Y2182628D01*
G01Y2186565D02*
Y2185777D01*
G01Y2189714D02*
Y2188927D01*
G01Y2192864D02*
Y2192077D01*
G01Y2196014D02*
Y2195226D01*
G01Y2199163D02*
Y2198376D01*
G01Y2202313D02*
Y2201525D01*
G01Y2205463D02*
Y2204675D01*
G01Y2208612D02*
Y2207825D01*
G01Y2211762D02*
Y2210974D01*
G01Y2214911D02*
Y2214124D01*
G01Y2218061D02*
Y2217274D01*
G01Y2221211D02*
Y2220423D01*
G01Y2224360D02*
Y2223573D01*
G01X2338718D02*
Y2224360D01*
G01Y2217274D02*
Y2218061D01*
G01Y2220423D02*
Y2221211D01*
G01Y2214124D02*
Y2214911D01*
G01Y2207825D02*
Y2208612D01*
G01Y2210974D02*
Y2211762D01*
G01Y2204675D02*
Y2205463D01*
G01Y2198376D02*
Y2199163D01*
G01Y2201525D02*
Y2202313D01*
G01Y2195226D02*
Y2196014D01*
G01Y2188927D02*
Y2189714D01*
G01Y2192077D02*
Y2192864D01*
G01Y2185777D02*
Y2186565D01*
G01Y2179478D02*
Y2180266D01*
G01Y2182628D02*
Y2183415D01*
G01Y2176329D02*
Y2177116D01*
G01Y2173179D02*
Y2173966D01*
G01Y2166880D02*
Y2167667D01*
G01Y2170029D02*
Y2170817D01*
G01Y2163730D02*
Y2164518D01*
G01X2336945Y2223573D02*
Y2224360D01*
G01Y2217274D02*
Y2218061D01*
G01Y2220423D02*
Y2221211D01*
G01Y2214124D02*
Y2214911D01*
G01Y2207825D02*
Y2208612D01*
G01Y2210974D02*
Y2211762D01*
G01Y2204675D02*
Y2205463D01*
G01Y2198376D02*
Y2199163D01*
G01Y2201525D02*
Y2202313D01*
G01Y2195226D02*
Y2196014D01*
G01Y2188927D02*
Y2189714D01*
G01Y2192077D02*
Y2192864D01*
G01Y2185777D02*
Y2186565D01*
G01Y2179478D02*
Y2180266D01*
G01Y2182628D02*
Y2183415D01*
G01Y2176329D02*
Y2177116D01*
G01Y2173179D02*
Y2173966D01*
G01Y2166880D02*
Y2167667D01*
G01Y2170029D02*
Y2170817D01*
G01Y2163730D02*
Y2164518D01*
G01X2335966Y2230561D02*
Y2227785D01*
G01X2335491Y2233317D02*
Y2227785D01*
G01X2335173Y2241663D02*
Y2227785D01*
G01X2345620Y2239596D02*
G03Y2234163I1955J-2717D01*
G01X2349529D02*
G03Y2239596I-1954J2716D01*
G01X2351079Y2236880D02*
G03I-3504J0D01*
G01X2349878Y2232982D02*
G03Y2240777I-2304J3897D01*
G01X2345271D02*
G03Y2232982I2304J-3898D01*
G01X2349529Y2234163D02*
X2345620D01*
G01X2358795Y2233947D02*
X2335173D01*
G01X2385173Y2233317D02*
X2335173D01*
G01X2345271Y2232982D02*
X2349878D01*
G01X2335173Y2231545D02*
X2358795D01*
G01X2350333Y2231014D02*
X2356433D01*
G01X2350333Y2230955D02*
X2356433D01*
G01X2335966Y2230561D02*
X2356433D01*
G01X2349529Y2234163D02*
X2349547Y2234107D01*
X2349599Y2233942D01*
X2349678Y2233683D01*
X2349774Y2233356D01*
X2349878Y2232982D01*
G01X2362732Y2241663D02*
Y2233317D01*
G01X2358795Y2233947D02*
Y2231545D01*
G01X2352890Y2233317D02*
Y2231014D01*
G01X2350333D02*
Y2230955D01*
G01X2349694Y2230561D02*
Y2233317D01*
G01X2341820Y2230561D02*
Y2233317D01*
G01X2345620Y2234163D02*
X2345603Y2234107D01*
X2345550Y2233942D01*
X2345472Y2233684D01*
X2345376Y2233357D01*
X2345271Y2232982D01*
G01X2350333Y2230955D02*
X2350078Y2230561D01*
G01X2358121Y2237737D02*
G03X2359551I715J0D01*
G01X2355231D02*
G03X2356661I715J0D01*
G01X2358992Y2247116D02*
G03Y2250266I0J1575D01*
G01X2354132Y2236661D02*
G03X2356768Y2236806I1248J1352D01*
G01D02*
G03X2359549Y2236811I1388J1207D01*
G01X2353838Y2237332D02*
G03X2354132Y2236661I914J0D01*
G01X2354661Y2250266D02*
G03Y2247116I0J-1575D01*
G01X2350159Y2239152D02*
G03Y2237468I2236J-842D01*
G01X2351632Y2239153D02*
G03X2350159I-736J-278D01*
G01Y2237468D02*
G03X2351632I737J277D01*
G01X2352904Y2239487D02*
G03X2352383Y2240053I-1352J-722D01*
G01X2349337Y2240051D02*
G03X2348816Y2239486I830J-1288D01*
G01X2348817Y2237173D02*
G03X2349338Y2236608I1351J723D01*
G01X2352384Y2236609D02*
G03X2352905Y2237174I-830J1288D01*
G01X2351632Y2237468D02*
G03Y2239152I-2237J842D01*
G01X2352905Y2237174D02*
G03X2352904Y2239487I-2163J1156D01*
G01X2348816Y2239486D02*
G03X2348817Y2237173I2163J-1156D01*
G01X2352383Y2240053D02*
G03X2349337Y2240051I-1521J-2363D01*
G01X2349338Y2236608D02*
G03X2352384I1523J2362D01*
G01X2349740Y2236880D02*
G03I-2165J0D01*
G01X2343658Y2239470D02*
G03X2343068Y2239105I-9J-645D01*
G01X2344432Y2238662D02*
G03X2343658Y2239470I-791J17D01*
G01X2342407Y2240175D02*
G03X2341564Y2239106I704J-1422D01*
G01X2341772Y2237219D02*
G03X2343007Y2236246I1735J931D01*
G01X2344649Y2236290D02*
G03X2345814Y2237428I-728J1911D01*
G01X2345727Y2239444D02*
G03X2343989Y2240461I-1806J-1093D01*
G01X2343007Y2236246D02*
G03X2344649Y2236290I755J2475D01*
G01X2345988Y2238584D02*
G03X2345726Y2239447I-2971J-431D01*
G01X2341433Y2238662D02*
G03X2341772Y2237219I3015J-53D01*
G01X2345988Y2238089D02*
G03Y2238586I-3524J249D01*
G01X2345814Y2237428D02*
G03X2345988Y2238089I-4018J1411D01*
G01X2343007Y2237837D02*
G03X2344432I712J-83D01*
G01X2343992Y2240461D02*
G03X2342407Y2240175I-264J-3073D01*
G01X2365016Y2254596D02*
X2348638D01*
G01X2354661Y2250266D02*
X2358992D01*
G01X2354036Y2249478D02*
X2359617D01*
G01Y2247903D02*
X2354036D01*
G01X2358992Y2247116D02*
X2354661D01*
G01X2365016Y2244419D02*
X2348638D01*
G01X2335173Y2241663D02*
X2389110D01*
G01X2349878Y2240777D02*
X2345271D01*
G01X2389110Y2240482D02*
X2362732D01*
G01X2338463Y2240262D02*
X2336914D01*
G01X2341407D02*
X2339999D01*
G01X2348039D02*
X2346579D01*
G01X2355231D02*
X2353838D01*
G01X2358121D02*
X2356661D01*
G01X2360992D02*
X2359551D01*
G01X2358795Y2239695D02*
X2335173D01*
G01X2345620Y2239596D02*
X2349529D01*
G01X2343067Y2239106D02*
X2341564D01*
G01X2344433Y2238662D02*
X2341433D01*
G01X2344432Y2237837D02*
X2343007D01*
G01X2338322Y2236255D02*
X2336940D01*
G01X2341233D02*
X2339617D01*
G01X2360992D02*
X2359549D01*
G01X2358795Y2235915D02*
X2335173D01*
G01X2348039Y2234508D02*
X2346579D01*
G01X2338463Y2240262D02*
X2339208Y2238984D01*
G01X2336914Y2240262D02*
X2338235Y2238106D01*
G01X2339011Y2237241D02*
X2339617Y2236255D01*
G01X2339965Y2238115D02*
X2341233Y2236255D01*
G01X2345620Y2239596D02*
X2345602Y2239652D01*
X2345550Y2239818D01*
X2345471Y2240076D01*
X2345376Y2240404D01*
X2345271Y2240777D01*
G01X2360992Y2240262D02*
Y2236255D01*
G01X2359617Y2247903D02*
Y2249478D01*
G01X2359583D02*
Y2247903D01*
G01X2359558Y2249478D02*
Y2247903D01*
G01X2359551Y2237737D02*
Y2240262D01*
G01X2359549Y2236811D02*
Y2236255D01*
G01X2358795Y2239695D02*
Y2235915D01*
G01X2358235Y2247903D02*
Y2249478D01*
G01X2358121Y2240262D02*
Y2237737D01*
G01X2357865Y2249478D02*
Y2247903D01*
G01X2356661Y2237737D02*
Y2240262D01*
G01X2355788Y2247903D02*
Y2249478D01*
G01X2355418D02*
Y2247903D01*
G01X2355231Y2240262D02*
Y2237737D01*
G01X2354095Y2247903D02*
Y2249478D01*
G01X2354071Y2247903D02*
Y2249478D01*
G01X2354036D02*
Y2247903D01*
G01X2353838Y2240262D02*
Y2237332D01*
G01X2348638Y2254596D02*
Y2241663D01*
G01X2348039Y2240262D02*
Y2234508D01*
G01X2346579Y2240262D02*
Y2234508D01*
G01X2349878Y2240777D02*
X2349775Y2240408D01*
X2349679Y2240079D01*
X2349599Y2239817D01*
X2349546Y2239651D01*
X2349529Y2239596D01*
G01X2339999Y2240262D02*
X2339208Y2238984D01*
G01X2338235Y2238106D02*
X2336940Y2236255D01*
G01X2339011Y2237241D02*
X2338322Y2236255D01*
G01X2341407Y2240262D02*
X2339965Y2238115D01*
G01X2373007Y-172119D02*
Y-191056D01*
G01X2367292Y307746D02*
X2575488D01*
G01X2377132Y483317D02*
X2376706Y482726D01*
G01X2382877Y481742D02*
X2383017Y481938D01*
X2383155Y482135D01*
X2383292Y482333D01*
G01X2377549Y482726D02*
X2377822Y483317D01*
G01X2378674Y482726D02*
X2378752Y483317D01*
G01X2378234Y482431D02*
X2378244Y482529D01*
X2378272Y482601D01*
X2378310Y482628D01*
G01X2387142Y468789D02*
Y611270D01*
G01X2386020Y606742D02*
Y473317D01*
G01X2385961Y503927D02*
Y472923D01*
G01X2385173Y473711D02*
Y606348D01*
G01X2383292Y482726D02*
Y482333D01*
G01X2383155Y482037D02*
Y482431D01*
G01X2378674Y482726D02*
Y482333D01*
G01X2378234Y482037D02*
Y482431D01*
G01X2377721D02*
Y482037D01*
G01X2377549Y482333D02*
Y482726D01*
G01X2376706Y482333D02*
Y482726D01*
G01X2376543Y482431D02*
Y482037D01*
G01X2377721D02*
X2377723Y481999D01*
X2377731Y481962D01*
X2377744Y481928D01*
X2377761Y481898D01*
X2377782Y481874D01*
X2377806Y481856D01*
X2377832Y481844D01*
X2377859Y481840D01*
G01X2378674Y482333D02*
X2378752Y481742D01*
G01X2383155Y482431D02*
X2383123Y482528D01*
X2383035Y482600D01*
X2382908Y482628D01*
G01X2377822Y481742D02*
X2377549Y482333D01*
G01X2383292Y482726D02*
X2383155Y482924D01*
X2383017Y483121D01*
X2382877Y483317D01*
G01X2377132Y481742D02*
X2376706Y482333D01*
G01X2378310Y481840D02*
X2378272Y481867D01*
X2378244Y481939D01*
X2378234Y482037D01*
G01X2382877Y483317D02*
X2377132D01*
G01X2376706Y482726D02*
X2383292D01*
G01X2382908Y482628D02*
X2376823D01*
G01X2376543Y482431D02*
X2383155D01*
G01X2376706Y482333D02*
X2383292D01*
G01X2383155Y482037D02*
X2376543D01*
G01X2382908Y481840D02*
X2376823D01*
G01X2382877Y481742D02*
X2377132D01*
G01X2377859Y482628D02*
X2377832Y482624D01*
X2377806Y482613D01*
X2377782Y482595D01*
X2377761Y482570D01*
X2377744Y482541D01*
X2377731Y482507D01*
X2377723Y482470D01*
X2377721Y482431D01*
G01X2382908Y481840D02*
X2383035Y481868D01*
X2383124Y481941D01*
X2383155Y482037D01*
G01X2378310Y479478D02*
X2378272Y479452D01*
X2378244Y479380D01*
X2378234Y479281D01*
G01X2387142Y470758D02*
X2385173Y468789D01*
G01X2377132Y478317D02*
X2376706Y477726D01*
G01X2382877Y476742D02*
X2383017Y476938D01*
X2383155Y477135D01*
X2383292Y477333D01*
G01X2377549Y477726D02*
X2377822Y478317D01*
G01X2378674Y477726D02*
X2378752Y478317D01*
G01X2383292Y477726D02*
Y477333D01*
G01X2383155Y478888D02*
Y479281D01*
G01X2378674Y477726D02*
Y477333D01*
G01X2378234Y478888D02*
Y479281D01*
G01X2377721D02*
Y478888D01*
G01X2377549Y477333D02*
Y477726D01*
G01X2376706Y477333D02*
Y477726D01*
G01X2376543Y479281D02*
Y478888D01*
G01X2377721D02*
X2377723Y478849D01*
X2377731Y478813D01*
X2377744Y478779D01*
X2377761Y478749D01*
X2377782Y478724D01*
X2377806Y478706D01*
X2377832Y478695D01*
X2377859Y478691D01*
G01X2378674Y477333D02*
X2378752Y476742D01*
G01X2383155Y479281D02*
X2383123Y479378D01*
X2383035Y479451D01*
X2382908Y479478D01*
G01X2377822Y476742D02*
X2377549Y477333D01*
G01X2383292Y477726D02*
X2383155Y477924D01*
X2383017Y478121D01*
X2382877Y478317D01*
G01X2377132Y476742D02*
X2376706Y477333D01*
G01X2387142Y471742D02*
X2385173Y473711D01*
G01X2378310Y478691D02*
X2378272Y478717D01*
X2378244Y478789D01*
X2378234Y478888D01*
G01X2382908Y479478D02*
X2376823D01*
G01X2376543Y479281D02*
X2383155D01*
G01Y478888D02*
X2376543D01*
G01X2382908Y478691D02*
X2376823D01*
G01X2382877Y478317D02*
X2377132D01*
G01X2376706Y477726D02*
X2383292D01*
G01X2376706Y477333D02*
X2383292D01*
G01X2382877Y476742D02*
X2377132D01*
G01X2390425Y468789D02*
X2387142D01*
G01X2377859Y479478D02*
X2377832Y479475D01*
X2377806Y479463D01*
X2377782Y479445D01*
X2377761Y479421D01*
X2377744Y479391D01*
X2377731Y479357D01*
X2377723Y479320D01*
X2377721Y479281D01*
G01X2382908Y478691D02*
X2383035Y478719D01*
X2383124Y478791D01*
X2383155Y478888D01*
G01X2367292Y438179D02*
X2575488D01*
G01X2439504Y423209D02*
G03X2471000I15748J0D01*
G01X2439504D02*
G03X2471000I15748J0D01*
G01X2439504D02*
G03X2471000I15748J0D01*
G01Y436988D02*
G03X2439504I-15748J0D01*
G01X2471000D02*
G03X2439504I-15748J0D01*
G01X2471000D02*
G03X2439504I-15748J0D01*
G01X2393835Y465088D02*
X2389110Y460443D01*
G01X2393835Y466192D02*
X2389114Y461550D01*
G01X2389142Y460474D02*
X2389198Y460609D01*
X2389205Y460844D01*
X2389168Y461173D01*
G01X2389142Y460474D02*
X2389199Y460614D01*
X2389204Y460854D01*
G01X2439504Y423209D02*
Y436988D01*
G01Y423209D02*
Y436988D01*
G01Y423209D02*
Y436988D01*
G01X2393835Y466821D02*
Y465088D01*
G01X2389110Y461624D02*
Y468789D01*
G01X2389169Y461165D02*
X2389114Y461550D01*
G01X2390425Y468789D02*
X2393835Y466821D01*
G01X2383155Y485187D02*
Y485581D01*
G01X2378234Y485187D02*
Y485581D01*
G01X2377721D02*
Y485187D01*
G01X2376543Y485581D02*
Y485187D01*
G01X2377721D02*
X2377723Y485149D01*
X2377731Y485112D01*
X2377744Y485078D01*
X2377761Y485048D01*
X2377782Y485023D01*
X2377806Y485005D01*
X2377832Y484994D01*
X2377859Y484990D01*
G01X2378310D02*
X2378272Y485016D01*
X2378244Y485089D01*
X2378234Y485187D01*
G01X2383155D02*
X2376543D01*
G01X2382908Y484990D02*
X2376823D01*
G01X2382908D02*
X2383035Y485018D01*
X2383124Y485091D01*
X2383155Y485187D01*
G01X2378310Y488927D02*
X2378272Y488901D01*
X2378244Y488829D01*
X2378234Y488730D01*
G01X2378310Y492077D02*
X2378272Y492050D01*
X2378244Y491978D01*
X2378234Y491880D01*
G01X2378310Y495226D02*
X2378272Y495200D01*
X2378244Y495128D01*
X2378234Y495029D01*
G01X2378310Y504675D02*
X2378272Y504649D01*
X2378244Y504577D01*
X2378234Y504478D01*
G01X2378310Y507825D02*
X2378272Y507798D01*
X2378244Y507726D01*
X2378234Y507628D01*
G01X2378310Y523573D02*
X2378272Y523546D01*
X2378244Y523474D01*
X2378234Y523376D01*
G01X2387142Y531762D02*
X2385173Y529793D01*
G01X2377132Y488317D02*
X2376706Y487726D01*
G01X2377132Y493317D02*
X2376706Y492726D01*
G01X2377132Y498317D02*
X2376706Y497726D01*
G01X2382877Y486742D02*
X2383017Y486938D01*
X2383155Y487135D01*
X2383292Y487333D01*
G01X2382877Y491742D02*
X2383017Y491938D01*
X2383155Y492135D01*
X2383292Y492333D01*
G01X2382877Y496742D02*
X2383017Y496938D01*
X2383155Y497135D01*
X2383292Y497333D01*
G01X2382877Y501742D02*
X2383017Y501938D01*
X2383155Y502135D01*
X2383292Y502333D01*
G01X2377132Y503317D02*
X2376706Y502726D01*
G01X2377132Y538317D02*
X2376706Y537726D01*
G01X2377132Y543317D02*
X2376706Y542726D01*
G01X2379101Y548317D02*
X2378674Y547726D01*
G01X2377132Y553317D02*
X2376706Y552726D01*
G01X2377064Y508317D02*
X2376640Y507726D01*
G01X2377064Y533317D02*
X2376640Y532726D01*
G01X2382877Y536742D02*
X2383017Y536938D01*
X2383155Y537135D01*
X2383292Y537333D01*
G01X2382877Y541742D02*
X2383017Y541938D01*
X2383155Y542135D01*
X2383292Y542333D01*
G01X2384846Y546742D02*
X2384985Y546938D01*
X2385123Y547135D01*
X2385260Y547333D01*
G01X2382877Y551742D02*
X2383017Y551938D01*
X2383155Y552135D01*
X2383292Y552333D01*
G01X2382877Y556742D02*
X2383017Y556938D01*
X2383155Y557135D01*
X2383292Y557333D01*
G01X2382977Y506742D02*
X2383113Y506938D01*
X2383249Y507135D01*
X2383383Y507333D01*
G01X2382977Y531742D02*
X2383113Y531938D01*
X2383249Y532135D01*
X2383383Y532333D01*
G01X2377549Y487726D02*
X2377822Y488317D01*
G01X2377549Y492726D02*
X2377822Y493317D01*
G01X2377549Y497726D02*
X2377822Y498317D01*
G01X2377549Y502726D02*
X2377822Y503317D01*
G01X2377549Y507726D02*
X2377822Y508317D01*
G01X2377549Y532726D02*
X2377822Y533317D01*
G01X2377549Y537726D02*
X2377822Y538317D01*
G01X2377549Y542726D02*
X2377822Y543317D01*
G01X2379518Y547726D02*
X2379791Y548317D01*
G01X2377549Y552726D02*
X2377822Y553317D01*
G01X2378674Y487726D02*
X2378752Y488317D01*
G01X2378674Y492726D02*
X2378752Y493317D01*
G01X2378674Y497726D02*
X2378752Y498317D01*
G01X2378674Y502726D02*
X2378752Y503317D01*
G01X2378674Y507726D02*
X2378752Y508317D01*
G01X2378674Y532726D02*
X2378752Y533317D01*
G01X2380643Y547726D02*
X2380720Y548317D01*
G01X2378674Y537726D02*
X2378752Y538317D01*
G01X2378674Y542726D02*
X2378752Y543317D01*
G01X2378674Y552726D02*
X2378752Y553317D01*
G01X2378234Y485581D02*
X2378244Y485679D01*
X2378272Y485751D01*
X2378310Y485777D01*
G01X2378234Y498179D02*
X2378244Y498277D01*
X2378272Y498349D01*
X2378310Y498376D01*
G01X2378234Y501329D02*
X2378244Y501427D01*
X2378272Y501499D01*
X2378310Y501525D01*
G01X2378234Y510777D02*
X2378244Y510876D01*
X2378272Y510948D01*
X2378310Y510974D01*
G01X2378234Y513927D02*
X2378244Y514025D01*
X2378272Y514097D01*
X2378310Y514124D01*
G01X2378234Y517077D02*
X2378244Y517175D01*
X2378272Y517247D01*
X2378310Y517274D01*
G01X2378234Y520226D02*
X2378244Y520325D01*
X2378272Y520397D01*
X2378310Y520423D01*
G01X2378234Y526525D02*
X2378244Y526624D01*
X2378272Y526696D01*
X2378310Y526722D01*
G01X2378234Y529675D02*
X2378244Y529773D01*
X2378272Y529846D01*
X2378310Y529872D01*
G01X2378234Y532825D02*
X2378244Y532923D01*
X2378272Y532995D01*
X2378310Y533022D01*
G01X2378234Y535974D02*
X2378244Y536073D01*
X2378272Y536145D01*
X2378310Y536171D01*
G01X2378234Y539124D02*
X2378244Y539222D01*
X2378272Y539294D01*
X2378310Y539321D01*
G01X2378234Y542274D02*
X2378244Y542372D01*
X2378272Y542444D01*
X2378310Y542470D01*
G01X2378234Y545423D02*
X2378244Y545521D01*
X2378272Y545594D01*
X2378310Y545620D01*
G01X2378234Y548573D02*
X2378244Y548671D01*
X2378272Y548743D01*
X2378310Y548770D01*
G01X2378234Y551722D02*
X2378244Y551821D01*
X2378272Y551893D01*
X2378310Y551919D01*
G01X2378234Y554872D02*
X2378244Y554970D01*
X2378272Y555042D01*
X2378310Y555069D01*
G01X2377789Y512650D02*
X2377792Y512688D01*
X2377800Y512725D01*
X2377814Y512759D01*
X2377832Y512789D01*
X2377855Y512813D01*
X2377880Y512831D01*
X2377908Y512843D01*
X2377937Y512847D01*
G01X2377789Y515799D02*
X2377792Y515838D01*
X2377800Y515874D01*
X2377814Y515908D01*
X2377832Y515939D01*
X2377855Y515963D01*
X2377880Y515981D01*
X2377908Y515992D01*
X2377937Y515996D01*
G01X2377789Y518949D02*
X2377792Y518987D01*
X2377800Y519024D01*
X2377814Y519058D01*
X2377832Y519088D01*
X2377855Y519112D01*
X2377880Y519131D01*
X2377908Y519142D01*
X2377937Y519146D01*
G01X2377789Y522099D02*
X2377792Y522137D01*
X2377800Y522174D01*
X2377814Y522207D01*
X2377832Y522238D01*
X2377855Y522262D01*
X2377880Y522280D01*
X2377908Y522291D01*
X2377937Y522295D01*
G01X2377789Y525248D02*
X2377792Y525286D01*
X2377800Y525323D01*
X2377814Y525357D01*
X2377832Y525387D01*
X2377855Y525412D01*
X2377880Y525430D01*
X2377908Y525441D01*
X2377937Y525445D01*
G01X2377789Y528398D02*
X2377792Y528436D01*
X2377800Y528473D01*
X2377814Y528507D01*
X2377832Y528537D01*
X2377855Y528561D01*
X2377880Y528579D01*
X2377908Y528591D01*
X2377937Y528595D01*
G01X2378941Y512650D02*
X2378942Y512688D01*
X2378943Y512725D01*
X2378946Y512759D01*
X2378951Y512789D01*
X2378955Y512813D01*
X2378961Y512831D01*
X2378967Y512843D01*
X2378974Y512847D01*
G01X2378941Y515799D02*
X2378942Y515838D01*
X2378943Y515874D01*
X2378946Y515908D01*
X2378951Y515939D01*
X2378955Y515963D01*
X2378961Y515981D01*
X2378967Y515992D01*
X2378974Y515996D01*
G01X2378941Y518949D02*
X2378942Y518987D01*
X2378943Y519024D01*
X2378946Y519058D01*
X2378951Y519088D01*
X2378955Y519112D01*
X2378961Y519131D01*
X2378967Y519142D01*
X2378974Y519146D01*
G01X2378941Y522099D02*
X2378942Y522137D01*
X2378943Y522174D01*
X2378946Y522207D01*
X2378951Y522238D01*
X2378955Y522262D01*
X2378961Y522280D01*
X2378967Y522291D01*
X2378974Y522295D01*
G01X2378941Y525248D02*
X2378942Y525286D01*
X2378943Y525323D01*
X2378946Y525357D01*
X2378951Y525387D01*
X2378955Y525412D01*
X2378961Y525430D01*
X2378967Y525441D01*
X2378974Y525445D01*
G01X2378941Y528398D02*
X2378942Y528436D01*
X2378943Y528473D01*
X2378946Y528507D01*
X2378951Y528537D01*
X2378955Y528561D01*
X2378961Y528579D01*
X2378967Y528591D01*
X2378974Y528595D01*
G01X2386130Y509308D02*
Y503927D01*
G01Y536230D02*
Y530750D01*
G01X2385961Y509104D02*
Y530955D01*
G01Y607136D02*
Y536230D01*
G01X2385260Y547726D02*
Y547333D01*
G01X2383383Y507726D02*
Y507333D01*
G01Y532726D02*
Y532333D01*
G01X2383292Y487726D02*
Y487333D01*
G01Y492726D02*
Y492333D01*
G01Y497726D02*
Y497333D01*
G01Y502726D02*
Y502333D01*
G01Y537726D02*
Y537333D01*
G01Y542726D02*
Y542333D01*
G01Y552726D02*
Y552333D01*
G01X2383165Y512650D02*
Y511665D01*
G01Y515799D02*
Y514815D01*
G01Y518949D02*
Y517965D01*
G01Y522099D02*
Y521114D01*
G01Y525248D02*
Y524264D01*
G01Y528398D02*
Y527413D01*
G01X2383155Y551329D02*
Y551722D01*
G01Y554478D02*
Y554872D01*
G01Y548179D02*
Y548573D01*
G01Y541880D02*
Y542274D01*
G01Y545029D02*
Y545423D01*
G01Y538730D02*
Y539124D01*
G01Y532431D02*
Y532825D01*
G01Y535581D02*
Y535974D01*
G01Y529281D02*
Y529675D01*
G01Y522982D02*
Y523376D01*
G01Y526132D02*
Y526525D01*
G01Y519833D02*
Y520226D01*
G01Y513533D02*
Y513927D01*
G01Y516683D02*
Y517077D01*
G01Y510384D02*
Y510777D01*
G01Y507234D02*
Y507628D01*
G01Y504085D02*
Y504478D01*
G01Y500935D02*
Y501329D01*
G01Y497785D02*
Y498179D01*
G01Y494636D02*
Y495029D01*
G01Y491486D02*
Y491880D01*
G01Y488337D02*
Y488730D01*
G01X2380673Y510285D02*
Y509104D01*
G01Y530955D02*
Y529774D01*
G01X2380643Y547726D02*
Y547333D01*
G01X2379518D02*
Y547726D01*
G01X2378941Y527413D02*
Y528398D01*
G01Y524264D02*
Y525248D01*
G01Y517965D02*
Y518949D01*
G01Y521114D02*
Y522099D01*
G01Y514815D02*
Y515799D01*
G01Y511665D02*
Y512650D01*
G01X2378674Y547333D02*
Y547726D01*
G01Y487726D02*
Y487333D01*
G01Y492726D02*
Y492333D01*
G01Y497726D02*
Y497333D01*
G01Y502726D02*
Y502333D01*
G01Y507726D02*
Y507333D01*
G01Y532726D02*
Y532333D01*
G01Y537726D02*
Y537333D01*
G01Y542726D02*
Y542333D01*
G01Y552726D02*
Y552333D01*
G01X2378234Y551329D02*
Y551722D01*
G01Y554478D02*
Y554872D01*
G01Y548179D02*
Y548573D01*
G01Y541880D02*
Y542274D01*
G01Y545029D02*
Y545423D01*
G01Y538730D02*
Y539124D01*
G01Y532431D02*
Y532825D01*
G01Y535581D02*
Y535974D01*
G01Y529281D02*
Y529675D01*
G01Y522982D02*
Y523376D01*
G01Y526132D02*
Y526525D01*
G01Y519833D02*
Y520226D01*
G01Y513533D02*
Y513927D01*
G01Y516683D02*
Y517077D01*
G01Y510384D02*
Y510777D01*
G01Y507234D02*
Y507628D01*
G01Y504085D02*
Y504478D01*
G01Y500935D02*
Y501329D01*
G01Y497785D02*
Y498179D01*
G01Y494636D02*
Y495029D01*
G01Y491486D02*
Y491880D01*
G01Y488337D02*
Y488730D01*
G01X2377789Y527413D02*
Y528398D01*
G01Y524264D02*
Y525248D01*
G01Y517965D02*
Y518949D01*
G01Y521114D02*
Y522099D01*
G01Y514815D02*
Y515799D01*
G01Y511665D02*
Y512650D01*
G01X2377721Y488730D02*
Y488337D01*
G01Y491880D02*
Y491486D01*
G01Y498179D02*
Y497785D01*
G01Y495029D02*
Y494636D01*
G01Y501329D02*
Y500935D01*
G01Y507628D02*
Y507234D01*
G01Y504478D02*
Y504085D01*
G01Y510777D02*
Y510384D01*
G01Y513927D02*
Y513533D01*
G01Y517077D02*
Y516683D01*
G01Y520226D02*
Y519833D01*
G01Y523376D02*
Y522982D01*
G01Y526525D02*
Y526132D01*
G01Y529675D02*
Y529281D01*
G01Y532825D02*
Y532431D01*
G01Y535974D02*
Y535581D01*
G01Y539124D02*
Y538730D01*
G01Y542274D02*
Y541880D01*
G01Y545423D02*
Y545029D01*
G01Y548573D02*
Y548179D01*
G01Y551722D02*
Y551329D01*
G01Y554872D02*
Y554478D01*
G01X2377549Y552333D02*
Y552726D01*
G01Y542333D02*
Y542726D01*
G01Y537333D02*
Y537726D01*
G01Y532333D02*
Y532726D01*
G01Y507333D02*
Y507726D01*
G01Y502333D02*
Y502726D01*
G01Y497333D02*
Y497726D01*
G01Y492333D02*
Y492726D01*
G01Y487333D02*
Y487726D01*
G01X2376847Y527413D02*
Y528398D01*
G01Y524264D02*
Y525248D01*
G01Y517965D02*
Y518949D01*
G01Y521114D02*
Y522099D01*
G01Y514815D02*
Y515799D01*
G01Y511665D02*
Y512650D01*
G01X2376706Y552333D02*
Y552726D01*
G01Y542333D02*
Y542726D01*
G01Y537333D02*
Y537726D01*
G01Y502333D02*
Y502726D01*
G01Y497333D02*
Y497726D01*
G01Y492333D02*
Y492726D01*
G01Y487333D02*
Y487726D01*
G01X2376640Y532333D02*
Y532726D01*
G01Y507333D02*
Y507726D01*
G01X2376543Y488730D02*
Y488337D01*
G01Y491880D02*
Y491486D01*
G01Y498179D02*
Y497785D01*
G01Y495029D02*
Y494636D01*
G01Y501329D02*
Y500935D01*
G01Y507628D02*
Y507234D01*
G01Y504478D02*
Y504085D01*
G01Y510777D02*
Y510384D01*
G01Y513927D02*
Y513533D01*
G01Y517077D02*
Y516683D01*
G01Y520226D02*
Y519833D01*
G01Y523376D02*
Y522982D01*
G01Y526525D02*
Y526132D01*
G01Y529675D02*
Y529281D01*
G01Y532825D02*
Y532431D01*
G01Y535974D02*
Y535581D01*
G01Y539124D02*
Y538730D01*
G01Y542274D02*
Y541880D01*
G01Y545423D02*
Y545029D01*
G01Y548573D02*
Y548179D01*
G01Y551722D02*
Y551329D01*
G01Y554872D02*
Y554478D01*
G01X2377721D02*
X2377723Y554440D01*
X2377731Y554403D01*
X2377744Y554369D01*
X2377761Y554339D01*
X2377782Y554315D01*
X2377806Y554297D01*
X2377832Y554285D01*
X2377859Y554281D01*
G01X2377721Y551329D02*
X2377723Y551290D01*
X2377731Y551254D01*
X2377744Y551220D01*
X2377761Y551189D01*
X2377782Y551165D01*
X2377806Y551147D01*
X2377832Y551136D01*
X2377859Y551132D01*
G01X2377721Y548179D02*
X2377723Y548141D01*
X2377731Y548104D01*
X2377744Y548070D01*
X2377761Y548040D01*
X2377782Y548015D01*
X2377806Y547997D01*
X2377832Y547986D01*
X2377859Y547982D01*
G01X2377721Y545029D02*
X2377723Y544991D01*
X2377731Y544954D01*
X2377744Y544921D01*
X2377761Y544890D01*
X2377782Y544866D01*
X2377806Y544848D01*
X2377832Y544836D01*
X2377859Y544833D01*
G01X2377721Y541880D02*
X2377723Y541842D01*
X2377731Y541805D01*
X2377744Y541771D01*
X2377761Y541741D01*
X2377782Y541716D01*
X2377806Y541698D01*
X2377832Y541687D01*
X2377859Y541683D01*
G01X2377721Y538730D02*
X2377723Y538692D01*
X2377731Y538655D01*
X2377744Y538621D01*
X2377761Y538591D01*
X2377782Y538567D01*
X2377806Y538548D01*
X2377832Y538537D01*
X2377859Y538533D01*
G01X2377721Y535581D02*
X2377723Y535542D01*
X2377731Y535506D01*
X2377744Y535472D01*
X2377761Y535441D01*
X2377782Y535417D01*
X2377806Y535399D01*
X2377832Y535388D01*
X2377859Y535384D01*
G01X2377721Y532431D02*
X2377723Y532393D01*
X2377731Y532356D01*
X2377744Y532322D01*
X2377761Y532292D01*
X2377782Y532267D01*
X2377806Y532249D01*
X2377832Y532238D01*
X2377859Y532234D01*
G01X2377721Y529281D02*
X2377723Y529243D01*
X2377731Y529206D01*
X2377744Y529172D01*
X2377761Y529142D01*
X2377782Y529118D01*
X2377806Y529100D01*
X2377832Y529088D01*
X2377859Y529085D01*
G01X2377721Y526132D02*
X2377723Y526094D01*
X2377731Y526057D01*
X2377744Y526023D01*
X2377761Y525993D01*
X2377782Y525968D01*
X2377806Y525950D01*
X2377832Y525939D01*
X2377859Y525935D01*
G01X2377721Y522982D02*
X2377723Y522944D01*
X2377731Y522907D01*
X2377744Y522873D01*
X2377761Y522843D01*
X2377782Y522819D01*
X2377806Y522800D01*
X2377832Y522789D01*
X2377859Y522785D01*
G01X2377721Y519833D02*
X2377723Y519794D01*
X2377731Y519758D01*
X2377744Y519724D01*
X2377761Y519693D01*
X2377782Y519669D01*
X2377806Y519651D01*
X2377832Y519640D01*
X2377859Y519636D01*
G01X2377721Y516683D02*
X2377723Y516645D01*
X2377731Y516608D01*
X2377744Y516574D01*
X2377761Y516544D01*
X2377782Y516519D01*
X2377806Y516501D01*
X2377832Y516490D01*
X2377859Y516486D01*
G01X2377721Y513533D02*
X2377723Y513495D01*
X2377731Y513458D01*
X2377744Y513424D01*
X2377761Y513394D01*
X2377782Y513370D01*
X2377806Y513352D01*
X2377832Y513340D01*
X2377859Y513337D01*
G01X2377721Y510384D02*
X2377723Y510346D01*
X2377731Y510309D01*
X2377744Y510275D01*
X2377761Y510245D01*
X2377782Y510220D01*
X2377806Y510202D01*
X2377832Y510191D01*
X2377859Y510187D01*
G01X2377721Y507234D02*
X2377723Y507196D01*
X2377731Y507159D01*
X2377744Y507125D01*
X2377761Y507095D01*
X2377782Y507071D01*
X2377806Y507052D01*
X2377832Y507041D01*
X2377859Y507037D01*
G01X2377721Y504085D02*
X2377723Y504046D01*
X2377731Y504010D01*
X2377744Y503976D01*
X2377761Y503945D01*
X2377782Y503921D01*
X2377806Y503903D01*
X2377832Y503892D01*
X2377859Y503888D01*
G01X2377721Y500935D02*
X2377723Y500897D01*
X2377731Y500860D01*
X2377744Y500826D01*
X2377761Y500796D01*
X2377782Y500771D01*
X2377806Y500753D01*
X2377832Y500742D01*
X2377859Y500738D01*
G01X2377721Y497785D02*
X2377723Y497747D01*
X2377731Y497710D01*
X2377744Y497676D01*
X2377761Y497646D01*
X2377782Y497622D01*
X2377806Y497604D01*
X2377832Y497592D01*
X2377859Y497588D01*
G01X2377721Y494636D02*
X2377723Y494597D01*
X2377731Y494561D01*
X2377744Y494527D01*
X2377761Y494497D01*
X2377782Y494472D01*
X2377806Y494454D01*
X2377832Y494443D01*
X2377859Y494439D01*
G01X2377721Y491486D02*
X2377723Y491448D01*
X2377731Y491411D01*
X2377744Y491377D01*
X2377761Y491347D01*
X2377782Y491323D01*
X2377806Y491304D01*
X2377832Y491293D01*
X2377859Y491289D01*
G01X2377721Y488337D02*
X2377723Y488298D01*
X2377731Y488262D01*
X2377744Y488228D01*
X2377761Y488197D01*
X2377782Y488173D01*
X2377806Y488155D01*
X2377832Y488144D01*
X2377859Y488140D01*
G01X2380643Y547333D02*
X2380720Y546742D01*
G01X2378674Y557333D02*
X2378752Y556742D01*
G01X2378674Y552333D02*
X2378752Y551742D01*
G01X2378674Y542333D02*
X2378752Y541742D01*
G01X2378674Y537333D02*
X2378752Y536742D01*
G01X2378674Y532333D02*
X2378752Y531742D01*
G01X2378674Y507333D02*
X2378752Y506742D01*
G01X2378674Y502333D02*
X2378752Y501742D01*
G01X2378674Y497333D02*
X2378752Y496742D01*
G01X2378674Y492333D02*
X2378752Y491742D01*
G01X2378674Y487333D02*
X2378752Y486742D01*
G01X2383155Y554872D02*
X2383123Y554969D01*
X2383035Y555041D01*
X2382908Y555069D01*
G01X2383155Y551722D02*
X2383123Y551819D01*
X2383035Y551892D01*
X2382908Y551919D01*
G01X2383155Y548573D02*
X2383123Y548670D01*
X2383035Y548742D01*
X2382908Y548770D01*
G01X2383155Y545423D02*
X2383123Y545520D01*
X2383035Y545592D01*
X2382908Y545620D01*
G01X2383155Y542274D02*
X2383123Y542371D01*
X2383035Y542443D01*
X2382908Y542470D01*
G01X2383155Y539124D02*
X2383123Y539221D01*
X2383035Y539293D01*
X2382908Y539321D01*
G01X2383155Y535974D02*
X2383123Y536071D01*
X2383035Y536144D01*
X2382908Y536171D01*
G01X2383155Y532825D02*
X2383123Y532922D01*
X2383035Y532994D01*
X2382908Y533022D01*
G01X2383155Y529675D02*
X2383123Y529772D01*
X2383035Y529844D01*
X2382908Y529872D01*
G01X2383155Y526525D02*
X2383123Y526623D01*
X2383035Y526695D01*
X2382908Y526722D01*
G01X2383155Y523376D02*
X2383123Y523473D01*
X2383035Y523545D01*
X2382908Y523573D01*
G01X2383155Y520226D02*
X2383123Y520323D01*
X2383035Y520395D01*
X2382908Y520423D01*
G01X2383155Y517077D02*
X2383123Y517174D01*
X2383035Y517246D01*
X2382908Y517274D01*
G01X2383155Y513927D02*
X2383123Y514024D01*
X2383035Y514096D01*
X2382908Y514124D01*
G01X2383155Y510777D02*
X2383123Y510874D01*
X2383035Y510947D01*
X2382908Y510974D01*
G01X2383155Y507628D02*
X2383123Y507725D01*
X2383035Y507797D01*
X2382908Y507825D01*
G01X2383155Y504478D02*
X2383123Y504575D01*
X2383035Y504647D01*
X2382908Y504675D01*
G01X2383155Y501329D02*
X2383123Y501426D01*
X2383035Y501498D01*
X2382908Y501525D01*
G01X2383155Y498179D02*
X2383123Y498276D01*
X2383035Y498348D01*
X2382908Y498376D01*
G01X2383155Y495029D02*
X2383123Y495126D01*
X2383035Y495199D01*
X2382908Y495226D01*
G01X2383155Y491880D02*
X2383123Y491977D01*
X2383035Y492049D01*
X2382908Y492077D01*
G01X2383155Y488730D02*
X2383123Y488827D01*
X2383035Y488899D01*
X2382908Y488927D01*
G01X2383155Y485581D02*
X2383123Y485678D01*
X2383035Y485750D01*
X2382908Y485777D01*
G01X2383165Y528398D02*
X2383132Y528497D01*
X2383043Y528568D01*
X2382917Y528595D01*
G01X2383165Y525248D02*
X2383132Y525347D01*
X2383043Y525418D01*
X2382917Y525445D01*
G01X2383165Y522099D02*
X2383132Y522198D01*
X2383043Y522268D01*
X2382917Y522295D01*
G01X2383165Y518949D02*
X2383132Y519048D01*
X2383043Y519119D01*
X2382917Y519146D01*
G01X2383165Y515799D02*
X2383132Y515898D01*
X2383043Y515969D01*
X2382917Y515996D01*
G01X2383165Y512650D02*
X2383132Y512749D01*
X2383043Y512820D01*
X2382917Y512847D01*
G01X2377822Y556742D02*
X2377549Y557333D01*
G01X2377822Y551742D02*
X2377549Y552333D01*
G01X2379791Y546742D02*
X2379518Y547333D01*
G01X2377822Y541742D02*
X2377549Y542333D01*
G01X2377822Y536742D02*
X2377549Y537333D01*
G01X2377822Y531742D02*
X2377549Y532333D01*
G01X2377822Y506742D02*
X2377549Y507333D01*
G01X2377822Y501742D02*
X2377549Y502333D01*
G01X2377822Y496742D02*
X2377549Y497333D01*
G01X2377822Y491742D02*
X2377549Y492333D01*
G01X2377822Y486742D02*
X2377549Y487333D01*
G01X2383383Y532726D02*
X2383249Y532924D01*
X2383113Y533121D01*
X2382977Y533317D01*
G01X2383292Y552726D02*
X2383155Y552924D01*
X2383017Y553121D01*
X2382877Y553317D01*
G01X2385260Y547726D02*
X2385123Y547924D01*
X2384985Y548121D01*
X2384846Y548317D01*
G01X2383383Y507726D02*
X2383249Y507924D01*
X2383113Y508121D01*
X2382977Y508317D01*
G01X2383292Y542726D02*
X2383155Y542924D01*
X2383017Y543121D01*
X2382877Y543317D01*
G01X2383292Y537726D02*
X2383155Y537924D01*
X2383017Y538121D01*
X2382877Y538317D01*
G01X2383292Y502726D02*
X2383155Y502924D01*
X2383017Y503121D01*
X2382877Y503317D01*
G01X2383292Y497726D02*
X2383155Y497924D01*
X2383017Y498121D01*
X2382877Y498317D01*
G01X2383292Y492726D02*
X2383155Y492924D01*
X2383017Y493121D01*
X2382877Y493317D01*
G01X2383292Y487726D02*
X2383155Y487924D01*
X2383017Y488121D01*
X2382877Y488317D01*
G01X2377064Y531742D02*
X2376640Y532333D01*
G01X2377064Y506742D02*
X2376640Y507333D01*
G01X2377132Y556742D02*
X2376706Y557333D01*
G01X2377132Y551742D02*
X2376706Y552333D01*
G01X2379101Y546742D02*
X2378674Y547333D01*
G01X2377132Y541742D02*
X2376706Y542333D01*
G01X2377132Y536742D02*
X2376706Y537333D01*
G01X2377132Y501742D02*
X2376706Y502333D01*
G01X2377132Y496742D02*
X2376706Y497333D01*
G01X2377132Y491742D02*
X2376706Y492333D01*
G01X2377132Y486742D02*
X2376706Y487333D01*
G01X2385173Y510266D02*
X2387142Y508297D01*
G01X2378310Y554281D02*
X2378272Y554308D01*
X2378244Y554380D01*
X2378234Y554478D01*
G01X2378310Y551132D02*
X2378272Y551158D01*
X2378244Y551230D01*
X2378234Y551329D01*
G01X2378310Y547982D02*
X2378272Y548009D01*
X2378244Y548081D01*
X2378234Y548179D01*
G01X2378310Y544833D02*
X2378272Y544859D01*
X2378244Y544931D01*
X2378234Y545029D01*
G01X2378310Y541683D02*
X2378272Y541709D01*
X2378244Y541781D01*
X2378234Y541880D01*
G01X2378310Y538533D02*
X2378272Y538560D01*
X2378244Y538632D01*
X2378234Y538730D01*
G01X2378310Y535384D02*
X2378272Y535410D01*
X2378244Y535482D01*
X2378234Y535581D01*
G01X2378310Y532234D02*
X2378272Y532261D01*
X2378244Y532333D01*
X2378234Y532431D01*
G01X2378310Y529085D02*
X2378272Y529111D01*
X2378244Y529183D01*
X2378234Y529281D01*
G01X2378310Y525935D02*
X2378272Y525961D01*
X2378244Y526033D01*
X2378234Y526132D01*
G01X2378310Y522785D02*
X2378272Y522812D01*
X2378244Y522884D01*
X2378234Y522982D01*
G01X2378310Y519636D02*
X2378272Y519662D01*
X2378244Y519734D01*
X2378234Y519833D01*
G01X2378310Y516486D02*
X2378272Y516513D01*
X2378244Y516585D01*
X2378234Y516683D01*
G01X2378310Y513337D02*
X2378272Y513363D01*
X2378244Y513435D01*
X2378234Y513533D01*
G01X2378310Y510187D02*
X2378272Y510213D01*
X2378244Y510285D01*
X2378234Y510384D01*
G01X2378310Y507037D02*
X2378272Y507064D01*
X2378244Y507136D01*
X2378234Y507234D01*
G01X2378310Y503888D02*
X2378272Y503914D01*
X2378244Y503986D01*
X2378234Y504085D01*
G01X2378310Y500738D02*
X2378272Y500765D01*
X2378244Y500837D01*
X2378234Y500935D01*
G01X2378310Y497588D02*
X2378272Y497615D01*
X2378244Y497687D01*
X2378234Y497785D01*
G01X2378310Y494439D02*
X2378272Y494465D01*
X2378244Y494537D01*
X2378234Y494636D01*
G01X2378310Y491289D02*
X2378272Y491316D01*
X2378244Y491388D01*
X2378234Y491486D01*
G01X2378310Y488140D02*
X2378272Y488166D01*
X2378244Y488238D01*
X2378234Y488337D01*
G01X2378974Y527217D02*
X2378967Y527220D01*
X2378961Y527231D01*
X2378956Y527250D01*
X2378951Y527274D01*
X2378947Y527304D01*
X2378944Y527338D01*
X2378942Y527375D01*
X2378941Y527413D01*
G01X2378974Y524067D02*
X2378967Y524071D01*
X2378961Y524082D01*
X2378956Y524100D01*
X2378951Y524125D01*
X2378947Y524154D01*
X2378944Y524188D01*
X2378942Y524225D01*
X2378941Y524264D01*
G01X2378974Y520917D02*
X2378967Y520921D01*
X2378961Y520932D01*
X2378956Y520950D01*
X2378951Y520975D01*
X2378947Y521005D01*
X2378944Y521039D01*
X2378942Y521075D01*
X2378941Y521114D01*
G01X2378974Y517768D02*
X2378967Y517772D01*
X2378961Y517783D01*
X2378956Y517801D01*
X2378951Y517825D01*
X2378947Y517855D01*
X2378944Y517889D01*
X2378942Y517926D01*
X2378941Y517965D01*
G01X2378974Y514618D02*
X2378967Y514622D01*
X2378961Y514633D01*
X2378956Y514651D01*
X2378951Y514676D01*
X2378947Y514706D01*
X2378944Y514739D01*
X2378942Y514776D01*
X2378941Y514815D01*
G01X2378974Y511469D02*
X2378967Y511472D01*
X2378961Y511483D01*
X2378956Y511501D01*
X2378951Y511526D01*
X2378947Y511556D01*
X2378944Y511590D01*
X2378942Y511627D01*
X2378941Y511665D01*
G01X2377937Y527217D02*
X2377908Y527220D01*
X2377881Y527231D01*
X2377855Y527250D01*
X2377832Y527274D01*
X2377814Y527304D01*
X2377800Y527338D01*
X2377792Y527375D01*
X2377789Y527413D01*
G01X2377937Y524067D02*
X2377908Y524071D01*
X2377881Y524082D01*
X2377855Y524100D01*
X2377832Y524125D01*
X2377814Y524154D01*
X2377800Y524188D01*
X2377792Y524225D01*
X2377789Y524264D01*
G01X2377937Y520917D02*
X2377908Y520921D01*
X2377881Y520932D01*
X2377855Y520950D01*
X2377832Y520975D01*
X2377814Y521005D01*
X2377800Y521039D01*
X2377792Y521075D01*
X2377789Y521114D01*
G01X2377937Y517768D02*
X2377908Y517772D01*
X2377881Y517783D01*
X2377855Y517801D01*
X2377832Y517825D01*
X2377814Y517855D01*
X2377800Y517889D01*
X2377792Y517926D01*
X2377789Y517965D01*
G01X2377937Y514618D02*
X2377908Y514622D01*
X2377881Y514633D01*
X2377855Y514651D01*
X2377832Y514676D01*
X2377814Y514706D01*
X2377800Y514739D01*
X2377792Y514776D01*
X2377789Y514815D01*
G01X2377937Y511469D02*
X2377908Y511472D01*
X2377881Y511483D01*
X2377855Y511501D01*
X2377832Y511526D01*
X2377814Y511556D01*
X2377800Y511590D01*
X2377792Y511627D01*
X2377789Y511665D01*
G01X2382877Y556742D02*
X2377132D01*
G01X2382908Y555069D02*
X2376823D01*
G01X2376543Y554872D02*
X2383155D01*
G01Y554478D02*
X2376543D01*
G01X2382908Y554281D02*
X2376823D01*
G01X2382877Y553317D02*
X2377132D01*
G01X2376706Y552726D02*
X2383292D01*
G01X2376706Y552333D02*
X2383292D01*
G01X2382908Y551919D02*
X2376823D01*
G01X2382877Y551742D02*
X2377132D01*
G01X2376543Y551722D02*
X2383155D01*
G01Y551329D02*
X2376543D01*
G01X2382908Y551132D02*
X2376823D01*
G01X2382908Y548770D02*
X2376823D01*
G01X2376543Y548573D02*
X2383155D01*
G01X2384846Y548317D02*
X2379101D01*
G01X2383155Y548179D02*
X2376543D01*
G01X2382908Y547982D02*
X2376823D01*
G01X2378674Y547726D02*
X2385260D01*
G01X2378674Y547333D02*
X2385260D01*
G01X2384846Y546742D02*
X2379101D01*
G01X2382908Y545620D02*
X2376823D01*
G01X2376543Y545423D02*
X2383155D01*
G01Y545029D02*
X2376543D01*
G01X2382908Y544833D02*
X2376823D01*
G01X2382877Y543317D02*
X2377132D01*
G01X2376706Y542726D02*
X2383292D01*
G01X2382908Y542470D02*
X2376823D01*
G01X2376706Y542333D02*
X2383292D01*
G01X2376543Y542274D02*
X2383155D01*
G01Y541880D02*
X2376543D01*
G01X2382877Y541742D02*
X2377132D01*
G01X2382908Y541683D02*
X2376823D01*
G01X2382908Y539321D02*
X2376823D01*
G01X2376543Y539124D02*
X2383155D01*
G01Y538730D02*
X2376543D01*
G01X2382908Y538533D02*
X2376823D01*
G01X2382877Y538317D02*
X2377132D01*
G01X2376706Y537726D02*
X2383292D01*
G01X2376706Y537333D02*
X2383292D01*
G01X2382877Y536742D02*
X2377132D01*
G01X2382908Y536171D02*
X2376823D01*
G01X2376543Y535974D02*
X2383155D01*
G01Y535581D02*
X2376543D01*
G01X2382908Y535384D02*
X2376823D01*
G01X2382977Y533317D02*
X2377064D01*
G01X2382908Y533022D02*
X2376823D01*
G01X2376543Y532825D02*
X2383155D01*
G01X2376640Y532726D02*
X2383383D01*
G01X2383155Y532431D02*
X2376543D01*
G01X2376640Y532333D02*
X2383383D01*
G01X2382908Y532234D02*
X2376823D01*
G01X2382977Y531742D02*
X2377064D01*
G01X2380673Y530955D02*
X2387142D01*
G01X2382908Y529872D02*
X2376823D01*
G01X2376543Y529675D02*
X2383155D01*
G01Y529281D02*
X2376543D01*
G01X2382908Y529085D02*
X2376823D01*
G01X2377109Y528595D02*
X2382917D01*
G01X2383165Y528398D02*
X2376847D01*
G01Y527413D02*
X2383165D01*
G01X2377109Y527217D02*
X2382917D01*
G01X2382908Y526722D02*
X2376823D01*
G01X2376543Y526525D02*
X2383155D01*
G01Y526132D02*
X2376543D01*
G01X2382908Y525935D02*
X2376823D01*
G01X2377109Y525445D02*
X2382917D01*
G01X2383165Y525248D02*
X2376847D01*
G01Y524264D02*
X2383165D01*
G01X2377109Y524067D02*
X2382917D01*
G01X2382908Y523573D02*
X2376823D01*
G01X2376543Y523376D02*
X2383155D01*
G01Y522982D02*
X2376543D01*
G01X2382908Y522785D02*
X2376823D01*
G01X2377109Y522295D02*
X2382917D01*
G01X2383165Y522099D02*
X2376847D01*
G01Y521114D02*
X2383165D01*
G01X2377109Y520917D02*
X2382917D01*
G01X2382908Y520423D02*
X2376823D01*
G01X2376543Y520226D02*
X2383155D01*
G01Y519833D02*
X2376543D01*
G01X2382908Y519636D02*
X2376823D01*
G01X2377109Y519146D02*
X2382917D01*
G01X2383165Y518949D02*
X2376847D01*
G01Y517965D02*
X2383165D01*
G01X2377109Y517768D02*
X2382917D01*
G01X2382908Y517274D02*
X2376823D01*
G01X2376543Y517077D02*
X2383155D01*
G01Y516683D02*
X2376543D01*
G01X2382908Y516486D02*
X2376823D01*
G01X2377109Y515996D02*
X2382917D01*
G01X2383165Y515799D02*
X2376847D01*
G01Y514815D02*
X2383165D01*
G01X2377109Y514618D02*
X2382917D01*
G01X2382908Y514124D02*
X2376823D01*
G01X2376543Y513927D02*
X2383155D01*
G01Y513533D02*
X2376543D01*
G01X2382908Y513337D02*
X2376823D01*
G01X2377109Y512847D02*
X2382917D01*
G01X2383165Y512650D02*
X2376847D01*
G01Y511665D02*
X2383165D01*
G01X2377109Y511469D02*
X2382917D01*
G01X2382908Y510974D02*
X2376823D01*
G01X2376543Y510777D02*
X2383155D01*
G01Y510384D02*
X2376543D01*
G01X2382908Y510187D02*
X2376823D01*
G01X2387142Y509104D02*
X2380673D01*
G01X2382977Y508317D02*
X2377064D01*
G01X2382908Y507825D02*
X2376823D01*
G01X2376640Y507726D02*
X2383383D01*
G01X2376543Y507628D02*
X2383155D01*
G01X2376640Y507333D02*
X2383383D01*
G01X2383155Y507234D02*
X2376543D01*
G01X2382908Y507037D02*
X2376823D01*
G01X2382977Y506742D02*
X2377064D01*
G01X2377859Y555069D02*
X2377832Y555065D01*
X2377806Y555054D01*
X2377782Y555036D01*
X2377761Y555011D01*
X2377744Y554981D01*
X2377731Y554948D01*
X2377723Y554911D01*
X2377721Y554872D01*
G01X2382908Y504675D02*
X2376823D01*
G01X2376543Y504478D02*
X2383155D01*
G01Y504085D02*
X2376543D01*
G01X2382908Y503888D02*
X2376823D01*
G01X2382877Y503317D02*
X2377132D01*
G01X2376706Y502726D02*
X2383292D01*
G01X2376706Y502333D02*
X2383292D01*
G01X2382877Y501742D02*
X2377132D01*
G01X2382908Y501525D02*
X2376823D01*
G01X2376543Y501329D02*
X2383155D01*
G01Y500935D02*
X2376543D01*
G01X2382908Y500738D02*
X2376823D01*
G01X2382908Y498376D02*
X2376823D01*
G01X2382877Y498317D02*
X2377132D01*
G01X2376543Y498179D02*
X2383155D01*
G01Y497785D02*
X2376543D01*
G01X2376706Y497726D02*
X2383292D01*
G01X2382908Y497588D02*
X2376823D01*
G01X2376706Y497333D02*
X2383292D01*
G01X2382877Y496742D02*
X2377132D01*
G01X2382908Y495226D02*
X2376823D01*
G01X2376543Y495029D02*
X2383155D01*
G01Y494636D02*
X2376543D01*
G01X2382908Y494439D02*
X2376823D01*
G01X2382877Y493317D02*
X2377132D01*
G01X2376706Y492726D02*
X2383292D01*
G01X2376706Y492333D02*
X2383292D01*
G01X2382908Y492077D02*
X2376823D01*
G01X2376543Y491880D02*
X2383155D01*
G01X2382877Y491742D02*
X2377132D01*
G01X2383155Y491486D02*
X2376543D01*
G01X2382908Y491289D02*
X2376823D01*
G01X2382908Y488927D02*
X2376823D01*
G01X2376543Y488730D02*
X2383155D01*
G01Y488337D02*
X2376543D01*
G01X2382877Y488317D02*
X2377132D01*
G01X2382908Y488140D02*
X2376823D01*
G01X2376706Y487726D02*
X2383292D01*
G01X2376706Y487333D02*
X2383292D01*
G01X2382877Y486742D02*
X2377132D01*
G01X2382908Y485777D02*
X2376823D01*
G01X2376543Y485581D02*
X2383155D01*
G01X2377859Y551919D02*
X2377832Y551915D01*
X2377806Y551904D01*
X2377782Y551886D01*
X2377761Y551862D01*
X2377744Y551832D01*
X2377731Y551798D01*
X2377723Y551761D01*
X2377721Y551722D01*
G01X2377859Y548770D02*
X2377832Y548766D01*
X2377806Y548755D01*
X2377782Y548737D01*
X2377761Y548712D01*
X2377744Y548682D01*
X2377731Y548648D01*
X2377723Y548612D01*
X2377721Y548573D01*
G01X2377859Y545620D02*
X2377832Y545616D01*
X2377806Y545605D01*
X2377782Y545587D01*
X2377761Y545562D01*
X2377744Y545533D01*
X2377731Y545499D01*
X2377723Y545462D01*
X2377721Y545423D01*
G01X2377859Y542470D02*
X2377832Y542467D01*
X2377806Y542456D01*
X2377782Y542437D01*
X2377761Y542413D01*
X2377744Y542383D01*
X2377731Y542349D01*
X2377723Y542312D01*
X2377721Y542274D01*
G01X2377859Y539321D02*
X2377832Y539317D01*
X2377806Y539306D01*
X2377782Y539288D01*
X2377761Y539263D01*
X2377744Y539233D01*
X2377731Y539200D01*
X2377723Y539163D01*
X2377721Y539124D01*
G01X2377859Y536171D02*
X2377832Y536167D01*
X2377806Y536156D01*
X2377782Y536138D01*
X2377761Y536114D01*
X2377744Y536084D01*
X2377731Y536050D01*
X2377723Y536013D01*
X2377721Y535974D01*
G01X2377859Y533022D02*
X2377832Y533018D01*
X2377806Y533007D01*
X2377782Y532989D01*
X2377761Y532964D01*
X2377744Y532934D01*
X2377731Y532900D01*
X2377723Y532864D01*
X2377721Y532825D01*
G01X2377859Y529872D02*
X2377832Y529868D01*
X2377806Y529857D01*
X2377782Y529839D01*
X2377761Y529814D01*
X2377744Y529785D01*
X2377731Y529751D01*
X2377723Y529714D01*
X2377721Y529675D01*
G01X2377859Y526722D02*
X2377832Y526719D01*
X2377806Y526707D01*
X2377782Y526689D01*
X2377761Y526665D01*
X2377744Y526635D01*
X2377731Y526601D01*
X2377723Y526564D01*
X2377721Y526525D01*
G01X2377859Y523573D02*
X2377832Y523569D01*
X2377806Y523558D01*
X2377782Y523540D01*
X2377761Y523515D01*
X2377744Y523485D01*
X2377731Y523452D01*
X2377723Y523415D01*
X2377721Y523376D01*
G01X2377859Y520423D02*
X2377832Y520419D01*
X2377806Y520408D01*
X2377782Y520390D01*
X2377761Y520365D01*
X2377744Y520336D01*
X2377731Y520302D01*
X2377723Y520265D01*
X2377721Y520226D01*
G01X2377859Y517274D02*
X2377832Y517270D01*
X2377806Y517259D01*
X2377782Y517241D01*
X2377761Y517216D01*
X2377744Y517186D01*
X2377731Y517152D01*
X2377723Y517116D01*
X2377721Y517077D01*
G01X2377859Y514124D02*
X2377832Y514120D01*
X2377806Y514109D01*
X2377782Y514091D01*
X2377761Y514066D01*
X2377744Y514037D01*
X2377731Y514003D01*
X2377723Y513966D01*
X2377721Y513927D01*
G01X2377859Y510974D02*
X2377832Y510971D01*
X2377806Y510959D01*
X2377782Y510941D01*
X2377761Y510917D01*
X2377744Y510887D01*
X2377731Y510853D01*
X2377723Y510816D01*
X2377721Y510777D01*
G01X2377859Y507825D02*
X2377832Y507821D01*
X2377806Y507810D01*
X2377782Y507792D01*
X2377761Y507767D01*
X2377744Y507737D01*
X2377731Y507704D01*
X2377723Y507667D01*
X2377721Y507628D01*
G01X2377859Y504675D02*
X2377832Y504671D01*
X2377806Y504660D01*
X2377782Y504642D01*
X2377761Y504617D01*
X2377744Y504588D01*
X2377731Y504554D01*
X2377723Y504517D01*
X2377721Y504478D01*
G01X2377859Y501525D02*
X2377832Y501522D01*
X2377806Y501511D01*
X2377782Y501493D01*
X2377761Y501468D01*
X2377744Y501438D01*
X2377731Y501404D01*
X2377723Y501368D01*
X2377721Y501329D01*
G01X2377859Y498376D02*
X2377832Y498372D01*
X2377806Y498361D01*
X2377782Y498343D01*
X2377761Y498318D01*
X2377744Y498289D01*
X2377731Y498255D01*
X2377723Y498218D01*
X2377721Y498179D01*
G01X2377859Y495226D02*
X2377832Y495223D01*
X2377806Y495211D01*
X2377782Y495193D01*
X2377761Y495169D01*
X2377744Y495139D01*
X2377731Y495105D01*
X2377723Y495068D01*
X2377721Y495029D01*
G01X2377859Y492077D02*
X2377832Y492073D01*
X2377806Y492062D01*
X2377782Y492044D01*
X2377761Y492019D01*
X2377744Y491989D01*
X2377731Y491955D01*
X2377723Y491919D01*
X2377721Y491880D01*
G01X2377859Y488927D02*
X2377832Y488923D01*
X2377806Y488912D01*
X2377782Y488894D01*
X2377761Y488869D01*
X2377744Y488840D01*
X2377731Y488806D01*
X2377723Y488769D01*
X2377721Y488730D01*
G01X2377859Y485777D02*
X2377832Y485774D01*
X2377806Y485763D01*
X2377782Y485745D01*
X2377761Y485720D01*
X2377744Y485690D01*
X2377731Y485656D01*
X2377723Y485620D01*
X2377721Y485581D01*
G01X2382917Y527217D02*
X2383044Y527244D01*
X2383133Y527317D01*
X2383165Y527413D01*
G01X2382917Y524067D02*
X2383044Y524094D01*
X2383133Y524167D01*
X2383165Y524264D01*
G01X2382917Y520917D02*
X2383044Y520945D01*
X2383133Y521017D01*
X2383165Y521114D01*
G01X2382917Y517768D02*
X2383044Y517795D01*
X2383133Y517868D01*
X2383165Y517965D01*
G01X2382917Y514618D02*
X2383044Y514646D01*
X2383133Y514718D01*
X2383165Y514815D01*
G01X2382917Y511469D02*
X2383044Y511496D01*
X2383133Y511569D01*
X2383165Y511665D01*
G01X2382908Y554281D02*
X2383035Y554309D01*
X2383124Y554382D01*
X2383155Y554478D01*
G01X2382908Y551132D02*
X2383035Y551160D01*
X2383124Y551232D01*
X2383155Y551329D01*
G01X2382908Y547982D02*
X2383035Y548010D01*
X2383124Y548083D01*
X2383155Y548179D01*
G01X2382908Y544833D02*
X2383035Y544860D01*
X2383124Y544933D01*
X2383155Y545029D01*
G01X2382908Y541683D02*
X2383035Y541711D01*
X2383124Y541784D01*
X2383155Y541880D01*
G01X2382908Y538533D02*
X2383035Y538561D01*
X2383124Y538634D01*
X2383155Y538730D01*
G01X2382908Y535384D02*
X2383035Y535412D01*
X2383124Y535484D01*
X2383155Y535581D01*
G01X2382908Y532234D02*
X2383035Y532262D01*
X2383124Y532335D01*
X2383155Y532431D01*
G01X2382908Y529085D02*
X2383035Y529112D01*
X2383124Y529185D01*
X2383155Y529281D01*
G01X2382908Y525935D02*
X2383035Y525963D01*
X2383124Y526036D01*
X2383155Y526132D01*
G01X2382908Y522785D02*
X2383035Y522813D01*
X2383124Y522886D01*
X2383155Y522982D01*
G01X2382908Y519636D02*
X2383035Y519663D01*
X2383124Y519736D01*
X2383155Y519833D01*
G01X2382908Y516486D02*
X2383035Y516514D01*
X2383124Y516587D01*
X2383155Y516683D01*
G01X2382908Y513337D02*
X2383035Y513364D01*
X2383124Y513437D01*
X2383155Y513533D01*
G01X2382908Y510187D02*
X2383035Y510215D01*
X2383124Y510288D01*
X2383155Y510384D01*
G01X2382908Y507037D02*
X2383035Y507065D01*
X2383124Y507138D01*
X2383155Y507234D01*
G01X2382908Y503888D02*
X2383035Y503915D01*
X2383124Y503988D01*
X2383155Y504085D01*
G01X2382908Y500738D02*
X2383035Y500766D01*
X2383124Y500839D01*
X2383155Y500935D01*
G01X2382908Y497588D02*
X2383035Y497616D01*
X2383124Y497689D01*
X2383155Y497785D01*
G01X2382908Y494439D02*
X2383035Y494467D01*
X2383124Y494540D01*
X2383155Y494636D01*
G01X2382908Y491289D02*
X2383035Y491317D01*
X2383124Y491390D01*
X2383155Y491486D01*
G01X2382908Y488140D02*
X2383035Y488167D01*
X2383124Y488240D01*
X2383155Y488337D01*
G01X2377132Y558317D02*
X2376706Y557726D01*
G01X2377549D02*
X2377822Y558317D01*
G01X2378674Y557726D02*
X2378752Y558317D01*
G01X2378234Y558022D02*
X2378244Y558120D01*
X2378272Y558192D01*
X2378310Y558218D01*
G01X2383292Y557726D02*
Y557333D01*
G01X2383155Y557628D02*
Y558022D01*
G01X2378674Y557726D02*
Y557333D01*
G01X2378234Y557628D02*
Y558022D01*
G01X2377721D02*
Y557628D01*
G01X2377549Y557333D02*
Y557726D01*
G01X2376706Y557333D02*
Y557726D01*
G01X2376543Y558022D02*
Y557628D01*
G01X2377721D02*
X2377723Y557590D01*
X2377731Y557553D01*
X2377744Y557519D01*
X2377761Y557489D01*
X2377782Y557464D01*
X2377806Y557446D01*
X2377832Y557435D01*
X2377859Y557431D01*
G01X2383155Y558022D02*
X2383123Y558119D01*
X2383035Y558191D01*
X2382908Y558218D01*
G01X2383292Y557726D02*
X2383155Y557924D01*
X2383017Y558121D01*
X2382877Y558317D01*
G01X2378310Y557431D02*
X2378272Y557457D01*
X2378244Y557529D01*
X2378234Y557628D01*
G01X2376543Y558022D02*
X2383155D01*
G01X2376706Y557726D02*
X2383292D01*
G01X2383155Y557628D02*
X2376543D01*
G01X2382908Y557431D02*
X2376823D01*
G01X2376706Y557333D02*
X2383292D01*
G01X2377859Y558218D02*
X2377832Y558215D01*
X2377806Y558204D01*
X2377782Y558186D01*
X2377761Y558161D01*
X2377744Y558131D01*
X2377731Y558097D01*
X2377723Y558060D01*
X2377721Y558022D01*
G01X2382908Y557431D02*
X2383035Y557459D01*
X2383124Y557532D01*
X2383155Y557628D01*
G01X2385173Y606348D02*
X2387142Y608317D01*
G01X2377132Y563317D02*
X2376706Y562726D01*
G01X2377132Y568317D02*
X2376706Y567726D01*
G01X2377132Y573317D02*
X2376706Y572726D01*
G01X2377132Y578317D02*
X2376706Y577726D01*
G01X2377132Y583317D02*
X2376706Y582726D01*
G01X2379101Y588317D02*
X2378674Y587726D01*
G01X2377132Y593317D02*
X2376706Y592726D01*
G01X2377132Y598317D02*
X2376706Y597726D01*
G01X2377132Y603317D02*
X2376706Y602726D01*
G01X2382877Y561742D02*
X2383017Y561938D01*
X2383155Y562135D01*
X2383292Y562333D01*
G01X2382877Y566742D02*
X2383017Y566938D01*
X2383155Y567135D01*
X2383292Y567333D01*
G01X2382877Y571742D02*
X2383017Y571938D01*
X2383155Y572135D01*
X2383292Y572333D01*
G01X2382877Y576742D02*
X2383017Y576938D01*
X2383155Y577135D01*
X2383292Y577333D01*
G01X2382877Y581742D02*
X2383017Y581938D01*
X2383155Y582135D01*
X2383292Y582333D01*
G01X2384846Y586742D02*
X2384985Y586938D01*
X2385123Y587135D01*
X2385260Y587333D01*
G01X2382877Y591742D02*
X2383017Y591938D01*
X2383155Y592135D01*
X2383292Y592333D01*
G01X2382877Y596742D02*
X2383017Y596938D01*
X2383155Y597135D01*
X2383292Y597333D01*
G01X2382877Y601742D02*
X2383017Y601938D01*
X2383155Y602135D01*
X2383292Y602333D01*
G01X2377549Y562726D02*
X2377822Y563317D01*
G01X2377549Y567726D02*
X2377822Y568317D01*
G01X2377549Y572726D02*
X2377822Y573317D01*
G01X2377549Y577726D02*
X2377822Y578317D01*
G01X2377549Y582726D02*
X2377822Y583317D01*
G01X2379518Y587726D02*
X2379791Y588317D01*
G01X2377549Y592726D02*
X2377822Y593317D01*
G01X2377549Y597726D02*
X2377822Y598317D01*
G01X2377549Y602726D02*
X2377822Y603317D01*
G01X2383155Y560777D02*
X2383122Y560678D01*
X2383034Y560608D01*
X2382908Y560581D01*
G01X2383155Y589124D02*
X2383122Y589025D01*
X2383034Y588954D01*
X2382908Y588927D01*
G01X2378674Y562726D02*
X2378752Y563317D01*
G01X2378674Y567726D02*
X2378752Y568317D01*
G01X2378674Y572726D02*
X2378752Y573317D01*
G01X2380643Y587726D02*
X2380720Y588317D01*
G01X2378674Y577726D02*
X2378752Y578317D01*
G01X2378674Y582726D02*
X2378752Y583317D01*
G01X2378674Y592726D02*
X2378752Y593317D01*
G01Y598317D02*
X2378674Y597726D01*
G01Y602726D02*
X2378752Y603317D01*
G01X2378234Y561171D02*
X2378244Y561270D01*
X2378272Y561342D01*
X2378310Y561368D01*
G01X2378234Y564321D02*
X2378244Y564419D01*
X2378272Y564491D01*
X2378310Y564518D01*
G01X2378234Y567470D02*
X2378244Y567569D01*
X2378272Y567641D01*
X2378310Y567667D01*
G01X2378234Y570620D02*
X2378244Y570718D01*
X2378272Y570790D01*
X2378310Y570817D01*
G01X2378234Y573770D02*
X2378244Y573868D01*
X2378272Y573940D01*
X2378310Y573966D01*
G01X2378234Y576919D02*
X2378244Y577018D01*
X2378272Y577090D01*
X2378310Y577116D01*
G01X2378234Y580069D02*
X2378244Y580167D01*
X2378272Y580239D01*
X2378310Y580266D01*
G01X2378234Y583218D02*
X2378244Y583317D01*
X2378272Y583389D01*
X2378310Y583415D01*
G01X2378234Y586368D02*
X2378244Y586466D01*
X2378272Y586538D01*
X2378310Y586565D01*
G01X2378234Y589518D02*
X2378244Y589616D01*
X2378272Y589688D01*
X2378310Y589714D01*
G01X2378234Y592667D02*
X2378244Y592766D01*
X2378272Y592838D01*
X2378310Y592864D01*
G01X2378234Y595817D02*
X2378244Y595915D01*
X2378272Y595987D01*
X2378310Y596014D01*
G01X2378234Y598966D02*
X2378244Y599065D01*
X2378272Y599137D01*
X2378310Y599163D01*
G01X2378234Y602116D02*
X2378244Y602214D01*
X2378272Y602286D01*
X2378310Y602313D01*
G01X2385260Y587726D02*
Y587333D01*
G01X2383292Y562726D02*
Y562333D01*
G01Y567726D02*
Y567333D01*
G01Y572726D02*
Y572333D01*
G01Y577726D02*
Y577333D01*
G01Y582726D02*
Y582333D01*
G01Y592726D02*
Y592333D01*
G01Y597726D02*
Y597333D01*
G01Y602726D02*
Y602333D01*
G01X2383155Y598573D02*
Y598966D01*
G01Y601722D02*
Y602116D01*
G01Y595423D02*
Y595817D01*
G01Y592274D02*
Y592667D01*
G01Y589124D02*
Y589518D01*
G01Y585974D02*
Y586368D01*
G01Y582825D02*
Y583218D01*
G01Y579675D02*
Y580069D01*
G01Y576525D02*
Y576919D01*
G01Y573376D02*
Y573770D01*
G01Y570226D02*
Y570620D01*
G01Y567077D02*
Y567470D01*
G01Y560777D02*
Y561171D01*
G01Y563927D02*
Y564321D01*
G01X2380643Y587726D02*
Y587333D01*
G01X2379518D02*
Y587726D01*
G01X2378674Y587333D02*
Y587726D01*
G01Y597333D02*
Y597726D01*
G01Y562726D02*
Y562333D01*
G01Y567726D02*
Y567333D01*
G01Y572726D02*
Y572333D01*
G01Y577726D02*
Y577333D01*
G01Y582726D02*
Y582333D01*
G01Y592726D02*
Y592333D01*
G01Y602726D02*
Y602333D01*
G01X2378234Y598573D02*
Y598966D01*
G01Y601722D02*
Y602116D01*
G01Y595423D02*
Y595817D01*
G01Y592274D02*
Y592667D01*
G01Y589124D02*
Y589518D01*
G01Y585974D02*
Y586368D01*
G01Y582825D02*
Y583218D01*
G01Y579675D02*
Y580069D01*
G01Y576525D02*
Y576919D01*
G01Y573376D02*
Y573770D01*
G01Y570226D02*
Y570620D01*
G01Y567077D02*
Y567470D01*
G01Y560777D02*
Y561171D01*
G01Y563927D02*
Y564321D01*
G01X2377721Y561171D02*
Y560777D01*
G01Y564321D02*
Y563927D01*
G01Y567470D02*
Y567077D01*
G01Y573770D02*
Y573376D01*
G01Y570620D02*
Y570226D01*
G01Y576919D02*
Y576525D01*
G01Y583218D02*
Y582825D01*
G01Y580069D02*
Y579675D01*
G01Y586368D02*
Y585974D01*
G01Y592667D02*
Y592274D01*
G01Y589518D02*
Y589124D01*
G01Y595817D02*
Y595423D01*
G01Y598966D02*
Y598573D01*
G01Y602116D02*
Y601722D01*
G01X2377549Y602333D02*
Y602726D01*
G01Y597333D02*
Y597726D01*
G01Y592333D02*
Y592726D01*
G01Y582333D02*
Y582726D01*
G01Y577333D02*
Y577726D01*
G01Y572333D02*
Y572726D01*
G01Y567333D02*
Y567726D01*
G01Y562333D02*
Y562726D01*
G01X2376706Y602333D02*
Y602726D01*
G01Y597333D02*
Y597726D01*
G01Y592333D02*
Y592726D01*
G01Y582333D02*
Y582726D01*
G01Y577333D02*
Y577726D01*
G01Y572333D02*
Y572726D01*
G01Y567333D02*
Y567726D01*
G01Y562333D02*
Y562726D01*
G01X2376543Y561171D02*
Y560777D01*
G01Y564321D02*
Y563927D01*
G01Y567470D02*
Y567077D01*
G01Y573770D02*
Y573376D01*
G01Y570620D02*
Y570226D01*
G01Y576919D02*
Y576525D01*
G01Y583218D02*
Y582825D01*
G01Y580069D02*
Y579675D01*
G01Y586368D02*
Y585974D01*
G01Y592667D02*
Y592274D01*
G01Y589518D02*
Y589124D01*
G01Y595817D02*
Y595423D01*
G01Y598966D02*
Y598573D01*
G01Y602116D02*
Y601722D01*
G01X2378674Y602333D02*
X2378752Y601742D01*
G01X2380643Y587333D02*
X2380720Y586742D01*
G01X2378752Y596742D02*
X2378674Y597333D01*
G01Y592333D02*
X2378752Y591742D01*
G01X2378674Y582333D02*
X2378752Y581742D01*
G01X2377721Y601722D02*
X2377723Y601684D01*
X2377731Y601647D01*
X2377744Y601613D01*
X2377761Y601583D01*
X2377782Y601559D01*
X2377806Y601541D01*
X2377832Y601529D01*
X2377859Y601525D01*
G01X2377721Y598573D02*
X2377723Y598535D01*
X2377731Y598498D01*
X2377744Y598464D01*
X2377761Y598434D01*
X2377782Y598409D01*
X2377806Y598391D01*
X2377832Y598380D01*
X2377859Y598376D01*
G01X2377721Y595423D02*
X2377723Y595385D01*
X2377731Y595348D01*
X2377744Y595314D01*
X2377761Y595284D01*
X2377782Y595260D01*
X2377806Y595241D01*
X2377832Y595230D01*
X2377859Y595226D01*
G01X2377721Y592274D02*
X2377723Y592235D01*
X2377731Y592199D01*
X2377744Y592165D01*
X2377761Y592134D01*
X2377782Y592110D01*
X2377806Y592092D01*
X2377832Y592081D01*
X2377859Y592077D01*
G01X2377721Y589124D02*
X2377723Y589086D01*
X2377731Y589049D01*
X2377744Y589015D01*
X2377761Y588985D01*
X2377782Y588960D01*
X2377806Y588942D01*
X2377832Y588931D01*
X2377859Y588927D01*
G01X2377721Y585974D02*
X2377723Y585936D01*
X2377731Y585899D01*
X2377744Y585865D01*
X2377761Y585835D01*
X2377782Y585811D01*
X2377806Y585793D01*
X2377832Y585781D01*
X2377859Y585777D01*
G01X2377721Y582825D02*
X2377723Y582786D01*
X2377731Y582750D01*
X2377744Y582716D01*
X2377761Y582686D01*
X2377782Y582661D01*
X2377806Y582643D01*
X2377832Y582632D01*
X2377859Y582628D01*
G01X2377721Y579675D02*
X2377723Y579637D01*
X2377731Y579600D01*
X2377744Y579566D01*
X2377761Y579536D01*
X2377782Y579512D01*
X2377806Y579493D01*
X2377832Y579482D01*
X2377859Y579478D01*
G01X2377721Y576525D02*
X2377723Y576487D01*
X2377731Y576450D01*
X2377744Y576417D01*
X2377761Y576386D01*
X2377782Y576362D01*
X2377806Y576344D01*
X2377832Y576333D01*
X2377859Y576329D01*
G01X2377721Y573376D02*
X2377723Y573338D01*
X2377731Y573301D01*
X2377744Y573267D01*
X2377761Y573237D01*
X2377782Y573212D01*
X2377806Y573194D01*
X2377832Y573183D01*
X2377859Y573179D01*
G01X2377721Y570226D02*
X2377723Y570188D01*
X2377731Y570151D01*
X2377744Y570117D01*
X2377761Y570087D01*
X2377782Y570063D01*
X2377806Y570045D01*
X2377832Y570033D01*
X2377859Y570029D01*
G01X2377721Y567077D02*
X2377723Y567038D01*
X2377731Y567002D01*
X2377744Y566968D01*
X2377761Y566937D01*
X2377782Y566913D01*
X2377806Y566895D01*
X2377832Y566884D01*
X2377859Y566880D01*
G01X2377721Y563927D02*
X2377723Y563889D01*
X2377731Y563852D01*
X2377744Y563818D01*
X2377761Y563788D01*
X2377782Y563763D01*
X2377806Y563745D01*
X2377832Y563734D01*
X2377859Y563730D01*
G01X2377721Y560777D02*
X2377723Y560739D01*
X2377731Y560702D01*
X2377744Y560669D01*
X2377761Y560638D01*
X2377782Y560614D01*
X2377806Y560596D01*
X2377832Y560585D01*
X2377859Y560581D01*
G01X2378674Y577333D02*
X2378752Y576742D01*
G01X2378674Y572333D02*
X2378752Y571742D01*
G01X2378674Y567333D02*
X2378752Y566742D01*
G01X2378674Y562333D02*
X2378752Y561742D01*
G01X2383155Y602116D02*
X2383123Y602213D01*
X2383035Y602285D01*
X2382908Y602313D01*
G01X2383155Y598966D02*
X2383123Y599063D01*
X2383035Y599136D01*
X2382908Y599163D01*
G01X2383155Y595817D02*
X2383123Y595914D01*
X2383035Y595986D01*
X2382908Y596014D01*
G01X2383155Y592667D02*
X2383123Y592764D01*
X2383035Y592836D01*
X2382908Y592864D01*
G01X2383155Y586368D02*
X2383123Y586465D01*
X2383035Y586537D01*
X2382908Y586565D01*
G01X2383155Y583218D02*
X2383123Y583315D01*
X2383035Y583388D01*
X2382908Y583415D01*
G01X2383155Y580069D02*
X2383123Y580166D01*
X2383035Y580238D01*
X2382908Y580266D01*
G01X2383155Y576919D02*
X2383123Y577016D01*
X2383035Y577088D01*
X2382908Y577116D01*
G01X2383155Y573770D02*
X2383123Y573867D01*
X2383035Y573939D01*
X2382908Y573966D01*
G01X2383155Y570620D02*
X2383123Y570717D01*
X2383035Y570789D01*
X2382908Y570817D01*
G01X2383155Y567470D02*
X2383123Y567567D01*
X2383035Y567640D01*
X2382908Y567667D01*
G01X2383155Y564321D02*
X2383123Y564418D01*
X2383035Y564490D01*
X2382908Y564518D01*
G01X2377822Y601742D02*
X2377549Y602333D01*
G01X2377822Y596742D02*
X2377549Y597333D01*
G01X2377822Y591742D02*
X2377549Y592333D01*
G01X2379791Y586742D02*
X2379518Y587333D01*
G01X2377822Y581742D02*
X2377549Y582333D01*
G01X2377822Y576742D02*
X2377549Y577333D01*
G01X2377822Y571742D02*
X2377549Y572333D01*
G01X2377822Y566742D02*
X2377549Y567333D01*
G01X2377822Y561742D02*
X2377549Y562333D01*
G01X2383292Y602726D02*
X2383155Y602924D01*
X2383017Y603121D01*
X2382877Y603317D01*
G01X2383292Y597726D02*
X2383155Y597924D01*
X2383017Y598121D01*
X2382877Y598317D01*
G01X2383292Y592726D02*
X2383155Y592924D01*
X2383017Y593121D01*
X2382877Y593317D01*
G01X2385260Y587726D02*
X2385123Y587924D01*
X2384985Y588121D01*
X2384846Y588317D01*
G01X2383292Y582726D02*
X2383155Y582924D01*
X2383017Y583121D01*
X2382877Y583317D01*
G01X2383292Y577726D02*
X2383155Y577924D01*
X2383017Y578121D01*
X2382877Y578317D01*
G01X2383292Y572726D02*
X2383155Y572924D01*
X2383017Y573121D01*
X2382877Y573317D01*
G01X2383292Y567726D02*
X2383155Y567924D01*
X2383017Y568121D01*
X2382877Y568317D01*
G01X2383292Y562726D02*
X2383155Y562924D01*
X2383017Y563121D01*
X2382877Y563317D01*
G01X2377132Y601742D02*
X2376706Y602333D01*
G01X2377132Y596742D02*
X2376706Y597333D01*
G01X2377132Y591742D02*
X2376706Y592333D01*
G01X2379101Y586742D02*
X2378674Y587333D01*
G01X2377132Y581742D02*
X2376706Y582333D01*
G01X2377132Y576742D02*
X2376706Y577333D01*
G01X2377132Y571742D02*
X2376706Y572333D01*
G01X2377132Y566742D02*
X2376706Y567333D01*
G01X2377132Y561742D02*
X2376706Y562333D01*
G01X2387142Y609301D02*
X2385173Y611270D01*
G01X2378310Y601525D02*
X2378272Y601552D01*
X2378244Y601624D01*
X2378234Y601722D01*
G01X2378310Y598376D02*
X2378272Y598402D01*
X2378244Y598474D01*
X2378234Y598573D01*
G01X2378310Y595226D02*
X2378272Y595253D01*
X2378244Y595325D01*
X2378234Y595423D01*
G01X2378310Y592077D02*
X2378272Y592103D01*
X2378244Y592175D01*
X2378234Y592274D01*
G01X2378310Y588927D02*
X2378272Y588953D01*
X2378244Y589026D01*
X2378234Y589124D01*
G01X2378310Y585777D02*
X2378272Y585804D01*
X2378244Y585876D01*
X2378234Y585974D01*
G01X2378310Y582628D02*
X2378272Y582654D01*
X2378244Y582726D01*
X2378234Y582825D01*
G01X2378310Y579478D02*
X2378272Y579505D01*
X2378244Y579577D01*
X2378234Y579675D01*
G01X2378310Y576329D02*
X2378272Y576355D01*
X2378244Y576427D01*
X2378234Y576525D01*
G01X2378310Y573179D02*
X2378272Y573205D01*
X2378244Y573278D01*
X2378234Y573376D01*
G01X2378310Y570029D02*
X2378272Y570056D01*
X2378244Y570128D01*
X2378234Y570226D01*
G01X2378310Y566880D02*
X2378272Y566906D01*
X2378244Y566978D01*
X2378234Y567077D01*
G01X2378310Y563730D02*
X2378272Y563757D01*
X2378244Y563829D01*
X2378234Y563927D01*
G01X2378310Y560581D02*
X2378272Y560607D01*
X2378244Y560679D01*
X2378234Y560777D01*
G01X2382908Y589714D02*
X2383034Y589687D01*
X2383124Y589614D01*
X2383155Y589518D01*
G01X2382908Y561368D02*
X2383034Y561341D01*
X2383124Y561268D01*
X2383155Y561171D01*
G01X2390425Y611270D02*
X2387142D01*
G01X2382877Y603317D02*
X2377132D01*
G01X2376706Y602726D02*
X2383292D01*
G01X2376706Y602333D02*
X2383292D01*
G01X2382908Y602313D02*
X2376823D01*
G01X2376543Y602116D02*
X2383155D01*
G01X2382877Y601742D02*
X2377132D01*
G01X2383155Y601722D02*
X2376543D01*
G01X2382908Y601525D02*
X2376823D01*
G01X2382908Y599163D02*
X2376823D01*
G01X2376543Y598966D02*
X2383155D01*
G01Y598573D02*
X2376543D01*
G01X2382908Y598376D02*
X2376823D01*
G01X2382877Y598317D02*
X2377132D01*
G01X2376706Y597726D02*
X2383292D01*
G01X2376706Y597333D02*
X2383292D01*
G01X2382877Y596742D02*
X2377132D01*
G01X2382908Y596014D02*
X2376823D01*
G01X2376543Y595817D02*
X2383155D01*
G01Y595423D02*
X2376543D01*
G01X2382908Y595226D02*
X2376823D01*
G01X2382877Y593317D02*
X2377132D01*
G01X2382908Y592864D02*
X2376823D01*
G01X2376706Y592726D02*
X2383292D01*
G01X2376543Y592667D02*
X2383155D01*
G01X2376706Y592333D02*
X2383292D01*
G01X2383155Y592274D02*
X2376543D01*
G01X2382908Y592077D02*
X2376823D01*
G01X2382877Y591742D02*
X2377132D01*
G01X2382908Y589714D02*
X2376823D01*
G01X2376543Y589518D02*
X2383155D01*
G01Y589124D02*
X2376543D01*
G01X2382908Y588927D02*
X2376823D01*
G01X2384846Y588317D02*
X2379101D01*
G01X2378674Y587726D02*
X2385260D01*
G01X2378674Y587333D02*
X2385260D01*
G01X2384846Y586742D02*
X2379101D01*
G01X2382908Y586565D02*
X2376823D01*
G01X2376543Y586368D02*
X2383155D01*
G01Y585974D02*
X2376543D01*
G01X2382908Y585777D02*
X2376823D01*
G01X2382908Y583415D02*
X2376823D01*
G01X2382877Y583317D02*
X2377132D01*
G01X2376543Y583218D02*
X2383155D01*
G01Y582825D02*
X2376543D01*
G01X2376706Y582726D02*
X2383292D01*
G01X2382908Y582628D02*
X2376823D01*
G01X2376706Y582333D02*
X2383292D01*
G01X2382877Y581742D02*
X2377132D01*
G01X2382908Y580266D02*
X2376823D01*
G01X2376543Y580069D02*
X2383155D01*
G01Y579675D02*
X2376543D01*
G01X2382908Y579478D02*
X2376823D01*
G01X2382877Y578317D02*
X2377132D01*
G01X2376706Y577726D02*
X2383292D01*
G01X2376706Y577333D02*
X2383292D01*
G01X2382908Y577116D02*
X2376823D01*
G01X2376543Y576919D02*
X2383155D01*
G01X2382877Y576742D02*
X2377132D01*
G01X2383155Y576525D02*
X2376543D01*
G01X2382908Y576329D02*
X2376823D01*
G01X2382908Y573966D02*
X2376823D01*
G01X2376543Y573770D02*
X2383155D01*
G01Y573376D02*
X2376543D01*
G01X2382877Y573317D02*
X2377132D01*
G01X2382908Y573179D02*
X2376823D01*
G01X2376706Y572726D02*
X2383292D01*
G01X2376706Y572333D02*
X2383292D01*
G01X2382877Y571742D02*
X2377132D01*
G01X2382908Y570817D02*
X2376823D01*
G01X2376543Y570620D02*
X2383155D01*
G01Y570226D02*
X2376543D01*
G01X2382908Y570029D02*
X2376823D01*
G01X2382877Y568317D02*
X2377132D01*
G01X2376706Y567726D02*
X2383292D01*
G01X2382908Y567667D02*
X2376823D01*
G01X2376543Y567470D02*
X2383155D01*
G01X2376706Y567333D02*
X2383292D01*
G01X2383155Y567077D02*
X2376543D01*
G01X2382908Y566880D02*
X2376823D01*
G01X2382877Y566742D02*
X2377132D01*
G01X2382908Y564518D02*
X2376823D01*
G01X2376543Y564321D02*
X2383155D01*
G01Y563927D02*
X2376543D01*
G01X2382908Y563730D02*
X2376823D01*
G01X2382877Y563317D02*
X2377132D01*
G01X2376706Y562726D02*
X2383292D01*
G01X2376706Y562333D02*
X2383292D01*
G01X2382877Y561742D02*
X2377132D01*
G01X2382908Y561368D02*
X2376823D01*
G01X2376543Y561171D02*
X2383155D01*
G01Y560777D02*
X2376543D01*
G01X2382908Y560581D02*
X2376823D01*
G01X2382877Y558317D02*
X2377132D01*
G01X2382908Y558218D02*
X2376823D01*
G01X2377859Y602313D02*
X2377832Y602309D01*
X2377806Y602298D01*
X2377782Y602280D01*
X2377761Y602255D01*
X2377744Y602226D01*
X2377731Y602192D01*
X2377723Y602155D01*
X2377721Y602116D01*
G01X2377859Y599163D02*
X2377832Y599160D01*
X2377806Y599148D01*
X2377782Y599130D01*
X2377761Y599106D01*
X2377744Y599076D01*
X2377731Y599042D01*
X2377723Y599005D01*
X2377721Y598966D01*
G01X2377859Y596014D02*
X2377832Y596010D01*
X2377806Y595999D01*
X2377782Y595981D01*
X2377761Y595956D01*
X2377744Y595926D01*
X2377731Y595892D01*
X2377723Y595856D01*
X2377721Y595817D01*
G01X2377859Y592864D02*
X2377832Y592860D01*
X2377806Y592849D01*
X2377782Y592831D01*
X2377761Y592806D01*
X2377744Y592777D01*
X2377731Y592743D01*
X2377723Y592706D01*
X2377721Y592667D01*
G01X2377859Y589714D02*
X2377832Y589711D01*
X2377806Y589700D01*
X2377782Y589682D01*
X2377761Y589657D01*
X2377744Y589627D01*
X2377731Y589593D01*
X2377723Y589557D01*
X2377721Y589518D01*
G01X2377859Y586565D02*
X2377832Y586561D01*
X2377806Y586550D01*
X2377782Y586532D01*
X2377761Y586507D01*
X2377744Y586478D01*
X2377731Y586444D01*
X2377723Y586407D01*
X2377721Y586368D01*
G01X2377859Y583415D02*
X2377832Y583412D01*
X2377806Y583400D01*
X2377782Y583382D01*
X2377761Y583358D01*
X2377744Y583328D01*
X2377731Y583294D01*
X2377723Y583257D01*
X2377721Y583218D01*
G01X2377859Y580266D02*
X2377832Y580262D01*
X2377806Y580251D01*
X2377782Y580233D01*
X2377761Y580208D01*
X2377744Y580178D01*
X2377731Y580144D01*
X2377723Y580108D01*
X2377721Y580069D01*
G01X2377859Y577116D02*
X2377832Y577112D01*
X2377806Y577101D01*
X2377782Y577083D01*
X2377761Y577058D01*
X2377744Y577029D01*
X2377731Y576995D01*
X2377723Y576958D01*
X2377721Y576919D01*
G01X2377859Y573966D02*
X2377832Y573963D01*
X2377806Y573952D01*
X2377782Y573934D01*
X2377761Y573909D01*
X2377744Y573879D01*
X2377731Y573845D01*
X2377723Y573809D01*
X2377721Y573770D01*
G01X2377859Y570817D02*
X2377832Y570813D01*
X2377806Y570802D01*
X2377782Y570784D01*
X2377761Y570759D01*
X2377744Y570729D01*
X2377731Y570696D01*
X2377723Y570659D01*
X2377721Y570620D01*
G01X2377859Y567667D02*
X2377832Y567663D01*
X2377806Y567652D01*
X2377782Y567634D01*
X2377761Y567610D01*
X2377744Y567580D01*
X2377731Y567546D01*
X2377723Y567509D01*
X2377721Y567470D01*
G01X2377859Y564518D02*
X2377832Y564514D01*
X2377806Y564503D01*
X2377782Y564485D01*
X2377761Y564460D01*
X2377744Y564430D01*
X2377731Y564396D01*
X2377723Y564360D01*
X2377721Y564321D01*
G01X2377859Y561368D02*
X2377832Y561364D01*
X2377806Y561353D01*
X2377782Y561335D01*
X2377761Y561310D01*
X2377744Y561281D01*
X2377731Y561247D01*
X2377723Y561210D01*
X2377721Y561171D01*
G01X2382908Y601525D02*
X2383035Y601553D01*
X2383124Y601626D01*
X2383155Y601722D01*
G01X2382908Y598376D02*
X2383035Y598404D01*
X2383124Y598477D01*
X2383155Y598573D01*
G01X2382908Y595226D02*
X2383035Y595254D01*
X2383124Y595327D01*
X2383155Y595423D01*
G01X2382908Y592077D02*
X2383035Y592104D01*
X2383124Y592177D01*
X2383155Y592274D01*
G01X2382908Y585777D02*
X2383035Y585805D01*
X2383124Y585878D01*
X2383155Y585974D01*
G01X2382908Y582628D02*
X2383035Y582656D01*
X2383124Y582728D01*
X2383155Y582825D01*
G01X2382908Y579478D02*
X2383035Y579506D01*
X2383124Y579579D01*
X2383155Y579675D01*
G01X2382908Y576329D02*
X2383035Y576356D01*
X2383124Y576429D01*
X2383155Y576525D01*
G01X2382908Y573179D02*
X2383035Y573207D01*
X2383124Y573280D01*
X2383155Y573376D01*
G01X2382908Y570029D02*
X2383035Y570057D01*
X2383124Y570130D01*
X2383155Y570226D01*
G01X2382908Y566880D02*
X2383035Y566908D01*
X2383124Y566980D01*
X2383155Y567077D01*
G01X2382908Y563730D02*
X2383035Y563758D01*
X2383124Y563831D01*
X2383155Y563927D01*
G01X2390425Y611270D02*
X2393835Y613238D01*
G01X2389168Y618886D02*
X2389114Y618509D01*
G01X2389168Y618884D02*
X2389205Y619208D01*
X2389199Y619449D01*
X2389142Y619585D01*
G01X2393835Y613238D02*
Y614970D01*
G01X2389110Y611270D02*
Y618435D01*
G01X2389142Y619585D02*
X2389199Y619445D01*
X2389204Y619205D01*
G01X2393835Y614970D02*
X2389110Y619616D01*
G01X2393835Y613867D02*
X2389114Y618509D01*
G01X2387142Y876270D02*
X2385173Y874301D01*
G01X2377132Y883829D02*
X2376706Y883238D01*
G01X2377132Y888829D02*
X2376706Y888238D01*
G01X2382877Y882254D02*
X2383017Y882450D01*
X2383155Y882647D01*
X2383292Y882844D01*
G01X2382877Y887254D02*
X2383017Y887450D01*
X2383155Y887647D01*
X2383292Y887844D01*
G01X2382877Y892254D02*
X2383017Y892450D01*
X2383155Y892647D01*
X2383292Y892844D01*
G01X2382877Y897254D02*
X2383017Y897450D01*
X2383155Y897647D01*
X2383292Y897844D01*
G01X2378310Y884990D02*
X2378272Y884964D01*
X2378244Y884892D01*
X2378234Y884793D01*
G01X2378310Y894439D02*
X2378272Y894412D01*
X2378244Y894340D01*
X2378234Y894242D01*
G01X2378310Y897588D02*
X2378272Y897562D01*
X2378244Y897490D01*
X2378234Y897392D01*
G01X2378310Y900738D02*
X2378272Y900712D01*
X2378244Y900640D01*
X2378234Y900541D01*
G01X2378310Y910187D02*
X2378272Y910160D01*
X2378244Y910088D01*
X2378234Y909990D01*
G01X2378310Y913337D02*
X2378272Y913310D01*
X2378244Y913238D01*
X2378234Y913140D01*
G01X2377132Y893829D02*
X2376706Y893238D01*
G01X2377132Y898829D02*
X2376706Y898238D01*
G01X2377132Y903829D02*
X2376706Y903238D01*
G01X2377132Y908829D02*
X2376706Y908238D01*
G01X2377064Y913829D02*
X2376640Y913238D01*
G01X2382877Y902254D02*
X2383017Y902450D01*
X2383155Y902647D01*
X2383292Y902844D01*
G01X2382877Y907254D02*
X2383017Y907450D01*
X2383155Y907647D01*
X2383292Y907844D01*
G01X2382977Y912254D02*
X2383113Y912450D01*
X2383249Y912647D01*
X2383383Y912844D01*
G01X2377549Y883238D02*
X2377822Y883829D01*
G01X2377549Y888238D02*
X2377822Y888829D01*
G01X2377549Y893238D02*
X2377822Y893829D01*
G01X2377549Y898238D02*
X2377822Y898829D01*
G01X2377549Y903238D02*
X2377822Y903829D01*
G01X2377549Y908238D02*
X2377822Y908829D01*
G01X2377549Y913238D02*
X2377822Y913829D01*
G01X2378674Y883238D02*
X2378752Y883829D01*
G01X2378674Y888238D02*
X2378752Y888829D01*
G01X2378674Y893238D02*
X2378752Y893829D01*
G01X2378674Y898238D02*
X2378752Y898829D01*
G01X2378674Y903238D02*
X2378752Y903829D01*
G01X2378674Y908238D02*
X2378752Y908829D01*
G01X2378674Y913238D02*
X2378752Y913829D01*
G01X2378234Y887943D02*
X2378244Y888041D01*
X2378272Y888113D01*
X2378310Y888140D01*
G01X2378234Y891092D02*
X2378244Y891191D01*
X2378272Y891263D01*
X2378310Y891289D01*
G01X2378234Y903691D02*
X2378244Y903789D01*
X2378272Y903861D01*
X2378310Y903888D01*
G01X2378234Y906840D02*
X2378244Y906939D01*
X2378272Y907011D01*
X2378310Y907037D01*
G01X2378234Y916289D02*
X2378244Y916388D01*
X2378272Y916460D01*
X2378310Y916486D01*
G01X2378234Y919439D02*
X2378244Y919537D01*
X2378272Y919609D01*
X2378310Y919636D01*
G01X2377789Y918162D02*
X2377792Y918200D01*
X2377800Y918237D01*
X2377814Y918270D01*
X2377832Y918301D01*
X2377855Y918325D01*
X2377880Y918343D01*
X2377908Y918354D01*
X2377937Y918358D01*
G01X2378941Y918162D02*
X2378942Y918200D01*
X2378943Y918237D01*
X2378946Y918270D01*
X2378951Y918301D01*
X2378955Y918325D01*
X2378961Y918343D01*
X2378967Y918354D01*
X2378974Y918358D01*
G01X2387142Y874301D02*
Y1016781D01*
G01X2386130Y914820D02*
Y909439D01*
G01X2386020Y1012254D02*
Y878829D01*
G01X2385961Y914616D02*
Y936466D01*
G01Y909439D02*
Y878435D01*
G01X2385173Y879222D02*
Y1011860D01*
G01X2383383Y913238D02*
Y912844D01*
G01X2383292Y883238D02*
Y882844D01*
G01Y888238D02*
Y887844D01*
G01Y893238D02*
Y892844D01*
G01Y898238D02*
Y897844D01*
G01Y903238D02*
Y902844D01*
G01Y908238D02*
Y907844D01*
G01X2383165Y918162D02*
Y917177D01*
G01Y921311D02*
Y920327D01*
G01X2383155Y919045D02*
Y919439D01*
G01Y912746D02*
Y913140D01*
G01Y915896D02*
Y916289D01*
G01Y909596D02*
Y909990D01*
G01Y906447D02*
Y906840D01*
G01Y903297D02*
Y903691D01*
G01Y900148D02*
Y900541D01*
G01Y896998D02*
Y897392D01*
G01Y893848D02*
Y894242D01*
G01Y890699D02*
Y891092D01*
G01Y884400D02*
Y884793D01*
G01Y887549D02*
Y887943D01*
G01X2380673Y915797D02*
Y914616D01*
G01X2378941Y920327D02*
Y921311D01*
G01Y917177D02*
Y918162D01*
G01X2378674Y883238D02*
Y882844D01*
G01Y888238D02*
Y887844D01*
G01Y893238D02*
Y892844D01*
G01Y898238D02*
Y897844D01*
G01Y903238D02*
Y902844D01*
G01Y908238D02*
Y907844D01*
G01Y913238D02*
Y912844D01*
G01X2378234Y919045D02*
Y919439D01*
G01Y912746D02*
Y913140D01*
G01Y915896D02*
Y916289D01*
G01Y909596D02*
Y909990D01*
G01Y906447D02*
Y906840D01*
G01Y903297D02*
Y903691D01*
G01Y900148D02*
Y900541D01*
G01Y896998D02*
Y897392D01*
G01Y893848D02*
Y894242D01*
G01Y890699D02*
Y891092D01*
G01Y884400D02*
Y884793D01*
G01Y887549D02*
Y887943D01*
G01X2377789Y920327D02*
Y921311D01*
G01Y917177D02*
Y918162D01*
G01X2377721Y884793D02*
Y884400D01*
G01Y887943D02*
Y887549D01*
G01Y891092D02*
Y890699D01*
G01Y897392D02*
Y896998D01*
G01Y894242D02*
Y893848D01*
G01Y900541D02*
Y900148D01*
G01Y906840D02*
Y906447D01*
G01Y903691D02*
Y903297D01*
G01Y909990D02*
Y909596D01*
G01Y913140D02*
Y912746D01*
G01Y916289D02*
Y915896D01*
G01Y919439D02*
Y919045D01*
G01X2377549Y912844D02*
Y913238D01*
G01Y907844D02*
Y908238D01*
G01Y902844D02*
Y903238D01*
G01Y897844D02*
Y898238D01*
G01Y892844D02*
Y893238D01*
G01Y887844D02*
Y888238D01*
G01Y882844D02*
Y883238D01*
G01X2376847Y920327D02*
Y921311D01*
G01Y917177D02*
Y918162D01*
G01X2376706Y907844D02*
Y908238D01*
G01Y902844D02*
Y903238D01*
G01Y897844D02*
Y898238D01*
G01Y892844D02*
Y893238D01*
G01Y887844D02*
Y888238D01*
G01Y882844D02*
Y883238D01*
G01X2376640Y912844D02*
Y913238D01*
G01X2376543Y884793D02*
Y884400D01*
G01Y887943D02*
Y887549D01*
G01Y891092D02*
Y890699D01*
G01Y897392D02*
Y896998D01*
G01Y894242D02*
Y893848D01*
G01Y900541D02*
Y900148D01*
G01Y906840D02*
Y906447D01*
G01Y903691D02*
Y903297D01*
G01Y909990D02*
Y909596D01*
G01Y913140D02*
Y912746D01*
G01Y916289D02*
Y915896D01*
G01Y919439D02*
Y919045D01*
G01X2378674Y912844D02*
X2378752Y912254D01*
G01X2378674Y907844D02*
X2378752Y907254D01*
G01X2378674Y902844D02*
X2378752Y902254D01*
G01X2378674Y897844D02*
X2378752Y897254D01*
G01X2378674Y892844D02*
X2378752Y892254D01*
G01X2378674Y887844D02*
X2378752Y887254D01*
G01X2378674Y882844D02*
X2378752Y882254D01*
G01X2377721Y919045D02*
X2377723Y919007D01*
X2377731Y918970D01*
X2377744Y918936D01*
X2377761Y918906D01*
X2377782Y918882D01*
X2377806Y918863D01*
X2377832Y918852D01*
X2377859Y918848D01*
G01X2377721Y915896D02*
X2377723Y915857D01*
X2377731Y915821D01*
X2377744Y915787D01*
X2377761Y915756D01*
X2377782Y915732D01*
X2377806Y915714D01*
X2377832Y915703D01*
X2377859Y915699D01*
G01X2377721Y912746D02*
X2377723Y912708D01*
X2377731Y912671D01*
X2377744Y912637D01*
X2377761Y912607D01*
X2377782Y912582D01*
X2377806Y912564D01*
X2377832Y912553D01*
X2377859Y912549D01*
G01X2377721Y909596D02*
X2377723Y909558D01*
X2377731Y909521D01*
X2377744Y909487D01*
X2377761Y909457D01*
X2377782Y909433D01*
X2377806Y909415D01*
X2377832Y909403D01*
X2377859Y909400D01*
G01X2377721Y906447D02*
X2377723Y906409D01*
X2377731Y906372D01*
X2377744Y906338D01*
X2377761Y906308D01*
X2377782Y906283D01*
X2377806Y906265D01*
X2377832Y906254D01*
X2377859Y906250D01*
G01X2377721Y903297D02*
X2377723Y903259D01*
X2377731Y903222D01*
X2377744Y903188D01*
X2377761Y903158D01*
X2377782Y903134D01*
X2377806Y903115D01*
X2377832Y903104D01*
X2377859Y903100D01*
G01X2377721Y900148D02*
X2377723Y900109D01*
X2377731Y900073D01*
X2377744Y900039D01*
X2377761Y900008D01*
X2377782Y899984D01*
X2377806Y899966D01*
X2377832Y899955D01*
X2377859Y899951D01*
G01X2377721Y896998D02*
X2377723Y896960D01*
X2377731Y896923D01*
X2377744Y896889D01*
X2377761Y896859D01*
X2377782Y896834D01*
X2377806Y896816D01*
X2377832Y896805D01*
X2377859Y896801D01*
G01X2377721Y893848D02*
X2377723Y893810D01*
X2377731Y893773D01*
X2377744Y893739D01*
X2377761Y893709D01*
X2377782Y893685D01*
X2377806Y893667D01*
X2377832Y893655D01*
X2377859Y893651D01*
G01X2377721Y890699D02*
X2377723Y890660D01*
X2377731Y890624D01*
X2377744Y890590D01*
X2377761Y890560D01*
X2377782Y890535D01*
X2377806Y890517D01*
X2377832Y890506D01*
X2377859Y890502D01*
G01X2377721Y887549D02*
X2377723Y887511D01*
X2377731Y887474D01*
X2377744Y887440D01*
X2377761Y887410D01*
X2377782Y887386D01*
X2377806Y887367D01*
X2377832Y887356D01*
X2377859Y887352D01*
G01X2377721Y884400D02*
X2377723Y884361D01*
X2377731Y884325D01*
X2377744Y884291D01*
X2377761Y884260D01*
X2377782Y884236D01*
X2377806Y884218D01*
X2377832Y884207D01*
X2377859Y884203D01*
G01X2383155Y919439D02*
X2383123Y919536D01*
X2383035Y919608D01*
X2382908Y919636D01*
G01X2383155Y916289D02*
X2383123Y916386D01*
X2383035Y916458D01*
X2382908Y916486D01*
G01X2383155Y913140D02*
X2383123Y913237D01*
X2383035Y913309D01*
X2382908Y913337D01*
G01X2383155Y909990D02*
X2383123Y910087D01*
X2383035Y910159D01*
X2382908Y910187D01*
G01X2383155Y906840D02*
X2383123Y906937D01*
X2383035Y907010D01*
X2382908Y907037D01*
G01X2383155Y903691D02*
X2383123Y903788D01*
X2383035Y903860D01*
X2382908Y903888D01*
G01X2383155Y900541D02*
X2383123Y900638D01*
X2383035Y900710D01*
X2382908Y900738D01*
G01X2383155Y897392D02*
X2383123Y897489D01*
X2383035Y897561D01*
X2382908Y897588D01*
G01X2383155Y894242D02*
X2383123Y894339D01*
X2383035Y894411D01*
X2382908Y894439D01*
G01X2383155Y891092D02*
X2383123Y891189D01*
X2383035Y891262D01*
X2382908Y891289D01*
G01X2383155Y887943D02*
X2383123Y888040D01*
X2383035Y888112D01*
X2382908Y888140D01*
G01X2383155Y884793D02*
X2383123Y884890D01*
X2383035Y884962D01*
X2382908Y884990D01*
G01X2383165Y918162D02*
X2383132Y918261D01*
X2383043Y918331D01*
X2382917Y918358D01*
G01X2377822Y912254D02*
X2377549Y912844D01*
G01X2377822Y907254D02*
X2377549Y907844D01*
G01X2377822Y902254D02*
X2377549Y902844D01*
G01X2377822Y897254D02*
X2377549Y897844D01*
G01X2377822Y892254D02*
X2377549Y892844D01*
G01X2377822Y887254D02*
X2377549Y887844D01*
G01X2377822Y882254D02*
X2377549Y882844D01*
G01X2383383Y913238D02*
X2383249Y913436D01*
X2383113Y913633D01*
X2382977Y913829D01*
G01X2383292Y908238D02*
X2383155Y908436D01*
X2383017Y908633D01*
X2382877Y908829D01*
G01X2383292Y903238D02*
X2383155Y903436D01*
X2383017Y903633D01*
X2382877Y903829D01*
G01X2383292Y898238D02*
X2383155Y898436D01*
X2383017Y898633D01*
X2382877Y898829D01*
G01X2383292Y893238D02*
X2383155Y893436D01*
X2383017Y893633D01*
X2382877Y893829D01*
G01X2383292Y888238D02*
X2383155Y888436D01*
X2383017Y888633D01*
X2382877Y888829D01*
G01X2383292Y883238D02*
X2383155Y883436D01*
X2383017Y883633D01*
X2382877Y883829D01*
G01X2377064Y912254D02*
X2376640Y912844D01*
G01X2377132Y907254D02*
X2376706Y907844D01*
G01X2377132Y902254D02*
X2376706Y902844D01*
G01X2377132Y897254D02*
X2376706Y897844D01*
G01X2377132Y892254D02*
X2376706Y892844D01*
G01X2377132Y887254D02*
X2376706Y887844D01*
G01X2377132Y882254D02*
X2376706Y882844D01*
G01X2385173Y915777D02*
X2387142Y913809D01*
G01Y877254D02*
X2385173Y879222D01*
G01X2378310Y918848D02*
X2378272Y918875D01*
X2378244Y918947D01*
X2378234Y919045D01*
G01X2378310Y915699D02*
X2378272Y915725D01*
X2378244Y915797D01*
X2378234Y915896D01*
G01X2378310Y912549D02*
X2378272Y912576D01*
X2378244Y912648D01*
X2378234Y912746D01*
G01X2378310Y909400D02*
X2378272Y909426D01*
X2378244Y909498D01*
X2378234Y909596D01*
G01X2378310Y906250D02*
X2378272Y906276D01*
X2378244Y906348D01*
X2378234Y906447D01*
G01X2378310Y903100D02*
X2378272Y903127D01*
X2378244Y903199D01*
X2378234Y903297D01*
G01X2378310Y899951D02*
X2378272Y899977D01*
X2378244Y900049D01*
X2378234Y900148D01*
G01X2378310Y896801D02*
X2378272Y896827D01*
X2378244Y896900D01*
X2378234Y896998D01*
G01X2378310Y893651D02*
X2378272Y893678D01*
X2378244Y893750D01*
X2378234Y893848D01*
G01X2378310Y890502D02*
X2378272Y890528D01*
X2378244Y890600D01*
X2378234Y890699D01*
G01X2378310Y887352D02*
X2378272Y887379D01*
X2378244Y887451D01*
X2378234Y887549D01*
G01X2378310Y884203D02*
X2378272Y884229D01*
X2378244Y884301D01*
X2378234Y884400D01*
G01X2378974Y920130D02*
X2378967Y920134D01*
X2378961Y920145D01*
X2378956Y920163D01*
X2378951Y920188D01*
X2378947Y920217D01*
X2378944Y920251D01*
X2378942Y920288D01*
X2378941Y920327D01*
G01X2378974Y916980D02*
X2378967Y916984D01*
X2378961Y916995D01*
X2378956Y917013D01*
X2378951Y917038D01*
X2378947Y917068D01*
X2378944Y917102D01*
X2378942Y917138D01*
X2378941Y917177D01*
G01X2377937Y920130D02*
X2377908Y920134D01*
X2377881Y920145D01*
X2377855Y920163D01*
X2377832Y920188D01*
X2377814Y920217D01*
X2377800Y920251D01*
X2377792Y920288D01*
X2377789Y920327D01*
G01X2377937Y916980D02*
X2377908Y916984D01*
X2377881Y916995D01*
X2377855Y917013D01*
X2377832Y917038D01*
X2377814Y917068D01*
X2377800Y917102D01*
X2377792Y917138D01*
X2377789Y917177D01*
G01X2376847Y920327D02*
X2383165D01*
G01X2377109Y920130D02*
X2382917D01*
G01X2382908Y919636D02*
X2376823D01*
G01X2376543Y919439D02*
X2383155D01*
G01Y919045D02*
X2376543D01*
G01X2382908Y918848D02*
X2376823D01*
G01X2377109Y918358D02*
X2382917D01*
G01X2383165Y918162D02*
X2376847D01*
G01Y917177D02*
X2383165D01*
G01X2377109Y916980D02*
X2382917D01*
G01X2382908Y916486D02*
X2376823D01*
G01X2376543Y916289D02*
X2383155D01*
G01Y915896D02*
X2376543D01*
G01X2382908Y915699D02*
X2376823D01*
G01X2387142Y914616D02*
X2380673D01*
G01X2382977Y913829D02*
X2377064D01*
G01X2382908Y913337D02*
X2376823D01*
G01X2376640Y913238D02*
X2383383D01*
G01X2376543Y913140D02*
X2383155D01*
G01X2376640Y912844D02*
X2383383D01*
G01X2383155Y912746D02*
X2376543D01*
G01X2382908Y912549D02*
X2376823D01*
G01X2382977Y912254D02*
X2377064D01*
G01X2382908Y910187D02*
X2376823D01*
G01X2376543Y909990D02*
X2383155D01*
G01Y909596D02*
X2376543D01*
G01X2382908Y909400D02*
X2376823D01*
G01X2382877Y908829D02*
X2377132D01*
G01X2376706Y908238D02*
X2383292D01*
G01X2376706Y907844D02*
X2383292D01*
G01X2382877Y907254D02*
X2377132D01*
G01X2382908Y907037D02*
X2376823D01*
G01X2376543Y906840D02*
X2383155D01*
G01Y906447D02*
X2376543D01*
G01X2382908Y906250D02*
X2376823D01*
G01X2382908Y903888D02*
X2376823D01*
G01X2382877Y903829D02*
X2377132D01*
G01X2376543Y903691D02*
X2383155D01*
G01Y903297D02*
X2376543D01*
G01X2376706Y903238D02*
X2383292D01*
G01X2382908Y903100D02*
X2376823D01*
G01X2376706Y902844D02*
X2383292D01*
G01X2382877Y902254D02*
X2377132D01*
G01X2382908Y900738D02*
X2376823D01*
G01X2376543Y900541D02*
X2383155D01*
G01Y900148D02*
X2376543D01*
G01X2382908Y899951D02*
X2376823D01*
G01X2382877Y898829D02*
X2377132D01*
G01X2376706Y898238D02*
X2383292D01*
G01X2376706Y897844D02*
X2383292D01*
G01X2382908Y897588D02*
X2376823D01*
G01X2376543Y897392D02*
X2383155D01*
G01X2382877Y897254D02*
X2377132D01*
G01X2383155Y896998D02*
X2376543D01*
G01X2382908Y896801D02*
X2376823D01*
G01X2382908Y894439D02*
X2376823D01*
G01X2376543Y894242D02*
X2383155D01*
G01Y893848D02*
X2376543D01*
G01X2382877Y893829D02*
X2377132D01*
G01X2382908Y893651D02*
X2376823D01*
G01X2376706Y893238D02*
X2383292D01*
G01X2376706Y892844D02*
X2383292D01*
G01X2382877Y892254D02*
X2377132D01*
G01X2382908Y891289D02*
X2376823D01*
G01X2376543Y891092D02*
X2383155D01*
G01Y890699D02*
X2376543D01*
G01X2382908Y890502D02*
X2376823D01*
G01X2382877Y888829D02*
X2377132D01*
G01X2376706Y888238D02*
X2383292D01*
G01X2382908Y888140D02*
X2376823D01*
G01X2376543Y887943D02*
X2383155D01*
G01X2376706Y887844D02*
X2383292D01*
G01X2383155Y887549D02*
X2376543D01*
G01X2382908Y887352D02*
X2376823D01*
G01X2382877Y887254D02*
X2377132D01*
G01X2382908Y884990D02*
X2376823D01*
G01X2376543Y884793D02*
X2383155D01*
G01Y884400D02*
X2376543D01*
G01X2382908Y884203D02*
X2376823D01*
G01X2382877Y883829D02*
X2377132D01*
G01X2376706Y883238D02*
X2383292D01*
G01X2376706Y882844D02*
X2383292D01*
G01X2382877Y882254D02*
X2377132D01*
G01X2390425Y874301D02*
X2387142D01*
G01X2377859Y919636D02*
X2377832Y919632D01*
X2377806Y919621D01*
X2377782Y919603D01*
X2377761Y919578D01*
X2377744Y919548D01*
X2377731Y919515D01*
X2377723Y919478D01*
X2377721Y919439D01*
G01X2377859Y916486D02*
X2377832Y916482D01*
X2377806Y916471D01*
X2377782Y916453D01*
X2377761Y916428D01*
X2377744Y916399D01*
X2377731Y916365D01*
X2377723Y916328D01*
X2377721Y916289D01*
G01X2377859Y913337D02*
X2377832Y913333D01*
X2377806Y913322D01*
X2377782Y913304D01*
X2377761Y913279D01*
X2377744Y913249D01*
X2377731Y913215D01*
X2377723Y913179D01*
X2377721Y913140D01*
G01X2377859Y910187D02*
X2377832Y910183D01*
X2377806Y910172D01*
X2377782Y910154D01*
X2377761Y910129D01*
X2377744Y910100D01*
X2377731Y910066D01*
X2377723Y910029D01*
X2377721Y909990D01*
G01X2377859Y907037D02*
X2377832Y907034D01*
X2377806Y907022D01*
X2377782Y907004D01*
X2377761Y906980D01*
X2377744Y906950D01*
X2377731Y906916D01*
X2377723Y906879D01*
X2377721Y906840D01*
G01X2377859Y903888D02*
X2377832Y903884D01*
X2377806Y903873D01*
X2377782Y903855D01*
X2377761Y903830D01*
X2377744Y903800D01*
X2377731Y903767D01*
X2377723Y903730D01*
X2377721Y903691D01*
G01X2377859Y900738D02*
X2377832Y900734D01*
X2377806Y900723D01*
X2377782Y900705D01*
X2377761Y900680D01*
X2377744Y900651D01*
X2377731Y900617D01*
X2377723Y900580D01*
X2377721Y900541D01*
G01X2377859Y897588D02*
X2377832Y897585D01*
X2377806Y897574D01*
X2377782Y897556D01*
X2377761Y897531D01*
X2377744Y897501D01*
X2377731Y897467D01*
X2377723Y897431D01*
X2377721Y897392D01*
G01X2377859Y894439D02*
X2377832Y894435D01*
X2377806Y894424D01*
X2377782Y894406D01*
X2377761Y894381D01*
X2377744Y894352D01*
X2377731Y894318D01*
X2377723Y894281D01*
X2377721Y894242D01*
G01X2377859Y891289D02*
X2377832Y891286D01*
X2377806Y891274D01*
X2377782Y891256D01*
X2377761Y891232D01*
X2377744Y891202D01*
X2377731Y891168D01*
X2377723Y891131D01*
X2377721Y891092D01*
G01X2377859Y888140D02*
X2377832Y888136D01*
X2377806Y888125D01*
X2377782Y888107D01*
X2377761Y888082D01*
X2377744Y888052D01*
X2377731Y888018D01*
X2377723Y887982D01*
X2377721Y887943D01*
G01X2377859Y884990D02*
X2377832Y884986D01*
X2377806Y884975D01*
X2377782Y884957D01*
X2377761Y884932D01*
X2377744Y884903D01*
X2377731Y884869D01*
X2377723Y884832D01*
X2377721Y884793D01*
G01X2382917Y920130D02*
X2383044Y920157D01*
X2383133Y920230D01*
X2383165Y920327D01*
G01X2382917Y916980D02*
X2383044Y917008D01*
X2383133Y917080D01*
X2383165Y917177D01*
G01X2382908Y918848D02*
X2383035Y918876D01*
X2383124Y918949D01*
X2383155Y919045D01*
G01X2382908Y915699D02*
X2383035Y915726D01*
X2383124Y915799D01*
X2383155Y915896D01*
G01X2382908Y912549D02*
X2383035Y912577D01*
X2383124Y912650D01*
X2383155Y912746D01*
G01X2382908Y909400D02*
X2383035Y909427D01*
X2383124Y909500D01*
X2383155Y909596D01*
G01X2382908Y906250D02*
X2383035Y906278D01*
X2383124Y906351D01*
X2383155Y906447D01*
G01X2382908Y903100D02*
X2383035Y903128D01*
X2383124Y903201D01*
X2383155Y903297D01*
G01X2382908Y899951D02*
X2383035Y899978D01*
X2383124Y900051D01*
X2383155Y900148D01*
G01X2382908Y896801D02*
X2383035Y896829D01*
X2383124Y896902D01*
X2383155Y896998D01*
G01X2382908Y893651D02*
X2383035Y893679D01*
X2383124Y893752D01*
X2383155Y893848D01*
G01X2382908Y890502D02*
X2383035Y890530D01*
X2383124Y890603D01*
X2383155Y890699D01*
G01X2382908Y887352D02*
X2383035Y887380D01*
X2383124Y887453D01*
X2383155Y887549D01*
G01X2382908Y884203D02*
X2383035Y884230D01*
X2383124Y884303D01*
X2383155Y884400D01*
G01X2393835Y870600D02*
X2389110Y865955D01*
G01X2393835Y871704D02*
X2389114Y867062D01*
G01X2389142Y865986D02*
X2389198Y866120D01*
X2389205Y866356D01*
X2389168Y866685D01*
G01X2389142Y865986D02*
X2389199Y866126D01*
X2389204Y866366D01*
G01X2393835Y872333D02*
Y870600D01*
G01X2389110Y867136D02*
Y874301D01*
G01X2389169Y866677D02*
X2389114Y867062D01*
G01X2390425Y874301D02*
X2393835Y872333D01*
G01X2377789Y921311D02*
X2377792Y921349D01*
X2377800Y921386D01*
X2377814Y921420D01*
X2377832Y921450D01*
X2377855Y921475D01*
X2377880Y921493D01*
X2377908Y921504D01*
X2377937Y921508D01*
G01X2378941Y921311D02*
X2378942Y921349D01*
X2378943Y921386D01*
X2378946Y921420D01*
X2378951Y921450D01*
X2378955Y921475D01*
X2378961Y921493D01*
X2378967Y921504D01*
X2378974Y921508D01*
G01X2383155Y922195D02*
Y922588D01*
G01X2378234Y922195D02*
Y922588D01*
G01X2377721D02*
Y922195D01*
G01X2376543Y922588D02*
Y922195D01*
G01X2377721D02*
X2377723Y922157D01*
X2377731Y922120D01*
X2377744Y922086D01*
X2377761Y922056D01*
X2377782Y922031D01*
X2377806Y922013D01*
X2377832Y922002D01*
X2377859Y921998D01*
G01X2383165Y921311D02*
X2383132Y921410D01*
X2383043Y921481D01*
X2382917Y921508D01*
G01X2378310Y921998D02*
X2378272Y922024D01*
X2378244Y922096D01*
X2378234Y922195D01*
G01X2383155D02*
X2376543D01*
G01X2382908Y921998D02*
X2376823D01*
G01X2377109Y921508D02*
X2382917D01*
G01X2383165Y921311D02*
X2376847D01*
G01X2382908Y921998D02*
X2383035Y922026D01*
X2383124Y922099D01*
X2383155Y922195D01*
G01X2378310Y929085D02*
X2378272Y929058D01*
X2378244Y928986D01*
X2378234Y928888D01*
G01X2387142Y937274D02*
X2385173Y935305D01*
G01X2377132Y943829D02*
X2376706Y943238D01*
G01X2377132Y948829D02*
X2376706Y948238D01*
G01X2379101Y953829D02*
X2378674Y953238D01*
G01X2377132Y958829D02*
X2376706Y958238D01*
G01X2377132Y963829D02*
X2376706Y963238D01*
G01X2377132Y968829D02*
X2376706Y968238D01*
G01X2377132Y973829D02*
X2376706Y973238D01*
G01X2377132Y978829D02*
X2376706Y978238D01*
G01X2377132Y983829D02*
X2376706Y983238D01*
G01X2377132Y988829D02*
X2376706Y988238D01*
G01X2379101Y993829D02*
X2378674Y993238D01*
G01X2377064Y938829D02*
X2376640Y938238D01*
G01X2382877Y942254D02*
X2383017Y942450D01*
X2383155Y942647D01*
X2383292Y942844D01*
G01X2382877Y947254D02*
X2383017Y947450D01*
X2383155Y947647D01*
X2383292Y947844D01*
G01X2384846Y952254D02*
X2384985Y952450D01*
X2385123Y952647D01*
X2385260Y952844D01*
G01X2382877Y957254D02*
X2383017Y957450D01*
X2383155Y957647D01*
X2383292Y957844D01*
G01X2382877Y962254D02*
X2383017Y962450D01*
X2383155Y962647D01*
X2383292Y962844D01*
G01X2382877Y967254D02*
X2383017Y967450D01*
X2383155Y967647D01*
X2383292Y967844D01*
G01X2382877Y972254D02*
X2383017Y972450D01*
X2383155Y972647D01*
X2383292Y972844D01*
G01X2382877Y977254D02*
X2383017Y977450D01*
X2383155Y977647D01*
X2383292Y977844D01*
G01X2382877Y982254D02*
X2383017Y982450D01*
X2383155Y982647D01*
X2383292Y982844D01*
G01X2382877Y987254D02*
X2383017Y987450D01*
X2383155Y987647D01*
X2383292Y987844D01*
G01X2384846Y992254D02*
X2384985Y992450D01*
X2385123Y992647D01*
X2385260Y992844D01*
G01X2382977Y937254D02*
X2383113Y937450D01*
X2383249Y937647D01*
X2383383Y937844D01*
G01X2377549Y938238D02*
X2377822Y938829D01*
G01X2377549Y943238D02*
X2377822Y943829D01*
G01X2377549Y948238D02*
X2377822Y948829D01*
G01X2379518Y953238D02*
X2379791Y953829D01*
G01X2377549Y958238D02*
X2377822Y958829D01*
G01X2377549Y963238D02*
X2377822Y963829D01*
G01X2377549Y968238D02*
X2377822Y968829D01*
G01X2377549Y973238D02*
X2377822Y973829D01*
G01X2377549Y978238D02*
X2377822Y978829D01*
G01X2377549Y983238D02*
X2377822Y983829D01*
G01X2377549Y988238D02*
X2377822Y988829D01*
G01X2379518Y993238D02*
X2379791Y993829D01*
G01X2383155Y966289D02*
X2383122Y966190D01*
X2383034Y966119D01*
X2382908Y966092D01*
G01X2378674Y938238D02*
X2378752Y938829D01*
G01X2380643Y953238D02*
X2380720Y953829D01*
G01X2378674Y943238D02*
X2378752Y943829D01*
G01X2378674Y948238D02*
X2378752Y948829D01*
G01X2378674Y958238D02*
X2378752Y958829D01*
G01X2378674Y963238D02*
X2378752Y963829D01*
G01X2378674Y968238D02*
X2378752Y968829D01*
G01X2378674Y973238D02*
X2378752Y973829D01*
G01X2378674Y978238D02*
X2378752Y978829D01*
G01X2380643Y993238D02*
X2380720Y993829D01*
G01X2378674Y983238D02*
X2378752Y983829D01*
G01X2378674Y988238D02*
X2378752Y988829D01*
G01X2378234Y922588D02*
X2378244Y922687D01*
X2378272Y922759D01*
X2378310Y922785D01*
G01X2378234Y925738D02*
X2378244Y925836D01*
X2378272Y925909D01*
X2378310Y925935D01*
G01X2378234Y932037D02*
X2378244Y932136D01*
X2378272Y932208D01*
X2378310Y932234D01*
G01X2378234Y935187D02*
X2378244Y935285D01*
X2378272Y935357D01*
X2378310Y935384D01*
G01X2378234Y938337D02*
X2378244Y938435D01*
X2378272Y938507D01*
X2378310Y938533D01*
G01X2378234Y941486D02*
X2378244Y941584D01*
X2378272Y941657D01*
X2378310Y941683D01*
G01X2378234Y944636D02*
X2378244Y944734D01*
X2378272Y944806D01*
X2378310Y944833D01*
G01X2378234Y947785D02*
X2378244Y947884D01*
X2378272Y947956D01*
X2378310Y947982D01*
G01X2378234Y950935D02*
X2378244Y951033D01*
X2378272Y951105D01*
X2378310Y951132D01*
G01X2378234Y954085D02*
X2378244Y954183D01*
X2378272Y954255D01*
X2378310Y954281D01*
G01X2378234Y957234D02*
X2378244Y957333D01*
X2378272Y957405D01*
X2378310Y957431D01*
G01X2378234Y960384D02*
X2378244Y960482D01*
X2378272Y960554D01*
X2378310Y960581D01*
G01X2378234Y963533D02*
X2378244Y963632D01*
X2378272Y963704D01*
X2378310Y963730D01*
G01X2378234Y966683D02*
X2378244Y966781D01*
X2378272Y966853D01*
X2378310Y966880D01*
G01X2378234Y969833D02*
X2378244Y969931D01*
X2378272Y970003D01*
X2378310Y970029D01*
G01X2378234Y972982D02*
X2378244Y973081D01*
X2378272Y973153D01*
X2378310Y973179D01*
G01X2378234Y976132D02*
X2378244Y976230D01*
X2378272Y976302D01*
X2378310Y976329D01*
G01X2378234Y979281D02*
X2378244Y979380D01*
X2378272Y979452D01*
X2378310Y979478D01*
G01X2378234Y982431D02*
X2378244Y982529D01*
X2378272Y982601D01*
X2378310Y982628D01*
G01X2378234Y985581D02*
X2378244Y985679D01*
X2378272Y985751D01*
X2378310Y985777D01*
G01X2378234Y988730D02*
X2378244Y988829D01*
X2378272Y988901D01*
X2378310Y988927D01*
G01X2378234Y991880D02*
X2378244Y991978D01*
X2378272Y992050D01*
X2378310Y992077D01*
G01X2377789Y924461D02*
X2377792Y924499D01*
X2377800Y924536D01*
X2377814Y924570D01*
X2377832Y924600D01*
X2377855Y924624D01*
X2377880Y924642D01*
X2377908Y924654D01*
X2377937Y924658D01*
G01X2377789Y927610D02*
X2377792Y927649D01*
X2377800Y927685D01*
X2377814Y927719D01*
X2377832Y927750D01*
X2377855Y927774D01*
X2377880Y927792D01*
X2377908Y927803D01*
X2377937Y927807D01*
G01X2377789Y930760D02*
X2377792Y930798D01*
X2377800Y930835D01*
X2377814Y930869D01*
X2377832Y930899D01*
X2377855Y930924D01*
X2377880Y930942D01*
X2377908Y930953D01*
X2377937Y930957D01*
G01X2377789Y933910D02*
X2377792Y933948D01*
X2377800Y933985D01*
X2377814Y934018D01*
X2377832Y934049D01*
X2377855Y934073D01*
X2377880Y934091D01*
X2377908Y934103D01*
X2377937Y934106D01*
G01X2378941Y924461D02*
X2378942Y924499D01*
X2378943Y924536D01*
X2378946Y924570D01*
X2378951Y924600D01*
X2378955Y924624D01*
X2378961Y924642D01*
X2378967Y924654D01*
X2378974Y924658D01*
G01X2378941Y927610D02*
X2378942Y927649D01*
X2378943Y927685D01*
X2378946Y927719D01*
X2378951Y927750D01*
X2378955Y927774D01*
X2378961Y927792D01*
X2378967Y927803D01*
X2378974Y927807D01*
G01X2378941Y930760D02*
X2378942Y930798D01*
X2378943Y930835D01*
X2378946Y930869D01*
X2378951Y930899D01*
X2378955Y930924D01*
X2378961Y930942D01*
X2378967Y930953D01*
X2378974Y930957D01*
G01X2378941Y933910D02*
X2378942Y933948D01*
X2378943Y933985D01*
X2378946Y934018D01*
X2378951Y934049D01*
X2378955Y934073D01*
X2378961Y934091D01*
X2378967Y934103D01*
X2378974Y934106D01*
G01X2386130Y941742D02*
Y936262D01*
G01X2385961Y1012648D02*
Y941742D01*
G01X2385260Y953238D02*
Y952844D01*
G01Y993238D02*
Y992844D01*
G01X2383383Y938238D02*
Y937844D01*
G01X2383292Y943238D02*
Y942844D01*
G01Y948238D02*
Y947844D01*
G01Y958238D02*
Y957844D01*
G01Y963238D02*
Y962844D01*
G01Y968238D02*
Y967844D01*
G01Y973238D02*
Y972844D01*
G01Y978238D02*
Y977844D01*
G01Y983238D02*
Y982844D01*
G01Y988238D02*
Y987844D01*
G01X2383165Y924461D02*
Y923476D01*
G01Y927610D02*
Y926626D01*
G01Y930760D02*
Y929776D01*
G01Y933910D02*
Y932925D01*
G01X2383155Y991486D02*
Y991880D01*
G01Y988337D02*
Y988730D01*
G01Y985187D02*
Y985581D01*
G01Y982037D02*
Y982431D01*
G01Y978888D02*
Y979281D01*
G01Y975738D02*
Y976132D01*
G01Y972588D02*
Y972982D01*
G01Y969439D02*
Y969833D01*
G01Y966289D02*
Y966683D01*
G01Y963140D02*
Y963533D01*
G01Y959990D02*
Y960384D01*
G01Y956840D02*
Y957234D01*
G01Y953691D02*
Y954085D01*
G01Y950541D02*
Y950935D01*
G01Y944242D02*
Y944636D01*
G01Y947392D02*
Y947785D01*
G01Y941092D02*
Y941486D01*
G01Y934793D02*
Y935187D01*
G01Y937943D02*
Y938337D01*
G01Y931644D02*
Y932037D01*
G01Y928494D02*
Y928888D01*
G01Y925344D02*
Y925738D01*
G01X2380673Y936466D02*
Y935285D01*
G01X2380643Y953238D02*
Y952844D01*
G01Y993238D02*
Y992844D01*
G01X2379518D02*
Y993238D01*
G01Y952844D02*
Y953238D01*
G01X2378941Y929776D02*
Y930760D01*
G01Y932925D02*
Y933910D01*
G01Y926626D02*
Y927610D01*
G01Y923476D02*
Y924461D01*
G01X2378674Y992844D02*
Y993238D01*
G01Y952844D02*
Y953238D01*
G01Y938238D02*
Y937844D01*
G01Y943238D02*
Y942844D01*
G01Y948238D02*
Y947844D01*
G01Y958238D02*
Y957844D01*
G01Y963238D02*
Y962844D01*
G01Y968238D02*
Y967844D01*
G01Y973238D02*
Y972844D01*
G01Y978238D02*
Y977844D01*
G01Y983238D02*
Y982844D01*
G01Y988238D02*
Y987844D01*
G01X2378234Y991486D02*
Y991880D01*
G01Y988337D02*
Y988730D01*
G01Y985187D02*
Y985581D01*
G01Y982037D02*
Y982431D01*
G01Y978888D02*
Y979281D01*
G01Y975738D02*
Y976132D01*
G01Y972588D02*
Y972982D01*
G01Y969439D02*
Y969833D01*
G01Y966289D02*
Y966683D01*
G01Y963140D02*
Y963533D01*
G01Y959990D02*
Y960384D01*
G01Y956840D02*
Y957234D01*
G01Y953691D02*
Y954085D01*
G01Y950541D02*
Y950935D01*
G01Y944242D02*
Y944636D01*
G01Y947392D02*
Y947785D01*
G01Y941092D02*
Y941486D01*
G01Y934793D02*
Y935187D01*
G01Y937943D02*
Y938337D01*
G01Y931644D02*
Y932037D01*
G01Y928494D02*
Y928888D01*
G01Y925344D02*
Y925738D01*
G01X2377789Y929776D02*
Y930760D01*
G01Y932925D02*
Y933910D01*
G01Y926626D02*
Y927610D01*
G01Y923476D02*
Y924461D01*
G01X2377721Y928888D02*
Y928494D01*
G01Y925738D02*
Y925344D01*
G01Y932037D02*
Y931644D01*
G01Y935187D02*
Y934793D01*
G01Y938337D02*
Y937943D01*
G01Y941486D02*
Y941092D01*
G01Y944636D02*
Y944242D01*
G01Y947785D02*
Y947392D01*
G01Y950935D02*
Y950541D01*
G01Y957234D02*
Y956840D01*
G01Y954085D02*
Y953691D01*
G01Y960384D02*
Y959990D01*
G01Y966683D02*
Y966289D01*
G01Y963533D02*
Y963140D01*
G01Y969833D02*
Y969439D01*
G01Y976132D02*
Y975738D01*
G01Y972982D02*
Y972588D01*
G01Y979281D02*
Y978888D01*
G01Y985581D02*
Y985187D01*
G01Y982431D02*
Y982037D01*
G01Y988730D02*
Y988337D01*
G01Y991880D02*
Y991486D01*
G01X2377549Y987844D02*
Y988238D01*
G01Y982844D02*
Y983238D01*
G01Y977844D02*
Y978238D01*
G01Y972844D02*
Y973238D01*
G01Y967844D02*
Y968238D01*
G01Y962844D02*
Y963238D01*
G01Y957844D02*
Y958238D01*
G01Y947844D02*
Y948238D01*
G01Y942844D02*
Y943238D01*
G01Y937844D02*
Y938238D01*
G01X2376847Y929776D02*
Y930760D01*
G01Y932925D02*
Y933910D01*
G01Y926626D02*
Y927610D01*
G01Y923476D02*
Y924461D01*
G01X2376706Y987844D02*
Y988238D01*
G01Y982844D02*
Y983238D01*
G01Y977844D02*
Y978238D01*
G01Y972844D02*
Y973238D01*
G01Y967844D02*
Y968238D01*
G01Y962844D02*
Y963238D01*
G01Y957844D02*
Y958238D01*
G01Y947844D02*
Y948238D01*
G01Y942844D02*
Y943238D01*
G01X2376640Y937844D02*
Y938238D01*
G01X2376543Y928888D02*
Y928494D01*
G01Y925738D02*
Y925344D01*
G01Y932037D02*
Y931644D01*
G01Y935187D02*
Y934793D01*
G01Y938337D02*
Y937943D01*
G01Y941486D02*
Y941092D01*
G01Y944636D02*
Y944242D01*
G01Y947785D02*
Y947392D01*
G01Y950935D02*
Y950541D01*
G01Y957234D02*
Y956840D01*
G01Y954085D02*
Y953691D01*
G01Y960384D02*
Y959990D01*
G01Y966683D02*
Y966289D01*
G01Y963533D02*
Y963140D01*
G01Y969833D02*
Y969439D01*
G01Y976132D02*
Y975738D01*
G01Y972982D02*
Y972588D01*
G01Y979281D02*
Y978888D01*
G01Y985581D02*
Y985187D01*
G01Y982431D02*
Y982037D01*
G01Y988730D02*
Y988337D01*
G01Y991880D02*
Y991486D01*
G01X2380643Y992844D02*
X2380720Y992254D01*
G01X2378674Y987844D02*
X2378752Y987254D01*
G01X2378674Y982844D02*
X2378752Y982254D01*
G01X2378674Y977844D02*
X2378752Y977254D01*
G01X2378674Y972844D02*
X2378752Y972254D01*
G01X2378674Y967844D02*
X2378752Y967254D01*
G01X2380643Y952844D02*
X2380720Y952254D01*
G01X2378674Y962844D02*
X2378752Y962254D01*
G01X2378674Y957844D02*
X2378752Y957254D01*
G01X2378674Y947844D02*
X2378752Y947254D01*
G01X2378674Y942844D02*
X2378752Y942254D01*
G01X2378674Y937844D02*
X2378752Y937254D01*
G01X2377721Y991486D02*
X2377723Y991448D01*
X2377731Y991411D01*
X2377744Y991377D01*
X2377761Y991347D01*
X2377782Y991323D01*
X2377806Y991304D01*
X2377832Y991293D01*
X2377859Y991289D01*
G01X2377721Y988337D02*
X2377723Y988298D01*
X2377731Y988262D01*
X2377744Y988228D01*
X2377761Y988197D01*
X2377782Y988173D01*
X2377806Y988155D01*
X2377832Y988144D01*
X2377859Y988140D01*
G01X2377721Y985187D02*
X2377723Y985149D01*
X2377731Y985112D01*
X2377744Y985078D01*
X2377761Y985048D01*
X2377782Y985023D01*
X2377806Y985005D01*
X2377832Y984994D01*
X2377859Y984990D01*
G01X2377721Y982037D02*
X2377723Y981999D01*
X2377731Y981962D01*
X2377744Y981928D01*
X2377761Y981898D01*
X2377782Y981874D01*
X2377806Y981856D01*
X2377832Y981844D01*
X2377859Y981840D01*
G01X2377721Y978888D02*
X2377723Y978849D01*
X2377731Y978813D01*
X2377744Y978779D01*
X2377761Y978749D01*
X2377782Y978724D01*
X2377806Y978706D01*
X2377832Y978695D01*
X2377859Y978691D01*
G01X2377721Y975738D02*
X2377723Y975700D01*
X2377731Y975663D01*
X2377744Y975629D01*
X2377761Y975599D01*
X2377782Y975575D01*
X2377806Y975556D01*
X2377832Y975545D01*
X2377859Y975541D01*
G01X2377721Y972588D02*
X2377723Y972550D01*
X2377731Y972513D01*
X2377744Y972480D01*
X2377761Y972449D01*
X2377782Y972425D01*
X2377806Y972407D01*
X2377832Y972396D01*
X2377859Y972392D01*
G01X2377721Y969439D02*
X2377723Y969401D01*
X2377731Y969364D01*
X2377744Y969330D01*
X2377761Y969300D01*
X2377782Y969275D01*
X2377806Y969257D01*
X2377832Y969246D01*
X2377859Y969242D01*
G01X2377721Y966289D02*
X2377723Y966251D01*
X2377731Y966214D01*
X2377744Y966180D01*
X2377761Y966150D01*
X2377782Y966126D01*
X2377806Y966108D01*
X2377832Y966096D01*
X2377859Y966092D01*
G01X2377721Y963140D02*
X2377723Y963101D01*
X2377731Y963065D01*
X2377744Y963031D01*
X2377761Y963000D01*
X2377782Y962976D01*
X2377806Y962958D01*
X2377832Y962947D01*
X2377859Y962943D01*
G01X2377721Y959990D02*
X2377723Y959952D01*
X2377731Y959915D01*
X2377744Y959881D01*
X2377761Y959851D01*
X2377782Y959826D01*
X2377806Y959808D01*
X2377832Y959797D01*
X2377859Y959793D01*
G01X2377721Y956840D02*
X2377723Y956802D01*
X2377731Y956765D01*
X2377744Y956732D01*
X2377761Y956701D01*
X2377782Y956677D01*
X2377806Y956659D01*
X2377832Y956647D01*
X2377859Y956644D01*
G01X2377721Y953691D02*
X2377723Y953653D01*
X2377731Y953616D01*
X2377744Y953582D01*
X2377761Y953552D01*
X2377782Y953527D01*
X2377806Y953509D01*
X2377832Y953498D01*
X2377859Y953494D01*
G01X2377721Y950541D02*
X2377723Y950503D01*
X2377731Y950466D01*
X2377744Y950432D01*
X2377761Y950402D01*
X2377782Y950378D01*
X2377806Y950360D01*
X2377832Y950348D01*
X2377859Y950344D01*
G01X2377721Y947392D02*
X2377723Y947353D01*
X2377731Y947317D01*
X2377744Y947283D01*
X2377761Y947252D01*
X2377782Y947228D01*
X2377806Y947210D01*
X2377832Y947199D01*
X2377859Y947195D01*
G01X2377721Y944242D02*
X2377723Y944204D01*
X2377731Y944167D01*
X2377744Y944133D01*
X2377761Y944103D01*
X2377782Y944078D01*
X2377806Y944060D01*
X2377832Y944049D01*
X2377859Y944045D01*
G01X2377721Y941092D02*
X2377723Y941054D01*
X2377731Y941017D01*
X2377744Y940983D01*
X2377761Y940953D01*
X2377782Y940929D01*
X2377806Y940911D01*
X2377832Y940899D01*
X2377859Y940896D01*
G01X2377721Y937943D02*
X2377723Y937905D01*
X2377731Y937868D01*
X2377744Y937834D01*
X2377761Y937804D01*
X2377782Y937779D01*
X2377806Y937761D01*
X2377832Y937750D01*
X2377859Y937746D01*
G01X2377721Y934793D02*
X2377723Y934755D01*
X2377731Y934718D01*
X2377744Y934684D01*
X2377761Y934654D01*
X2377782Y934630D01*
X2377806Y934611D01*
X2377832Y934600D01*
X2377859Y934596D01*
G01X2377721Y931644D02*
X2377723Y931605D01*
X2377731Y931569D01*
X2377744Y931535D01*
X2377761Y931504D01*
X2377782Y931480D01*
X2377806Y931462D01*
X2377832Y931451D01*
X2377859Y931447D01*
G01X2377721Y928494D02*
X2377723Y928456D01*
X2377731Y928419D01*
X2377744Y928385D01*
X2377761Y928355D01*
X2377782Y928330D01*
X2377806Y928312D01*
X2377832Y928301D01*
X2377859Y928297D01*
G01X2377721Y925344D02*
X2377723Y925306D01*
X2377731Y925269D01*
X2377744Y925235D01*
X2377761Y925205D01*
X2377782Y925181D01*
X2377806Y925163D01*
X2377832Y925151D01*
X2377859Y925148D01*
G01X2383155Y991880D02*
X2383123Y991977D01*
X2383035Y992049D01*
X2382908Y992077D01*
G01X2383155Y988730D02*
X2383123Y988827D01*
X2383035Y988899D01*
X2382908Y988927D01*
G01X2383155Y985581D02*
X2383123Y985678D01*
X2383035Y985750D01*
X2382908Y985777D01*
G01X2383155Y982431D02*
X2383123Y982528D01*
X2383035Y982600D01*
X2382908Y982628D01*
G01X2383155Y979281D02*
X2383123Y979378D01*
X2383035Y979451D01*
X2382908Y979478D01*
G01X2383155Y976132D02*
X2383123Y976229D01*
X2383035Y976301D01*
X2382908Y976329D01*
G01X2383155Y972982D02*
X2383123Y973079D01*
X2383035Y973151D01*
X2382908Y973179D01*
G01X2383155Y969833D02*
X2383123Y969930D01*
X2383035Y970002D01*
X2382908Y970029D01*
G01X2383155Y963533D02*
X2383123Y963630D01*
X2383035Y963703D01*
X2382908Y963730D01*
G01X2383155Y960384D02*
X2383123Y960481D01*
X2383035Y960553D01*
X2382908Y960581D01*
G01X2383155Y957234D02*
X2383123Y957331D01*
X2383035Y957403D01*
X2382908Y957431D01*
G01X2383155Y954085D02*
X2383123Y954182D01*
X2383035Y954254D01*
X2382908Y954281D01*
G01X2383155Y950935D02*
X2383123Y951032D01*
X2383035Y951104D01*
X2382908Y951132D01*
G01X2383155Y947785D02*
X2383123Y947882D01*
X2383035Y947955D01*
X2382908Y947982D01*
G01X2383155Y944636D02*
X2383123Y944733D01*
X2383035Y944805D01*
X2382908Y944833D01*
G01X2383155Y941486D02*
X2383123Y941583D01*
X2383035Y941655D01*
X2382908Y941683D01*
G01X2383155Y938337D02*
X2383123Y938434D01*
X2383035Y938506D01*
X2382908Y938533D01*
G01X2383155Y935187D02*
X2383123Y935284D01*
X2383035Y935356D01*
X2382908Y935384D01*
G01X2383155Y932037D02*
X2383123Y932134D01*
X2383035Y932207D01*
X2382908Y932234D01*
G01X2383155Y928888D02*
X2383123Y928985D01*
X2383035Y929057D01*
X2382908Y929085D01*
G01X2383155Y925738D02*
X2383123Y925835D01*
X2383035Y925907D01*
X2382908Y925935D01*
G01X2383155Y922588D02*
X2383123Y922685D01*
X2383035Y922758D01*
X2382908Y922785D01*
G01X2383165Y933910D02*
X2383132Y934009D01*
X2383043Y934079D01*
X2382917Y934106D01*
G01X2383165Y930760D02*
X2383132Y930859D01*
X2383043Y930930D01*
X2382917Y930957D01*
G01X2383165Y927610D02*
X2383132Y927709D01*
X2383043Y927780D01*
X2382917Y927807D01*
G01X2383165Y924461D02*
X2383132Y924560D01*
X2383043Y924631D01*
X2382917Y924658D01*
G01X2379791Y992254D02*
X2379518Y992844D01*
G01X2377822Y987254D02*
X2377549Y987844D01*
G01X2377822Y982254D02*
X2377549Y982844D01*
G01X2377822Y977254D02*
X2377549Y977844D01*
G01X2377822Y972254D02*
X2377549Y972844D01*
G01X2377822Y967254D02*
X2377549Y967844D01*
G01X2377822Y962254D02*
X2377549Y962844D01*
G01X2377822Y957254D02*
X2377549Y957844D01*
G01X2379791Y952254D02*
X2379518Y952844D01*
G01X2377822Y947254D02*
X2377549Y947844D01*
G01X2377822Y942254D02*
X2377549Y942844D01*
G01X2377822Y937254D02*
X2377549Y937844D01*
G01X2385260Y993238D02*
X2385123Y993436D01*
X2384985Y993633D01*
X2384846Y993829D01*
G01X2383292Y988238D02*
X2383155Y988436D01*
X2383017Y988633D01*
X2382877Y988829D01*
G01X2383292Y983238D02*
X2383155Y983436D01*
X2383017Y983633D01*
X2382877Y983829D01*
G01X2383292Y978238D02*
X2383155Y978436D01*
X2383017Y978633D01*
X2382877Y978829D01*
G01X2383292Y973238D02*
X2383155Y973436D01*
X2383017Y973633D01*
X2382877Y973829D01*
G01X2383292Y968238D02*
X2383155Y968436D01*
X2383017Y968633D01*
X2382877Y968829D01*
G01X2383292Y963238D02*
X2383155Y963436D01*
X2383017Y963633D01*
X2382877Y963829D01*
G01X2383292Y958238D02*
X2383155Y958436D01*
X2383017Y958633D01*
X2382877Y958829D01*
G01X2385260Y953238D02*
X2385123Y953436D01*
X2384985Y953633D01*
X2384846Y953829D01*
G01X2379101Y992254D02*
X2378674Y992844D01*
G01X2377132Y987254D02*
X2376706Y987844D01*
G01X2377132Y982254D02*
X2376706Y982844D01*
G01X2383383Y938238D02*
X2383249Y938436D01*
X2383113Y938633D01*
X2382977Y938829D01*
G01X2383292Y948238D02*
X2383155Y948436D01*
X2383017Y948633D01*
X2382877Y948829D01*
G01X2383292Y943238D02*
X2383155Y943436D01*
X2383017Y943633D01*
X2382877Y943829D01*
G01X2377064Y937254D02*
X2376640Y937844D01*
G01X2377132Y977254D02*
X2376706Y977844D01*
G01X2377132Y972254D02*
X2376706Y972844D01*
G01X2377132Y967254D02*
X2376706Y967844D01*
G01X2377132Y962254D02*
X2376706Y962844D01*
G01X2377132Y957254D02*
X2376706Y957844D01*
G01X2379101Y952254D02*
X2378674Y952844D01*
G01X2377132Y947254D02*
X2376706Y947844D01*
G01X2377132Y942254D02*
X2376706Y942844D01*
G01X2378310Y991289D02*
X2378272Y991316D01*
X2378244Y991388D01*
X2378234Y991486D01*
G01X2378310Y988140D02*
X2378272Y988166D01*
X2378244Y988238D01*
X2378234Y988337D01*
G01X2378310Y984990D02*
X2378272Y985016D01*
X2378244Y985089D01*
X2378234Y985187D01*
G01X2378310Y981840D02*
X2378272Y981867D01*
X2378244Y981939D01*
X2378234Y982037D01*
G01X2378310Y978691D02*
X2378272Y978717D01*
X2378244Y978789D01*
X2378234Y978888D01*
G01X2378310Y975541D02*
X2378272Y975568D01*
X2378244Y975640D01*
X2378234Y975738D01*
G01X2378310Y972392D02*
X2378272Y972418D01*
X2378244Y972490D01*
X2378234Y972588D01*
G01X2378310Y969242D02*
X2378272Y969268D01*
X2378244Y969341D01*
X2378234Y969439D01*
G01X2378310Y966092D02*
X2378272Y966119D01*
X2378244Y966191D01*
X2378234Y966289D01*
G01X2378310Y962943D02*
X2378272Y962969D01*
X2378244Y963041D01*
X2378234Y963140D01*
G01X2378310Y959793D02*
X2378272Y959820D01*
X2378244Y959892D01*
X2378234Y959990D01*
G01X2378310Y956644D02*
X2378272Y956670D01*
X2378244Y956742D01*
X2378234Y956840D01*
G01X2378310Y953494D02*
X2378272Y953520D01*
X2378244Y953593D01*
X2378234Y953691D01*
G01X2378310Y950344D02*
X2378272Y950371D01*
X2378244Y950443D01*
X2378234Y950541D01*
G01X2378310Y947195D02*
X2378272Y947221D01*
X2378244Y947293D01*
X2378234Y947392D01*
G01X2378310Y944045D02*
X2378272Y944072D01*
X2378244Y944144D01*
X2378234Y944242D01*
G01X2378310Y940896D02*
X2378272Y940922D01*
X2378244Y940994D01*
X2378234Y941092D01*
G01X2378310Y937746D02*
X2378272Y937772D01*
X2378244Y937844D01*
X2378234Y937943D01*
G01X2378310Y934596D02*
X2378272Y934623D01*
X2378244Y934695D01*
X2378234Y934793D01*
G01X2378310Y931447D02*
X2378272Y931473D01*
X2378244Y931545D01*
X2378234Y931644D01*
G01X2378310Y928297D02*
X2378272Y928324D01*
X2378244Y928396D01*
X2378234Y928494D01*
G01X2378310Y925148D02*
X2378272Y925174D01*
X2378244Y925246D01*
X2378234Y925344D01*
G01X2378974Y932728D02*
X2378967Y932732D01*
X2378961Y932743D01*
X2378956Y932761D01*
X2378951Y932786D01*
X2378947Y932816D01*
X2378944Y932850D01*
X2378942Y932886D01*
X2378941Y932925D01*
G01X2378974Y929579D02*
X2378967Y929583D01*
X2378961Y929594D01*
X2378956Y929612D01*
X2378951Y929636D01*
X2378947Y929666D01*
X2378944Y929700D01*
X2378942Y929737D01*
X2378941Y929776D01*
G01X2378974Y926429D02*
X2378967Y926433D01*
X2378961Y926444D01*
X2378956Y926462D01*
X2378951Y926487D01*
X2378947Y926517D01*
X2378944Y926550D01*
X2378942Y926587D01*
X2378941Y926626D01*
G01X2378974Y923280D02*
X2378967Y923283D01*
X2378961Y923294D01*
X2378956Y923313D01*
X2378951Y923337D01*
X2378947Y923367D01*
X2378944Y923401D01*
X2378942Y923438D01*
X2378941Y923476D01*
G01X2382908Y966880D02*
X2383034Y966852D01*
X2383124Y966780D01*
X2383155Y966683D01*
G01X2377937Y932728D02*
X2377908Y932732D01*
X2377881Y932743D01*
X2377855Y932761D01*
X2377832Y932786D01*
X2377814Y932816D01*
X2377800Y932850D01*
X2377792Y932886D01*
X2377789Y932925D01*
G01X2377937Y929579D02*
X2377908Y929583D01*
X2377881Y929594D01*
X2377855Y929612D01*
X2377832Y929636D01*
X2377814Y929666D01*
X2377800Y929700D01*
X2377792Y929737D01*
X2377789Y929776D01*
G01X2377937Y926429D02*
X2377908Y926433D01*
X2377881Y926444D01*
X2377855Y926462D01*
X2377832Y926487D01*
X2377814Y926517D01*
X2377800Y926550D01*
X2377792Y926587D01*
X2377789Y926626D01*
G01X2377937Y923280D02*
X2377908Y923283D01*
X2377881Y923294D01*
X2377855Y923313D01*
X2377832Y923337D01*
X2377814Y923367D01*
X2377800Y923401D01*
X2377792Y923438D01*
X2377789Y923476D01*
G01X2378674Y993238D02*
X2385260D01*
G01X2378674Y992844D02*
X2385260D01*
G01X2384846Y992254D02*
X2379101D01*
G01X2382908Y992077D02*
X2376823D01*
G01X2376543Y991880D02*
X2383155D01*
G01Y991486D02*
X2376543D01*
G01X2382908Y991289D02*
X2376823D01*
G01X2382908Y988927D02*
X2376823D01*
G01X2382877Y988829D02*
X2377132D01*
G01X2376543Y988730D02*
X2383155D01*
G01Y988337D02*
X2376543D01*
G01X2376706Y988238D02*
X2383292D01*
G01X2382908Y988140D02*
X2376823D01*
G01X2376706Y987844D02*
X2383292D01*
G01X2382877Y987254D02*
X2377132D01*
G01X2382908Y985777D02*
X2376823D01*
G01X2376543Y985581D02*
X2383155D01*
G01Y985187D02*
X2376543D01*
G01X2382908Y984990D02*
X2376823D01*
G01X2382877Y983829D02*
X2377132D01*
G01X2376706Y983238D02*
X2383292D01*
G01X2376706Y982844D02*
X2383292D01*
G01X2382908Y982628D02*
X2376823D01*
G01X2376543Y982431D02*
X2383155D01*
G01X2382877Y982254D02*
X2377132D01*
G01X2383155Y982037D02*
X2376543D01*
G01X2382908Y981840D02*
X2376823D01*
G01X2382908Y979478D02*
X2376823D01*
G01X2376543Y979281D02*
X2383155D01*
G01Y978888D02*
X2376543D01*
G01X2382877Y978829D02*
X2377132D01*
G01X2382908Y978691D02*
X2376823D01*
G01X2376706Y978238D02*
X2383292D01*
G01X2376706Y977844D02*
X2383292D01*
G01X2382877Y977254D02*
X2377132D01*
G01X2382908Y976329D02*
X2376823D01*
G01X2376543Y976132D02*
X2383155D01*
G01Y975738D02*
X2376543D01*
G01X2382908Y975541D02*
X2376823D01*
G01X2382877Y973829D02*
X2377132D01*
G01X2376706Y973238D02*
X2383292D01*
G01X2382908Y973179D02*
X2376823D01*
G01X2376543Y972982D02*
X2383155D01*
G01X2376706Y972844D02*
X2383292D01*
G01X2383155Y972588D02*
X2376543D01*
G01X2382908Y972392D02*
X2376823D01*
G01X2382877Y972254D02*
X2377132D01*
G01X2382908Y970029D02*
X2376823D01*
G01X2376543Y969833D02*
X2383155D01*
G01Y969439D02*
X2376543D01*
G01X2382908Y969242D02*
X2376823D01*
G01X2382877Y968829D02*
X2377132D01*
G01X2376706Y968238D02*
X2383292D01*
G01X2376706Y967844D02*
X2383292D01*
G01X2382877Y967254D02*
X2377132D01*
G01X2382908Y966880D02*
X2376823D01*
G01X2376543Y966683D02*
X2383155D01*
G01Y966289D02*
X2376543D01*
G01X2382908Y966092D02*
X2376823D01*
G01X2382877Y963829D02*
X2377132D01*
G01X2382908Y963730D02*
X2376823D01*
G01X2376543Y963533D02*
X2383155D01*
G01X2376706Y963238D02*
X2383292D01*
G01X2383155Y963140D02*
X2376543D01*
G01X2382908Y962943D02*
X2376823D01*
G01X2376706Y962844D02*
X2383292D01*
G01X2382877Y962254D02*
X2377132D01*
G01X2382908Y960581D02*
X2376823D01*
G01X2376543Y960384D02*
X2383155D01*
G01Y959990D02*
X2376543D01*
G01X2382908Y959793D02*
X2376823D01*
G01X2382877Y958829D02*
X2377132D01*
G01X2376706Y958238D02*
X2383292D01*
G01X2376706Y957844D02*
X2383292D01*
G01X2382908Y957431D02*
X2376823D01*
G01X2382877Y957254D02*
X2377132D01*
G01X2376543Y957234D02*
X2383155D01*
G01Y956840D02*
X2376543D01*
G01X2382908Y956644D02*
X2376823D01*
G01X2382908Y954281D02*
X2376823D01*
G01X2376543Y954085D02*
X2383155D01*
G01X2384846Y953829D02*
X2379101D01*
G01X2383155Y953691D02*
X2376543D01*
G01X2382908Y953494D02*
X2376823D01*
G01X2378674Y953238D02*
X2385260D01*
G01X2378674Y952844D02*
X2385260D01*
G01X2384846Y952254D02*
X2379101D01*
G01X2382908Y951132D02*
X2376823D01*
G01X2376543Y950935D02*
X2383155D01*
G01Y950541D02*
X2376543D01*
G01X2382908Y950344D02*
X2376823D01*
G01X2382877Y948829D02*
X2377132D01*
G01X2376706Y948238D02*
X2383292D01*
G01X2382908Y947982D02*
X2376823D01*
G01X2376706Y947844D02*
X2383292D01*
G01X2376543Y947785D02*
X2383155D01*
G01Y947392D02*
X2376543D01*
G01X2382877Y947254D02*
X2377132D01*
G01X2382908Y947195D02*
X2376823D01*
G01X2382908Y944833D02*
X2376823D01*
G01X2376543Y944636D02*
X2383155D01*
G01Y944242D02*
X2376543D01*
G01X2382908Y944045D02*
X2376823D01*
G01X2382877Y943829D02*
X2377132D01*
G01X2376706Y943238D02*
X2383292D01*
G01X2376706Y942844D02*
X2383292D01*
G01X2382877Y942254D02*
X2377132D01*
G01X2382908Y941683D02*
X2376823D01*
G01X2376543Y941486D02*
X2383155D01*
G01Y941092D02*
X2376543D01*
G01X2382908Y940896D02*
X2376823D01*
G01X2382977Y938829D02*
X2377064D01*
G01X2382908Y938533D02*
X2376823D01*
G01X2376543Y938337D02*
X2383155D01*
G01X2376640Y938238D02*
X2383383D01*
G01X2383155Y937943D02*
X2376543D01*
G01X2376640Y937844D02*
X2383383D01*
G01X2382908Y937746D02*
X2376823D01*
G01X2382977Y937254D02*
X2377064D01*
G01X2380673Y936466D02*
X2387142D01*
G01X2382908Y935384D02*
X2376823D01*
G01X2376543Y935187D02*
X2383155D01*
G01Y934793D02*
X2376543D01*
G01X2382908Y934596D02*
X2376823D01*
G01X2377109Y934106D02*
X2382917D01*
G01X2383165Y933910D02*
X2376847D01*
G01Y932925D02*
X2383165D01*
G01X2377109Y932728D02*
X2382917D01*
G01X2382908Y932234D02*
X2376823D01*
G01X2376543Y932037D02*
X2383155D01*
G01Y931644D02*
X2376543D01*
G01X2382908Y931447D02*
X2376823D01*
G01X2377109Y930957D02*
X2382917D01*
G01X2383165Y930760D02*
X2376847D01*
G01Y929776D02*
X2383165D01*
G01X2377109Y929579D02*
X2382917D01*
G01X2382908Y929085D02*
X2376823D01*
G01X2376543Y928888D02*
X2383155D01*
G01Y928494D02*
X2376543D01*
G01X2382908Y928297D02*
X2376823D01*
G01X2377109Y927807D02*
X2382917D01*
G01X2383165Y927610D02*
X2376847D01*
G01Y926626D02*
X2383165D01*
G01X2377109Y926429D02*
X2382917D01*
G01X2382908Y925935D02*
X2376823D01*
G01X2376543Y925738D02*
X2383155D01*
G01Y925344D02*
X2376543D01*
G01X2382908Y925148D02*
X2376823D01*
G01X2377109Y924658D02*
X2382917D01*
G01X2383165Y924461D02*
X2376847D01*
G01Y923476D02*
X2383165D01*
G01X2377109Y923280D02*
X2382917D01*
G01X2382908Y922785D02*
X2376823D01*
G01X2376543Y922588D02*
X2383155D01*
G01X2377859Y992077D02*
X2377832Y992073D01*
X2377806Y992062D01*
X2377782Y992044D01*
X2377761Y992019D01*
X2377744Y991989D01*
X2377731Y991955D01*
X2377723Y991919D01*
X2377721Y991880D01*
G01X2377859Y988927D02*
X2377832Y988923D01*
X2377806Y988912D01*
X2377782Y988894D01*
X2377761Y988869D01*
X2377744Y988840D01*
X2377731Y988806D01*
X2377723Y988769D01*
X2377721Y988730D01*
G01X2377859Y985777D02*
X2377832Y985774D01*
X2377806Y985763D01*
X2377782Y985745D01*
X2377761Y985720D01*
X2377744Y985690D01*
X2377731Y985656D01*
X2377723Y985620D01*
X2377721Y985581D01*
G01X2377859Y982628D02*
X2377832Y982624D01*
X2377806Y982613D01*
X2377782Y982595D01*
X2377761Y982570D01*
X2377744Y982541D01*
X2377731Y982507D01*
X2377723Y982470D01*
X2377721Y982431D01*
G01X2377859Y979478D02*
X2377832Y979475D01*
X2377806Y979463D01*
X2377782Y979445D01*
X2377761Y979421D01*
X2377744Y979391D01*
X2377731Y979357D01*
X2377723Y979320D01*
X2377721Y979281D01*
G01X2377859Y976329D02*
X2377832Y976325D01*
X2377806Y976314D01*
X2377782Y976296D01*
X2377761Y976271D01*
X2377744Y976241D01*
X2377731Y976207D01*
X2377723Y976171D01*
X2377721Y976132D01*
G01X2377859Y973179D02*
X2377832Y973175D01*
X2377806Y973164D01*
X2377782Y973146D01*
X2377761Y973121D01*
X2377744Y973092D01*
X2377731Y973058D01*
X2377723Y973021D01*
X2377721Y972982D01*
G01X2377859Y970029D02*
X2377832Y970026D01*
X2377806Y970015D01*
X2377782Y969997D01*
X2377761Y969972D01*
X2377744Y969942D01*
X2377731Y969908D01*
X2377723Y969871D01*
X2377721Y969833D01*
G01X2377859Y966880D02*
X2377832Y966876D01*
X2377806Y966865D01*
X2377782Y966847D01*
X2377761Y966822D01*
X2377744Y966792D01*
X2377731Y966759D01*
X2377723Y966722D01*
X2377721Y966683D01*
G01X2377859Y963730D02*
X2377832Y963726D01*
X2377806Y963715D01*
X2377782Y963697D01*
X2377761Y963673D01*
X2377744Y963643D01*
X2377731Y963609D01*
X2377723Y963572D01*
X2377721Y963533D01*
G01X2377859Y960581D02*
X2377832Y960577D01*
X2377806Y960566D01*
X2377782Y960548D01*
X2377761Y960523D01*
X2377744Y960493D01*
X2377731Y960459D01*
X2377723Y960423D01*
X2377721Y960384D01*
G01X2377859Y957431D02*
X2377832Y957427D01*
X2377806Y957416D01*
X2377782Y957398D01*
X2377761Y957373D01*
X2377744Y957344D01*
X2377731Y957310D01*
X2377723Y957273D01*
X2377721Y957234D01*
G01X2377859Y954281D02*
X2377832Y954278D01*
X2377806Y954267D01*
X2377782Y954249D01*
X2377761Y954224D01*
X2377744Y954194D01*
X2377731Y954160D01*
X2377723Y954123D01*
X2377721Y954085D01*
G01X2377859Y951132D02*
X2377832Y951128D01*
X2377806Y951117D01*
X2377782Y951099D01*
X2377761Y951074D01*
X2377744Y951044D01*
X2377731Y951011D01*
X2377723Y950974D01*
X2377721Y950935D01*
G01X2377859Y947982D02*
X2377832Y947978D01*
X2377806Y947967D01*
X2377782Y947949D01*
X2377761Y947925D01*
X2377744Y947895D01*
X2377731Y947861D01*
X2377723Y947824D01*
X2377721Y947785D01*
G01X2377859Y944833D02*
X2377832Y944829D01*
X2377806Y944818D01*
X2377782Y944800D01*
X2377761Y944775D01*
X2377744Y944745D01*
X2377731Y944711D01*
X2377723Y944675D01*
X2377721Y944636D01*
G01X2382908Y991289D02*
X2383035Y991317D01*
X2383124Y991390D01*
X2383155Y991486D01*
G01X2382908Y988140D02*
X2383035Y988167D01*
X2383124Y988240D01*
X2383155Y988337D01*
G01X2382908Y984990D02*
X2383035Y985018D01*
X2383124Y985091D01*
X2383155Y985187D01*
G01X2382908Y981840D02*
X2383035Y981868D01*
X2383124Y981941D01*
X2383155Y982037D01*
G01X2382908Y978691D02*
X2383035Y978719D01*
X2383124Y978791D01*
X2383155Y978888D01*
G01X2382908Y975541D02*
X2383035Y975569D01*
X2383124Y975642D01*
X2383155Y975738D01*
G01X2382908Y972392D02*
X2383035Y972419D01*
X2383124Y972492D01*
X2383155Y972588D01*
G01X2377859Y941683D02*
X2377832Y941679D01*
X2377806Y941668D01*
X2377782Y941650D01*
X2377761Y941625D01*
X2377744Y941596D01*
X2377731Y941562D01*
X2377723Y941525D01*
X2377721Y941486D01*
G01X2377859Y938533D02*
X2377832Y938530D01*
X2377806Y938519D01*
X2377782Y938500D01*
X2377761Y938476D01*
X2377744Y938446D01*
X2377731Y938412D01*
X2377723Y938375D01*
X2377721Y938337D01*
G01X2377859Y935384D02*
X2377832Y935380D01*
X2377806Y935369D01*
X2377782Y935351D01*
X2377761Y935326D01*
X2377744Y935296D01*
X2377731Y935263D01*
X2377723Y935226D01*
X2377721Y935187D01*
G01X2377859Y932234D02*
X2377832Y932230D01*
X2377806Y932219D01*
X2377782Y932201D01*
X2377761Y932177D01*
X2377744Y932147D01*
X2377731Y932113D01*
X2377723Y932076D01*
X2377721Y932037D01*
G01X2377859Y929085D02*
X2377832Y929081D01*
X2377806Y929070D01*
X2377782Y929052D01*
X2377761Y929027D01*
X2377744Y928997D01*
X2377731Y928963D01*
X2377723Y928927D01*
X2377721Y928888D01*
G01X2377859Y925935D02*
X2377832Y925931D01*
X2377806Y925920D01*
X2377782Y925902D01*
X2377761Y925877D01*
X2377744Y925848D01*
X2377731Y925814D01*
X2377723Y925777D01*
X2377721Y925738D01*
G01X2377859Y922785D02*
X2377832Y922782D01*
X2377806Y922770D01*
X2377782Y922752D01*
X2377761Y922728D01*
X2377744Y922698D01*
X2377731Y922664D01*
X2377723Y922627D01*
X2377721Y922588D01*
G01X2382917Y932728D02*
X2383044Y932756D01*
X2383133Y932829D01*
X2383165Y932925D01*
G01X2382917Y929579D02*
X2383044Y929606D01*
X2383133Y929679D01*
X2383165Y929776D01*
G01X2382917Y926429D02*
X2383044Y926457D01*
X2383133Y926529D01*
X2383165Y926626D01*
G01X2382917Y923280D02*
X2383044Y923307D01*
X2383133Y923380D01*
X2383165Y923476D01*
G01X2382908Y969242D02*
X2383035Y969270D01*
X2383124Y969343D01*
X2383155Y969439D01*
G01X2382908Y962943D02*
X2383035Y962971D01*
X2383124Y963043D01*
X2383155Y963140D01*
G01X2382908Y959793D02*
X2383035Y959821D01*
X2383124Y959894D01*
X2383155Y959990D01*
G01X2382908Y956644D02*
X2383035Y956671D01*
X2383124Y956744D01*
X2383155Y956840D01*
G01X2382908Y953494D02*
X2383035Y953522D01*
X2383124Y953595D01*
X2383155Y953691D01*
G01X2382908Y950344D02*
X2383035Y950372D01*
X2383124Y950445D01*
X2383155Y950541D01*
G01X2382908Y947195D02*
X2383035Y947223D01*
X2383124Y947295D01*
X2383155Y947392D01*
G01X2382908Y944045D02*
X2383035Y944073D01*
X2383124Y944146D01*
X2383155Y944242D01*
G01X2382908Y940896D02*
X2383035Y940923D01*
X2383124Y940996D01*
X2383155Y941092D01*
G01X2382908Y937746D02*
X2383035Y937774D01*
X2383124Y937847D01*
X2383155Y937943D01*
G01X2382908Y934596D02*
X2383035Y934624D01*
X2383124Y934697D01*
X2383155Y934793D01*
G01X2382908Y931447D02*
X2383035Y931475D01*
X2383124Y931547D01*
X2383155Y931644D01*
G01X2382908Y928297D02*
X2383035Y928325D01*
X2383124Y928398D01*
X2383155Y928494D01*
G01X2382908Y925148D02*
X2383035Y925175D01*
X2383124Y925248D01*
X2383155Y925344D01*
G01X2471000Y960610D02*
G03X2439504I-15748J0D01*
G01X2471000D02*
G03X2439504I-15748J0D01*
G01X2471000D02*
G03X2439504I-15748J0D01*
G01Y946831D02*
G03X2471000I15748J0D01*
G01X2439504D02*
G03X2471000I15748J0D01*
G01X2439504D02*
G03X2471000I15748J0D01*
G01X2439504D02*
Y960610D01*
G01Y946831D02*
Y960610D01*
G01Y946831D02*
Y960610D01*
G01X2383155Y994636D02*
X2383122Y994537D01*
X2383034Y994466D01*
X2382908Y994439D01*
G01X2378234Y995029D02*
X2378244Y995128D01*
X2378272Y995200D01*
X2378310Y995226D01*
G01X2383155Y994636D02*
Y995029D01*
G01X2378234Y994636D02*
Y995029D01*
G01X2377721D02*
Y994636D01*
G01X2376543Y995029D02*
Y994636D01*
G01X2377721D02*
X2377723Y994597D01*
X2377731Y994561D01*
X2377744Y994527D01*
X2377761Y994497D01*
X2377782Y994472D01*
X2377806Y994454D01*
X2377832Y994443D01*
X2377859Y994439D01*
G01X2378310D02*
X2378272Y994465D01*
X2378244Y994537D01*
X2378234Y994636D01*
G01X2382908Y995226D02*
X2383034Y995199D01*
X2383124Y995126D01*
X2383155Y995029D01*
G01X2382908Y995226D02*
X2376823D01*
G01X2376543Y995029D02*
X2383155D01*
G01Y994636D02*
X2376543D01*
G01X2382908Y994439D02*
X2376823D01*
G01X2384846Y993829D02*
X2379101D01*
G01X2377859Y995226D02*
X2377832Y995223D01*
X2377806Y995211D01*
X2377782Y995193D01*
X2377761Y995169D01*
X2377744Y995139D01*
X2377731Y995105D01*
X2377723Y995068D01*
X2377721Y995029D01*
G01X2385173Y1011860D02*
X2387142Y1013829D01*
G01X2377132Y998829D02*
X2376706Y998238D01*
G01X2377132Y1003829D02*
X2376706Y1003238D01*
G01X2377132Y1008829D02*
X2376706Y1008238D01*
G01X2382877Y997254D02*
X2383017Y997450D01*
X2383155Y997647D01*
X2383292Y997844D01*
G01X2382877Y1002254D02*
X2383017Y1002450D01*
X2383155Y1002647D01*
X2383292Y1002844D01*
G01X2382877Y1007254D02*
X2383017Y1007450D01*
X2383155Y1007647D01*
X2383292Y1007844D01*
G01X2377549Y998238D02*
X2377822Y998829D01*
G01X2377549Y1003238D02*
X2377822Y1003829D01*
G01X2377549Y1008238D02*
X2377822Y1008829D01*
G01X2378674Y998238D02*
X2378752Y998829D01*
G01Y1003829D02*
X2378674Y1003238D01*
G01Y1008238D02*
X2378752Y1008829D01*
G01X2378234Y998179D02*
X2378244Y998277D01*
X2378272Y998349D01*
X2378310Y998376D01*
G01X2378234Y1001329D02*
X2378244Y1001427D01*
X2378272Y1001499D01*
X2378310Y1001525D01*
G01X2378234Y1004478D02*
X2378244Y1004577D01*
X2378272Y1004649D01*
X2378310Y1004675D01*
G01X2378234Y1007628D02*
X2378244Y1007726D01*
X2378272Y1007798D01*
X2378310Y1007825D01*
G01X2383292Y998238D02*
Y997844D01*
G01Y1003238D02*
Y1002844D01*
G01Y1008238D02*
Y1007844D01*
G01X2383155Y1007234D02*
Y1007628D01*
G01Y1004085D02*
Y1004478D01*
G01Y1000935D02*
Y1001329D01*
G01Y997785D02*
Y998179D01*
G01X2378674Y1002844D02*
Y1003238D01*
G01Y998238D02*
Y997844D01*
G01Y1008238D02*
Y1007844D01*
G01X2378234Y1007234D02*
Y1007628D01*
G01Y1004085D02*
Y1004478D01*
G01Y1000935D02*
Y1001329D01*
G01Y997785D02*
Y998179D01*
G01X2377721D02*
Y997785D01*
G01Y1004478D02*
Y1004085D01*
G01Y1001329D02*
Y1000935D01*
G01Y1007628D02*
Y1007234D01*
G01X2377549Y1007844D02*
Y1008238D01*
G01Y1002844D02*
Y1003238D01*
G01Y997844D02*
Y998238D01*
G01X2376706Y1007844D02*
Y1008238D01*
G01Y1002844D02*
Y1003238D01*
G01Y997844D02*
Y998238D01*
G01X2376543Y998179D02*
Y997785D01*
G01Y1004478D02*
Y1004085D01*
G01Y1001329D02*
Y1000935D01*
G01Y1007628D02*
Y1007234D01*
G01X2378674Y1007844D02*
X2378752Y1007254D01*
G01Y1002254D02*
X2378674Y1002844D01*
G01Y997844D02*
X2378752Y997254D01*
G01X2377721Y1007234D02*
X2377723Y1007196D01*
X2377731Y1007159D01*
X2377744Y1007125D01*
X2377761Y1007095D01*
X2377782Y1007071D01*
X2377806Y1007052D01*
X2377832Y1007041D01*
X2377859Y1007037D01*
G01X2377721Y1004085D02*
X2377723Y1004046D01*
X2377731Y1004010D01*
X2377744Y1003976D01*
X2377761Y1003945D01*
X2377782Y1003921D01*
X2377806Y1003903D01*
X2377832Y1003892D01*
X2377859Y1003888D01*
G01X2377721Y1000935D02*
X2377723Y1000897D01*
X2377731Y1000860D01*
X2377744Y1000826D01*
X2377761Y1000796D01*
X2377782Y1000771D01*
X2377806Y1000753D01*
X2377832Y1000742D01*
X2377859Y1000738D01*
G01X2377721Y997785D02*
X2377723Y997747D01*
X2377731Y997710D01*
X2377744Y997676D01*
X2377761Y997646D01*
X2377782Y997622D01*
X2377806Y997604D01*
X2377832Y997592D01*
X2377859Y997588D01*
G01X2383155Y1007628D02*
X2383123Y1007725D01*
X2383035Y1007797D01*
X2382908Y1007825D01*
G01X2383155Y1004478D02*
X2383123Y1004575D01*
X2383035Y1004647D01*
X2382908Y1004675D01*
G01X2383155Y1001329D02*
X2383123Y1001426D01*
X2383035Y1001498D01*
X2382908Y1001525D01*
G01X2383155Y998179D02*
X2383123Y998276D01*
X2383035Y998348D01*
X2382908Y998376D01*
G01X2377822Y1007254D02*
X2377549Y1007844D01*
G01X2377822Y1002254D02*
X2377549Y1002844D01*
G01X2377822Y997254D02*
X2377549Y997844D01*
G01X2383292Y1008238D02*
X2383155Y1008436D01*
X2383017Y1008633D01*
X2382877Y1008829D01*
G01X2383292Y1003238D02*
X2383155Y1003436D01*
X2383017Y1003633D01*
X2382877Y1003829D01*
G01X2383292Y998238D02*
X2383155Y998436D01*
X2383017Y998633D01*
X2382877Y998829D01*
G01X2377132Y1007254D02*
X2376706Y1007844D01*
G01X2377132Y1002254D02*
X2376706Y1002844D01*
G01X2377132Y997254D02*
X2376706Y997844D01*
G01X2385173Y1016781D02*
X2387142Y1014813D01*
G01X2378310Y1007037D02*
X2378272Y1007064D01*
X2378244Y1007136D01*
X2378234Y1007234D01*
G01X2378310Y1003888D02*
X2378272Y1003914D01*
X2378244Y1003986D01*
X2378234Y1004085D01*
G01X2378310Y1000738D02*
X2378272Y1000765D01*
X2378244Y1000837D01*
X2378234Y1000935D01*
G01X2378310Y997588D02*
X2378272Y997615D01*
X2378244Y997687D01*
X2378234Y997785D01*
G01X2390425Y1016781D02*
X2387142D01*
G01X2382877Y1008829D02*
X2377132D01*
G01X2376706Y1008238D02*
X2383292D01*
G01X2376706Y1007844D02*
X2383292D01*
G01X2382908Y1007825D02*
X2376823D01*
G01X2376543Y1007628D02*
X2383155D01*
G01X2382877Y1007254D02*
X2377132D01*
G01X2383155Y1007234D02*
X2376543D01*
G01X2382908Y1007037D02*
X2376823D01*
G01X2382908Y1004675D02*
X2376823D01*
G01X2376543Y1004478D02*
X2383155D01*
G01Y1004085D02*
X2376543D01*
G01X2382908Y1003888D02*
X2376823D01*
G01X2382877Y1003829D02*
X2377132D01*
G01X2376706Y1003238D02*
X2383292D01*
G01X2376706Y1002844D02*
X2383292D01*
G01X2382877Y1002254D02*
X2377132D01*
G01X2382908Y1001525D02*
X2376823D01*
G01X2376543Y1001329D02*
X2383155D01*
G01Y1000935D02*
X2376543D01*
G01X2382908Y1000738D02*
X2376823D01*
G01X2382877Y998829D02*
X2377132D01*
G01X2382908Y998376D02*
X2376823D01*
G01X2376706Y998238D02*
X2383292D01*
G01X2376543Y998179D02*
X2383155D01*
G01X2376706Y997844D02*
X2383292D01*
G01X2383155Y997785D02*
X2376543D01*
G01X2382908Y997588D02*
X2376823D01*
G01X2382877Y997254D02*
X2377132D01*
G01X2377859Y1007825D02*
X2377832Y1007821D01*
X2377806Y1007810D01*
X2377782Y1007792D01*
X2377761Y1007767D01*
X2377744Y1007737D01*
X2377731Y1007704D01*
X2377723Y1007667D01*
X2377721Y1007628D01*
G01X2377859Y1004675D02*
X2377832Y1004671D01*
X2377806Y1004660D01*
X2377782Y1004642D01*
X2377761Y1004617D01*
X2377744Y1004588D01*
X2377731Y1004554D01*
X2377723Y1004517D01*
X2377721Y1004478D01*
G01X2377859Y1001525D02*
X2377832Y1001522D01*
X2377806Y1001511D01*
X2377782Y1001493D01*
X2377761Y1001468D01*
X2377744Y1001438D01*
X2377731Y1001404D01*
X2377723Y1001368D01*
X2377721Y1001329D01*
G01X2377859Y998376D02*
X2377832Y998372D01*
X2377806Y998361D01*
X2377782Y998343D01*
X2377761Y998318D01*
X2377744Y998289D01*
X2377731Y998255D01*
X2377723Y998218D01*
X2377721Y998179D01*
G01X2382908Y1007037D02*
X2383035Y1007065D01*
X2383124Y1007138D01*
X2383155Y1007234D01*
G01X2382908Y1003888D02*
X2383035Y1003915D01*
X2383124Y1003988D01*
X2383155Y1004085D01*
G01X2382908Y1000738D02*
X2383035Y1000766D01*
X2383124Y1000839D01*
X2383155Y1000935D01*
G01X2382908Y997588D02*
X2383035Y997616D01*
X2383124Y997689D01*
X2383155Y997785D01*
G01X2390425Y1016781D02*
X2393835Y1018750D01*
G01X2389168Y1024398D02*
X2389114Y1024020D01*
G01X2389168Y1024396D02*
X2389205Y1024720D01*
X2389199Y1024961D01*
X2389142Y1025097D01*
G01X2393835Y1018750D02*
Y1020482D01*
G01X2389110Y1016781D02*
Y1023947D01*
G01X2389142Y1025097D02*
X2389199Y1024957D01*
X2389204Y1024717D01*
G01X2393835Y1020482D02*
X2389110Y1025128D01*
G01X2389114Y1024020D02*
X2393835Y1019379D01*
G01X2387142Y1279813D02*
Y1422293D01*
G01X2386020Y1417766D02*
Y1284340D01*
G01X2385961Y1314951D02*
Y1283947D01*
G01X2387142Y1282766D02*
X2385173Y1284734D01*
G01X2387142Y1281781D02*
X2385173Y1279813D01*
G01X2390425D02*
X2387142D01*
G01X2389169Y1272188D02*
X2389114Y1272574D01*
G01X2393835Y1277844D02*
Y1276112D01*
G01X2389110Y1272648D02*
Y1279813D01*
G01X2389142Y1271498D02*
X2389198Y1271632D01*
X2389205Y1271868D01*
X2389168Y1272197D01*
G01X2389142Y1271498D02*
X2389199Y1271638D01*
X2389204Y1271877D01*
G01X2393835Y1276112D02*
X2389110Y1271466D01*
G01X2393835Y1277215D02*
X2389114Y1272574D01*
G01X2390425Y1279813D02*
X2393835Y1277844D01*
G01X2385173Y1284734D02*
Y1417372D01*
G01X2378674Y1353356D02*
X2378752Y1352766D01*
G01X2378674Y1348356D02*
X2378752Y1347766D01*
G01X2378674Y1343356D02*
X2378752Y1342766D01*
G01X2378674Y1318356D02*
X2378752Y1317766D01*
G01X2378674Y1313356D02*
X2378752Y1312766D01*
G01X2378674Y1308356D02*
X2378752Y1307766D01*
G01X2378674Y1303356D02*
X2378752Y1302766D01*
G01X2378674Y1298356D02*
X2378752Y1297766D01*
G01X2378674Y1293356D02*
X2378752Y1292766D01*
G01X2378674Y1288356D02*
X2378752Y1287766D01*
G01X2383155Y1356447D02*
X2383123Y1356544D01*
X2383035Y1356616D01*
X2382908Y1356644D01*
G01X2383155Y1353297D02*
X2383123Y1353394D01*
X2383035Y1353466D01*
X2382908Y1353494D01*
G01X2383155Y1350148D02*
X2383123Y1350245D01*
X2383035Y1350317D01*
X2382908Y1350344D01*
G01X2383155Y1346998D02*
X2383123Y1347095D01*
X2383035Y1347167D01*
X2382908Y1347195D01*
G01X2383155Y1343848D02*
X2383123Y1343945D01*
X2383035Y1344018D01*
X2382908Y1344045D01*
G01X2383155Y1340699D02*
X2383123Y1340796D01*
X2383035Y1340868D01*
X2382908Y1340896D01*
G01X2383155Y1337549D02*
X2383123Y1337646D01*
X2383035Y1337718D01*
X2382908Y1337746D01*
G01X2383155Y1334400D02*
X2383123Y1334497D01*
X2383035Y1334569D01*
X2382908Y1334596D01*
G01X2383155Y1331250D02*
X2383123Y1331347D01*
X2383035Y1331419D01*
X2382908Y1331447D01*
G01X2383155Y1328100D02*
X2383123Y1328197D01*
X2383035Y1328269D01*
X2382908Y1328297D01*
G01X2383155Y1324951D02*
X2383123Y1325048D01*
X2383035Y1325120D01*
X2382908Y1325148D01*
G01X2383155Y1321801D02*
X2383123Y1321898D01*
X2383035Y1321970D01*
X2382908Y1321998D01*
G01X2383155Y1318651D02*
X2383123Y1318748D01*
X2383035Y1318821D01*
X2382908Y1318848D01*
G01X2383155Y1315502D02*
X2383123Y1315599D01*
X2383035Y1315671D01*
X2382908Y1315699D01*
G01X2383155Y1312352D02*
X2383123Y1312449D01*
X2383035Y1312521D01*
X2382908Y1312549D01*
G01X2383155Y1309203D02*
X2383123Y1309300D01*
X2383035Y1309372D01*
X2382908Y1309400D01*
G01X2383155Y1306053D02*
X2383123Y1306150D01*
X2383035Y1306222D01*
X2382908Y1306250D01*
G01X2383155Y1302903D02*
X2383123Y1303000D01*
X2383035Y1303073D01*
X2382908Y1303100D01*
G01X2383155Y1299754D02*
X2383123Y1299851D01*
X2383035Y1299923D01*
X2382908Y1299951D01*
G01X2383155Y1296604D02*
X2383123Y1296701D01*
X2383035Y1296773D01*
X2382908Y1296801D01*
G01X2383155Y1293455D02*
X2383123Y1293552D01*
X2383035Y1293624D01*
X2382908Y1293651D01*
G01X2383155Y1290305D02*
X2383123Y1290402D01*
X2383035Y1290474D01*
X2382908Y1290502D01*
G01X2383165Y1339421D02*
X2383132Y1339520D01*
X2383043Y1339591D01*
X2382917Y1339618D01*
G01X2383165Y1336272D02*
X2383132Y1336371D01*
X2383043Y1336442D01*
X2382917Y1336469D01*
G01X2383165Y1333122D02*
X2383132Y1333221D01*
X2383043Y1333292D01*
X2382917Y1333319D01*
G01X2383165Y1329973D02*
X2383132Y1330072D01*
X2383043Y1330142D01*
X2382917Y1330169D01*
G01X2383165Y1326823D02*
X2383132Y1326922D01*
X2383043Y1326993D01*
X2382917Y1327020D01*
G01X2383165Y1323673D02*
X2383132Y1323772D01*
X2383043Y1323843D01*
X2382917Y1323870D01*
G01X2377822Y1352766D02*
X2377549Y1353356D01*
G01X2377822Y1347766D02*
X2377549Y1348356D01*
G01X2377822Y1342766D02*
X2377549Y1343356D01*
G01X2378674Y1288750D02*
X2378752Y1289340D01*
G01X2378674Y1293750D02*
X2378752Y1294340D01*
G01X2378674Y1298750D02*
X2378752Y1299340D01*
G01X2378674Y1303750D02*
X2378752Y1304340D01*
G01X2378674Y1308750D02*
X2378752Y1309340D01*
G01X2378674Y1313750D02*
X2378752Y1314340D01*
G01X2378674Y1318750D02*
X2378752Y1319340D01*
G01X2378674Y1343750D02*
X2378752Y1344340D01*
G01X2378674Y1348750D02*
X2378752Y1349340D01*
G01X2378674Y1353750D02*
X2378752Y1354340D01*
G01X2378234Y1293455D02*
X2378244Y1293553D01*
X2378272Y1293625D01*
X2378310Y1293651D01*
G01X2378234Y1296604D02*
X2378244Y1296703D01*
X2378272Y1296775D01*
X2378310Y1296801D01*
G01X2378234Y1309203D02*
X2378244Y1309301D01*
X2378272Y1309373D01*
X2378310Y1309400D01*
G01X2378234Y1312352D02*
X2378244Y1312451D01*
X2378272Y1312523D01*
X2378310Y1312549D01*
G01X2378234Y1321801D02*
X2378244Y1321899D01*
X2378272Y1321972D01*
X2378310Y1321998D01*
G01X2378234Y1324951D02*
X2378244Y1325049D01*
X2378272Y1325121D01*
X2378310Y1325148D01*
G01X2378234Y1328100D02*
X2378244Y1328199D01*
X2378272Y1328271D01*
X2378310Y1328297D01*
G01X2378234Y1331250D02*
X2378244Y1331348D01*
X2378272Y1331420D01*
X2378310Y1331447D01*
G01X2378234Y1337549D02*
X2378244Y1337647D01*
X2378272Y1337720D01*
X2378310Y1337746D01*
G01X2378234Y1340699D02*
X2378244Y1340797D01*
X2378272Y1340869D01*
X2378310Y1340896D01*
G01X2378234Y1343848D02*
X2378244Y1343947D01*
X2378272Y1344019D01*
X2378310Y1344045D01*
G01X2378234Y1346998D02*
X2378244Y1347096D01*
X2378272Y1347168D01*
X2378310Y1347195D01*
G01X2378234Y1350148D02*
X2378244Y1350246D01*
X2378272Y1350318D01*
X2378310Y1350344D01*
G01X2378234Y1353297D02*
X2378244Y1353395D01*
X2378272Y1353468D01*
X2378310Y1353494D01*
G01X2378234Y1356447D02*
X2378244Y1356545D01*
X2378272Y1356617D01*
X2378310Y1356644D01*
G01X2377789Y1323673D02*
X2377792Y1323712D01*
X2377800Y1323748D01*
X2377814Y1323782D01*
X2377832Y1323813D01*
X2377855Y1323837D01*
X2377880Y1323855D01*
X2377908Y1323866D01*
X2377937Y1323870D01*
G01X2377789Y1326823D02*
X2377792Y1326861D01*
X2377800Y1326898D01*
X2377814Y1326932D01*
X2377832Y1326962D01*
X2377855Y1326987D01*
X2377880Y1327005D01*
X2377908Y1327016D01*
X2377937Y1327020D01*
G01X2377789Y1329973D02*
X2377792Y1330011D01*
X2377800Y1330048D01*
X2377814Y1330081D01*
X2377832Y1330112D01*
X2377855Y1330136D01*
X2377880Y1330154D01*
X2377908Y1330165D01*
X2377937Y1330169D01*
G01X2377789Y1333122D02*
X2377792Y1333160D01*
X2377800Y1333197D01*
X2377814Y1333231D01*
X2377832Y1333261D01*
X2377855Y1333286D01*
X2377880Y1333304D01*
X2377908Y1333315D01*
X2377937Y1333319D01*
G01X2377789Y1336272D02*
X2377792Y1336310D01*
X2377800Y1336347D01*
X2377814Y1336381D01*
X2377832Y1336411D01*
X2377855Y1336435D01*
X2377880Y1336453D01*
X2377908Y1336465D01*
X2377937Y1336469D01*
G01X2377789Y1339421D02*
X2377792Y1339460D01*
X2377800Y1339496D01*
X2377814Y1339530D01*
X2377832Y1339561D01*
X2377855Y1339585D01*
X2377880Y1339603D01*
X2377908Y1339614D01*
X2377937Y1339618D01*
G01X2378941Y1323673D02*
X2378942Y1323712D01*
X2378943Y1323748D01*
X2378946Y1323782D01*
X2378951Y1323813D01*
X2378955Y1323837D01*
X2378961Y1323855D01*
X2378967Y1323866D01*
X2378974Y1323870D01*
G01X2378941Y1326823D02*
X2378942Y1326861D01*
X2378943Y1326898D01*
X2378946Y1326932D01*
X2378951Y1326962D01*
X2378955Y1326987D01*
X2378961Y1327005D01*
X2378967Y1327016D01*
X2378974Y1327020D01*
G01X2378941Y1329973D02*
X2378942Y1330011D01*
X2378943Y1330048D01*
X2378946Y1330081D01*
X2378951Y1330112D01*
X2378955Y1330136D01*
X2378961Y1330154D01*
X2378967Y1330165D01*
X2378974Y1330169D01*
G01X2378941Y1333122D02*
X2378942Y1333160D01*
X2378943Y1333197D01*
X2378946Y1333231D01*
X2378951Y1333261D01*
X2378955Y1333286D01*
X2378961Y1333304D01*
X2378967Y1333315D01*
X2378974Y1333319D01*
G01X2378941Y1336272D02*
X2378942Y1336310D01*
X2378943Y1336347D01*
X2378946Y1336381D01*
X2378951Y1336411D01*
X2378955Y1336435D01*
X2378961Y1336453D01*
X2378967Y1336465D01*
X2378974Y1336469D01*
G01X2378941Y1339421D02*
X2378942Y1339460D01*
X2378943Y1339496D01*
X2378946Y1339530D01*
X2378951Y1339561D01*
X2378955Y1339585D01*
X2378961Y1339603D01*
X2378967Y1339614D01*
X2378974Y1339618D01*
G01X2386130Y1320332D02*
Y1314951D01*
G01Y1347254D02*
Y1341774D01*
G01X2385961Y1320128D02*
Y1341978D01*
G01Y1418159D02*
Y1347254D01*
G01X2383383Y1318750D02*
Y1318356D01*
G01Y1343750D02*
Y1343356D01*
G01X2383292Y1288750D02*
Y1288356D01*
G01Y1293750D02*
Y1293356D01*
G01Y1298750D02*
Y1298356D01*
G01Y1303750D02*
Y1303356D01*
G01Y1308750D02*
Y1308356D01*
G01Y1313750D02*
Y1313356D01*
G01Y1348750D02*
Y1348356D01*
G01Y1353750D02*
Y1353356D01*
G01X2383165Y1323673D02*
Y1322689D01*
G01Y1326823D02*
Y1325839D01*
G01Y1329973D02*
Y1328988D01*
G01Y1333122D02*
Y1332138D01*
G01Y1336272D02*
Y1335287D01*
G01Y1339421D02*
Y1338437D01*
G01X2383155Y1356053D02*
Y1356447D01*
G01Y1352903D02*
Y1353297D01*
G01Y1349754D02*
Y1350148D01*
G01Y1346604D02*
Y1346998D01*
G01Y1343455D02*
Y1343848D01*
G01Y1340305D02*
Y1340699D01*
G01Y1334006D02*
Y1334400D01*
G01Y1337155D02*
Y1337549D01*
G01Y1330856D02*
Y1331250D01*
G01Y1324557D02*
Y1324951D01*
G01Y1327707D02*
Y1328100D01*
G01Y1321407D02*
Y1321801D01*
G01Y1318258D02*
Y1318651D01*
G01Y1315108D02*
Y1315502D01*
G01Y1311959D02*
Y1312352D01*
G01Y1308809D02*
Y1309203D01*
G01Y1305659D02*
Y1306053D01*
G01Y1302510D02*
Y1302903D01*
G01Y1299360D02*
Y1299754D01*
G01Y1296211D02*
Y1296604D01*
G01Y1293061D02*
Y1293455D01*
G01Y1289911D02*
Y1290305D01*
G01X2380673Y1321309D02*
Y1320128D01*
G01Y1341978D02*
Y1340797D01*
G01X2378941Y1338437D02*
Y1339421D01*
G01Y1332138D02*
Y1333122D01*
G01Y1335287D02*
Y1336272D01*
G01Y1328988D02*
Y1329973D01*
G01Y1322689D02*
Y1323673D01*
G01Y1325839D02*
Y1326823D01*
G01X2378674Y1288750D02*
Y1288356D01*
G01Y1293750D02*
Y1293356D01*
G01Y1298750D02*
Y1298356D01*
G01Y1303750D02*
Y1303356D01*
G01Y1308750D02*
Y1308356D01*
G01Y1313750D02*
Y1313356D01*
G01Y1318750D02*
Y1318356D01*
G01Y1343750D02*
Y1343356D01*
G01Y1348750D02*
Y1348356D01*
G01Y1353750D02*
Y1353356D01*
G01X2378234Y1356053D02*
Y1356447D01*
G01Y1352903D02*
Y1353297D01*
G01Y1349754D02*
Y1350148D01*
G01Y1346604D02*
Y1346998D01*
G01Y1343455D02*
Y1343848D01*
G01Y1340305D02*
Y1340699D01*
G01Y1334006D02*
Y1334400D01*
G01Y1337155D02*
Y1337549D01*
G01Y1330856D02*
Y1331250D01*
G01Y1324557D02*
Y1324951D01*
G01Y1327707D02*
Y1328100D01*
G01Y1321407D02*
Y1321801D01*
G01Y1318258D02*
Y1318651D01*
G01Y1315108D02*
Y1315502D01*
G01Y1311959D02*
Y1312352D01*
G01Y1308809D02*
Y1309203D01*
G01Y1305659D02*
Y1306053D01*
G01Y1302510D02*
Y1302903D01*
G01Y1299360D02*
Y1299754D01*
G01Y1296211D02*
Y1296604D01*
G01Y1293061D02*
Y1293455D01*
G01Y1289911D02*
Y1290305D01*
G01X2377789Y1338437D02*
Y1339421D01*
G01Y1332138D02*
Y1333122D01*
G01Y1335287D02*
Y1336272D01*
G01Y1328988D02*
Y1329973D01*
G01Y1322689D02*
Y1323673D01*
G01Y1325839D02*
Y1326823D01*
G01X2377721Y1290305D02*
Y1289911D01*
G01Y1293455D02*
Y1293061D01*
G01Y1299754D02*
Y1299360D01*
G01Y1296604D02*
Y1296211D01*
G01Y1302903D02*
Y1302510D01*
G01Y1309203D02*
Y1308809D01*
G01Y1306053D02*
Y1305659D01*
G01Y1312352D02*
Y1311959D01*
G01Y1318651D02*
Y1318258D01*
G01Y1315502D02*
Y1315108D01*
G01Y1321801D02*
Y1321407D01*
G01Y1324951D02*
Y1324557D01*
G01Y1328100D02*
Y1327707D01*
G01Y1331250D02*
Y1330856D01*
G01Y1334400D02*
Y1334006D01*
G01Y1337549D02*
Y1337155D01*
G01Y1340699D02*
Y1340305D01*
G01Y1343848D02*
Y1343455D01*
G01Y1350148D02*
Y1349754D01*
G01Y1346998D02*
Y1346604D01*
G01Y1353297D02*
Y1352903D01*
G01Y1356447D02*
Y1356053D01*
G01X2377549Y1353356D02*
Y1353750D01*
G01Y1348356D02*
Y1348750D01*
G01Y1343356D02*
Y1343750D01*
G01Y1318356D02*
Y1318750D01*
G01Y1313356D02*
Y1313750D01*
G01Y1308356D02*
Y1308750D01*
G01Y1303356D02*
Y1303750D01*
G01Y1298356D02*
Y1298750D01*
G01Y1293356D02*
Y1293750D01*
G01Y1288356D02*
Y1288750D01*
G01X2376847Y1338437D02*
Y1339421D01*
G01Y1332138D02*
Y1333122D01*
G01Y1335287D02*
Y1336272D01*
G01Y1328988D02*
Y1329973D01*
G01Y1322689D02*
Y1323673D01*
G01Y1325839D02*
Y1326823D01*
G01X2376706Y1353356D02*
Y1353750D01*
G01Y1348356D02*
Y1348750D01*
G01Y1313356D02*
Y1313750D01*
G01Y1308356D02*
Y1308750D01*
G01Y1303356D02*
Y1303750D01*
G01Y1298356D02*
Y1298750D01*
G01Y1293356D02*
Y1293750D01*
G01Y1288356D02*
Y1288750D01*
G01X2376640Y1343356D02*
Y1343750D01*
G01Y1318356D02*
Y1318750D01*
G01X2376543Y1290305D02*
Y1289911D01*
G01Y1293455D02*
Y1293061D01*
G01Y1299754D02*
Y1299360D01*
G01Y1296604D02*
Y1296211D01*
G01Y1302903D02*
Y1302510D01*
G01Y1309203D02*
Y1308809D01*
G01Y1306053D02*
Y1305659D01*
G01Y1312352D02*
Y1311959D01*
G01Y1318651D02*
Y1318258D01*
G01Y1315502D02*
Y1315108D01*
G01Y1321801D02*
Y1321407D01*
G01Y1324951D02*
Y1324557D01*
G01Y1328100D02*
Y1327707D01*
G01Y1331250D02*
Y1330856D01*
G01Y1334400D02*
Y1334006D01*
G01Y1337549D02*
Y1337155D01*
G01Y1340699D02*
Y1340305D01*
G01Y1343848D02*
Y1343455D01*
G01Y1350148D02*
Y1349754D01*
G01Y1346998D02*
Y1346604D01*
G01Y1353297D02*
Y1352903D01*
G01Y1356447D02*
Y1356053D01*
G01X2377721D02*
X2377723Y1356015D01*
X2377731Y1355978D01*
X2377744Y1355944D01*
X2377761Y1355914D01*
X2377782Y1355889D01*
X2377806Y1355871D01*
X2377832Y1355860D01*
X2377859Y1355856D01*
G01X2377721Y1352903D02*
X2377723Y1352865D01*
X2377731Y1352828D01*
X2377744Y1352795D01*
X2377761Y1352764D01*
X2377782Y1352740D01*
X2377806Y1352722D01*
X2377832Y1352710D01*
X2377859Y1352707D01*
G01X2377721Y1349754D02*
X2377723Y1349716D01*
X2377731Y1349679D01*
X2377744Y1349645D01*
X2377761Y1349615D01*
X2377782Y1349590D01*
X2377806Y1349572D01*
X2377832Y1349561D01*
X2377859Y1349557D01*
G01X2377721Y1346604D02*
X2377723Y1346566D01*
X2377731Y1346529D01*
X2377744Y1346495D01*
X2377761Y1346465D01*
X2377782Y1346441D01*
X2377806Y1346423D01*
X2377832Y1346411D01*
X2377859Y1346407D01*
G01X2377721Y1343455D02*
X2377723Y1343416D01*
X2377731Y1343380D01*
X2377744Y1343346D01*
X2377761Y1343315D01*
X2377782Y1343291D01*
X2377806Y1343273D01*
X2377832Y1343262D01*
X2377859Y1343258D01*
G01X2377721Y1340305D02*
X2377723Y1340267D01*
X2377731Y1340230D01*
X2377744Y1340196D01*
X2377761Y1340166D01*
X2377782Y1340141D01*
X2377806Y1340123D01*
X2377832Y1340112D01*
X2377859Y1340108D01*
G01X2377721Y1337155D02*
X2377723Y1337117D01*
X2377731Y1337080D01*
X2377744Y1337046D01*
X2377761Y1337016D01*
X2377782Y1336992D01*
X2377806Y1336974D01*
X2377832Y1336962D01*
X2377859Y1336959D01*
G01X2377721Y1334006D02*
X2377723Y1333968D01*
X2377731Y1333931D01*
X2377744Y1333897D01*
X2377761Y1333867D01*
X2377782Y1333842D01*
X2377806Y1333824D01*
X2377832Y1333813D01*
X2377859Y1333809D01*
G01X2377721Y1330856D02*
X2377723Y1330818D01*
X2377731Y1330781D01*
X2377744Y1330747D01*
X2377761Y1330717D01*
X2377782Y1330693D01*
X2377806Y1330674D01*
X2377832Y1330663D01*
X2377859Y1330659D01*
G01X2377721Y1327707D02*
X2377723Y1327668D01*
X2377731Y1327632D01*
X2377744Y1327598D01*
X2377761Y1327567D01*
X2377782Y1327543D01*
X2377806Y1327525D01*
X2377832Y1327514D01*
X2377859Y1327510D01*
G01X2377721Y1324557D02*
X2377723Y1324519D01*
X2377731Y1324482D01*
X2377744Y1324448D01*
X2377761Y1324418D01*
X2377782Y1324393D01*
X2377806Y1324375D01*
X2377832Y1324364D01*
X2377859Y1324360D01*
G01X2377721Y1321407D02*
X2377723Y1321369D01*
X2377731Y1321332D01*
X2377744Y1321298D01*
X2377761Y1321268D01*
X2377782Y1321244D01*
X2377806Y1321226D01*
X2377832Y1321214D01*
X2377859Y1321211D01*
G01X2377721Y1318258D02*
X2377723Y1318220D01*
X2377731Y1318183D01*
X2377744Y1318149D01*
X2377761Y1318119D01*
X2377782Y1318094D01*
X2377806Y1318076D01*
X2377832Y1318065D01*
X2377859Y1318061D01*
G01X2377721Y1315108D02*
X2377723Y1315070D01*
X2377731Y1315033D01*
X2377744Y1314999D01*
X2377761Y1314969D01*
X2377782Y1314945D01*
X2377806Y1314926D01*
X2377832Y1314915D01*
X2377859Y1314911D01*
G01X2377721Y1311959D02*
X2377723Y1311920D01*
X2377731Y1311884D01*
X2377744Y1311850D01*
X2377761Y1311819D01*
X2377782Y1311795D01*
X2377806Y1311777D01*
X2377832Y1311766D01*
X2377859Y1311762D01*
G01X2377721Y1308809D02*
X2377723Y1308771D01*
X2377731Y1308734D01*
X2377744Y1308700D01*
X2377761Y1308670D01*
X2377782Y1308645D01*
X2377806Y1308627D01*
X2377832Y1308616D01*
X2377859Y1308612D01*
G01X2377721Y1305659D02*
X2377723Y1305621D01*
X2377731Y1305584D01*
X2377744Y1305550D01*
X2377761Y1305520D01*
X2377782Y1305496D01*
X2377806Y1305478D01*
X2377832Y1305466D01*
X2377859Y1305463D01*
G01X2377721Y1302510D02*
X2377723Y1302472D01*
X2377731Y1302435D01*
X2377744Y1302401D01*
X2377761Y1302371D01*
X2377782Y1302346D01*
X2377806Y1302328D01*
X2377832Y1302317D01*
X2377859Y1302313D01*
G01X2377721Y1299360D02*
X2377723Y1299322D01*
X2377731Y1299285D01*
X2377744Y1299251D01*
X2377761Y1299221D01*
X2377782Y1299197D01*
X2377806Y1299178D01*
X2377832Y1299167D01*
X2377859Y1299163D01*
G01X2377721Y1296211D02*
X2377723Y1296172D01*
X2377731Y1296136D01*
X2377744Y1296102D01*
X2377761Y1296071D01*
X2377782Y1296047D01*
X2377806Y1296029D01*
X2377832Y1296018D01*
X2377859Y1296014D01*
G01X2377721Y1293061D02*
X2377723Y1293023D01*
X2377731Y1292986D01*
X2377744Y1292952D01*
X2377761Y1292922D01*
X2377782Y1292897D01*
X2377806Y1292879D01*
X2377832Y1292868D01*
X2377859Y1292864D01*
G01X2377721Y1289911D02*
X2377723Y1289873D01*
X2377731Y1289836D01*
X2377744Y1289802D01*
X2377761Y1289772D01*
X2377782Y1289748D01*
X2377806Y1289730D01*
X2377832Y1289718D01*
X2377859Y1289714D01*
G01X2377822Y1317766D02*
X2377549Y1318356D01*
G01X2377822Y1312766D02*
X2377549Y1313356D01*
G01X2377822Y1307766D02*
X2377549Y1308356D01*
G01X2377822Y1302766D02*
X2377549Y1303356D01*
G01X2377822Y1297766D02*
X2377549Y1298356D01*
G01X2377822Y1292766D02*
X2377549Y1293356D01*
G01X2377822Y1287766D02*
X2377549Y1288356D01*
G01X2383383Y1343750D02*
X2383249Y1343947D01*
X2383113Y1344144D01*
X2382977Y1344340D01*
G01X2383383Y1318750D02*
X2383249Y1318947D01*
X2383113Y1319144D01*
X2382977Y1319340D01*
G01X2383292Y1353750D02*
X2383155Y1353948D01*
X2383017Y1354144D01*
X2382877Y1354340D01*
G01X2383292Y1348750D02*
X2383155Y1348948D01*
X2383017Y1349144D01*
X2382877Y1349340D01*
G01X2383292Y1313750D02*
X2383155Y1313948D01*
X2383017Y1314144D01*
X2382877Y1314340D01*
G01X2383292Y1308750D02*
X2383155Y1308948D01*
X2383017Y1309144D01*
X2382877Y1309340D01*
G01X2383292Y1303750D02*
X2383155Y1303948D01*
X2383017Y1304144D01*
X2382877Y1304340D01*
G01X2383292Y1298750D02*
X2383155Y1298948D01*
X2383017Y1299144D01*
X2382877Y1299340D01*
G01X2383292Y1293750D02*
X2383155Y1293948D01*
X2383017Y1294144D01*
X2382877Y1294340D01*
G01X2383292Y1288750D02*
X2383155Y1288948D01*
X2383017Y1289144D01*
X2382877Y1289340D01*
G01X2377064Y1342766D02*
X2376640Y1343356D01*
G01X2377064Y1317766D02*
X2376640Y1318356D01*
G01X2377132Y1352766D02*
X2376706Y1353356D01*
G01X2377132Y1347766D02*
X2376706Y1348356D01*
G01X2377132Y1312766D02*
X2376706Y1313356D01*
G01X2377132Y1307766D02*
X2376706Y1308356D01*
G01X2377132Y1302766D02*
X2376706Y1303356D01*
G01X2377132Y1297766D02*
X2376706Y1298356D01*
G01X2377132Y1292766D02*
X2376706Y1293356D01*
G01X2377132Y1287766D02*
X2376706Y1288356D01*
G01X2385173Y1321289D02*
X2387142Y1319321D01*
G01X2382877Y1287766D02*
X2383017Y1287962D01*
X2383155Y1288159D01*
X2383292Y1288356D01*
G01X2382877Y1292766D02*
X2383017Y1292962D01*
X2383155Y1293159D01*
X2383292Y1293356D01*
G01X2382877Y1297766D02*
X2383017Y1297962D01*
X2383155Y1298159D01*
X2383292Y1298356D01*
G01X2377549Y1288750D02*
X2377822Y1289340D01*
G01X2377549Y1293750D02*
X2377822Y1294340D01*
G01X2377549Y1298750D02*
X2377822Y1299340D01*
G01X2377549Y1303750D02*
X2377822Y1304340D01*
G01X2377549Y1308750D02*
X2377822Y1309340D01*
G01X2377549Y1313750D02*
X2377822Y1314340D01*
G01X2377549Y1318750D02*
X2377822Y1319340D01*
G01X2377549Y1343750D02*
X2377822Y1344340D01*
G01X2377549Y1348750D02*
X2377822Y1349340D01*
G01X2377549Y1353750D02*
X2377822Y1354340D01*
G01X2378310Y1355856D02*
X2378272Y1355883D01*
X2378244Y1355955D01*
X2378234Y1356053D01*
G01X2378310Y1352707D02*
X2378272Y1352733D01*
X2378244Y1352805D01*
X2378234Y1352903D01*
G01X2378310Y1349557D02*
X2378272Y1349583D01*
X2378244Y1349655D01*
X2378234Y1349754D01*
G01X2378310Y1346407D02*
X2378272Y1346434D01*
X2378244Y1346506D01*
X2378234Y1346604D01*
G01X2378310Y1343258D02*
X2378272Y1343284D01*
X2378244Y1343356D01*
X2378234Y1343455D01*
G01X2378310Y1340108D02*
X2378272Y1340135D01*
X2378244Y1340207D01*
X2378234Y1340305D01*
G01X2378310Y1336959D02*
X2378272Y1336985D01*
X2378244Y1337057D01*
X2378234Y1337155D01*
G01X2378310Y1333809D02*
X2378272Y1333835D01*
X2378244Y1333907D01*
X2378234Y1334006D01*
G01X2378310Y1330659D02*
X2378272Y1330686D01*
X2378244Y1330758D01*
X2378234Y1330856D01*
G01X2378310Y1327510D02*
X2378272Y1327536D01*
X2378244Y1327608D01*
X2378234Y1327707D01*
G01X2378310Y1324360D02*
X2378272Y1324387D01*
X2378244Y1324459D01*
X2378234Y1324557D01*
G01X2378310Y1321211D02*
X2378272Y1321237D01*
X2378244Y1321309D01*
X2378234Y1321407D01*
G01X2378310Y1318061D02*
X2378272Y1318087D01*
X2378244Y1318159D01*
X2378234Y1318258D01*
G01X2378310Y1314911D02*
X2378272Y1314938D01*
X2378244Y1315010D01*
X2378234Y1315108D01*
G01X2378310Y1311762D02*
X2378272Y1311788D01*
X2378244Y1311860D01*
X2378234Y1311959D01*
G01X2378310Y1308612D02*
X2378272Y1308639D01*
X2378244Y1308711D01*
X2378234Y1308809D01*
G01X2378310Y1305463D02*
X2378272Y1305489D01*
X2378244Y1305561D01*
X2378234Y1305659D01*
G01X2378310Y1302313D02*
X2378272Y1302339D01*
X2378244Y1302411D01*
X2378234Y1302510D01*
G01X2378310Y1299163D02*
X2378272Y1299190D01*
X2378244Y1299262D01*
X2378234Y1299360D01*
G01X2378310Y1296014D02*
X2378272Y1296040D01*
X2378244Y1296112D01*
X2378234Y1296211D01*
G01X2378310Y1292864D02*
X2378272Y1292891D01*
X2378244Y1292963D01*
X2378234Y1293061D01*
G01X2378310Y1289714D02*
X2378272Y1289741D01*
X2378244Y1289813D01*
X2378234Y1289911D01*
G01X2378974Y1338240D02*
X2378967Y1338244D01*
X2378961Y1338255D01*
X2378956Y1338273D01*
X2378951Y1338298D01*
X2378947Y1338328D01*
X2378944Y1338361D01*
X2378942Y1338398D01*
X2378941Y1338437D01*
G01X2378974Y1335091D02*
X2378967Y1335094D01*
X2378961Y1335105D01*
X2378956Y1335124D01*
X2378951Y1335148D01*
X2378947Y1335178D01*
X2378944Y1335212D01*
X2378942Y1335249D01*
X2378941Y1335287D01*
G01X2378974Y1331941D02*
X2378967Y1331945D01*
X2378961Y1331956D01*
X2378956Y1331974D01*
X2378951Y1331999D01*
X2378947Y1332028D01*
X2378944Y1332062D01*
X2378942Y1332099D01*
X2378941Y1332138D01*
G01X2378974Y1328791D02*
X2378967Y1328795D01*
X2378961Y1328806D01*
X2378956Y1328824D01*
X2378951Y1328849D01*
X2378947Y1328879D01*
X2378944Y1328913D01*
X2378942Y1328949D01*
X2378941Y1328988D01*
G01X2378974Y1325642D02*
X2378967Y1325646D01*
X2378961Y1325657D01*
X2378956Y1325675D01*
X2378951Y1325699D01*
X2378947Y1325729D01*
X2378944Y1325763D01*
X2378942Y1325800D01*
X2378941Y1325839D01*
G01X2378974Y1322492D02*
X2378967Y1322496D01*
X2378961Y1322507D01*
X2378956Y1322525D01*
X2378951Y1322550D01*
X2378947Y1322580D01*
X2378944Y1322613D01*
X2378942Y1322650D01*
X2378941Y1322689D01*
G01X2377132Y1289340D02*
X2376706Y1288750D01*
G01X2377132Y1294340D02*
X2376706Y1293750D01*
G01X2377132Y1299340D02*
X2376706Y1298750D01*
G01X2377132Y1304340D02*
X2376706Y1303750D01*
G01X2377132Y1309340D02*
X2376706Y1308750D01*
G01X2377132Y1314340D02*
X2376706Y1313750D01*
G01X2377132Y1349340D02*
X2376706Y1348750D01*
G01X2377132Y1354340D02*
X2376706Y1353750D01*
G01X2377064Y1319340D02*
X2376640Y1318750D01*
G01X2377064Y1344340D02*
X2376640Y1343750D01*
G01X2382877Y1302766D02*
X2383017Y1302962D01*
X2383155Y1303159D01*
X2383292Y1303356D01*
G01X2382877Y1307766D02*
X2383017Y1307962D01*
X2383155Y1308159D01*
X2383292Y1308356D01*
G01X2382877Y1312766D02*
X2383017Y1312962D01*
X2383155Y1313159D01*
X2383292Y1313356D01*
G01X2382877Y1347766D02*
X2383017Y1347962D01*
X2383155Y1348159D01*
X2383292Y1348356D01*
G01X2382877Y1352766D02*
X2383017Y1352962D01*
X2383155Y1353159D01*
X2383292Y1353356D01*
G01X2382977Y1317766D02*
X2383113Y1317962D01*
X2383249Y1318159D01*
X2383383Y1318356D01*
G01X2382977Y1342766D02*
X2383113Y1342962D01*
X2383249Y1343159D01*
X2383383Y1343356D01*
G01X2378310Y1290502D02*
X2378272Y1290475D01*
X2378244Y1290403D01*
X2378234Y1290305D01*
G01X2378310Y1299951D02*
X2378272Y1299924D01*
X2378244Y1299852D01*
X2378234Y1299754D01*
G01X2378310Y1303100D02*
X2378272Y1303074D01*
X2378244Y1303002D01*
X2378234Y1302903D01*
G01X2378310Y1306250D02*
X2378272Y1306223D01*
X2378244Y1306151D01*
X2378234Y1306053D01*
G01X2378310Y1315699D02*
X2378272Y1315672D01*
X2378244Y1315600D01*
X2378234Y1315502D01*
G01X2378310Y1318848D02*
X2378272Y1318822D01*
X2378244Y1318750D01*
X2378234Y1318651D01*
G01X2378310Y1334596D02*
X2378272Y1334570D01*
X2378244Y1334498D01*
X2378234Y1334400D01*
G01X2387142Y1342785D02*
X2385173Y1340817D01*
G01X2377937Y1338240D02*
X2377908Y1338244D01*
X2377881Y1338255D01*
X2377855Y1338273D01*
X2377832Y1338298D01*
X2377814Y1338328D01*
X2377800Y1338361D01*
X2377792Y1338398D01*
X2377789Y1338437D01*
G01X2377937Y1335091D02*
X2377908Y1335094D01*
X2377881Y1335105D01*
X2377855Y1335124D01*
X2377832Y1335148D01*
X2377814Y1335178D01*
X2377800Y1335212D01*
X2377792Y1335249D01*
X2377789Y1335287D01*
G01X2377937Y1331941D02*
X2377908Y1331945D01*
X2377881Y1331956D01*
X2377855Y1331974D01*
X2377832Y1331999D01*
X2377814Y1332028D01*
X2377800Y1332062D01*
X2377792Y1332099D01*
X2377789Y1332138D01*
G01X2377937Y1328791D02*
X2377908Y1328795D01*
X2377881Y1328806D01*
X2377855Y1328824D01*
X2377832Y1328849D01*
X2377814Y1328879D01*
X2377800Y1328913D01*
X2377792Y1328949D01*
X2377789Y1328988D01*
G01X2377937Y1325642D02*
X2377908Y1325646D01*
X2377881Y1325657D01*
X2377855Y1325675D01*
X2377832Y1325699D01*
X2377814Y1325729D01*
X2377800Y1325763D01*
X2377792Y1325800D01*
X2377789Y1325839D01*
G01X2377937Y1322492D02*
X2377908Y1322496D01*
X2377881Y1322507D01*
X2377855Y1322525D01*
X2377832Y1322550D01*
X2377814Y1322580D01*
X2377800Y1322613D01*
X2377792Y1322650D01*
X2377789Y1322689D01*
G01X2382908Y1356644D02*
X2376823D01*
G01X2376543Y1356447D02*
X2383155D01*
G01Y1356053D02*
X2376543D01*
G01X2382908Y1355856D02*
X2376823D01*
G01X2382877Y1354340D02*
X2377132D01*
G01X2376706Y1353750D02*
X2383292D01*
G01X2382908Y1353494D02*
X2376823D01*
G01X2376706Y1353356D02*
X2383292D01*
G01X2376543Y1353297D02*
X2383155D01*
G01Y1352903D02*
X2376543D01*
G01X2382877Y1352766D02*
X2377132D01*
G01X2382908Y1352707D02*
X2376823D01*
G01X2382908Y1350344D02*
X2376823D01*
G01X2376543Y1350148D02*
X2383155D01*
G01Y1349754D02*
X2376543D01*
G01X2382908Y1349557D02*
X2376823D01*
G01X2382877Y1349340D02*
X2377132D01*
G01X2376706Y1348750D02*
X2383292D01*
G01X2376706Y1348356D02*
X2383292D01*
G01X2382877Y1347766D02*
X2377132D01*
G01X2382908Y1347195D02*
X2376823D01*
G01X2376543Y1346998D02*
X2383155D01*
G01Y1346604D02*
X2376543D01*
G01X2382908Y1346407D02*
X2376823D01*
G01X2382977Y1344340D02*
X2377064D01*
G01X2382908Y1344045D02*
X2376823D01*
G01X2376543Y1343848D02*
X2383155D01*
G01X2376640Y1343750D02*
X2383383D01*
G01X2383155Y1343455D02*
X2376543D01*
G01X2376640Y1343356D02*
X2383383D01*
G01X2382908Y1343258D02*
X2376823D01*
G01X2382977Y1342766D02*
X2377064D01*
G01X2380673Y1341978D02*
X2387142D01*
G01X2382908Y1340896D02*
X2376823D01*
G01X2376543Y1340699D02*
X2383155D01*
G01Y1340305D02*
X2376543D01*
G01X2382908Y1340108D02*
X2376823D01*
G01X2377109Y1339618D02*
X2382917D01*
G01X2383165Y1339421D02*
X2376847D01*
G01Y1338437D02*
X2383165D01*
G01X2377109Y1338240D02*
X2382917D01*
G01X2382908Y1337746D02*
X2376823D01*
G01X2376543Y1337549D02*
X2383155D01*
G01Y1337155D02*
X2376543D01*
G01X2382908Y1336959D02*
X2376823D01*
G01X2377109Y1336469D02*
X2382917D01*
G01X2383165Y1336272D02*
X2376847D01*
G01Y1335287D02*
X2383165D01*
G01X2377109Y1335091D02*
X2382917D01*
G01X2382908Y1334596D02*
X2376823D01*
G01X2376543Y1334400D02*
X2383155D01*
G01Y1334006D02*
X2376543D01*
G01X2382908Y1333809D02*
X2376823D01*
G01X2377109Y1333319D02*
X2382917D01*
G01X2383165Y1333122D02*
X2376847D01*
G01Y1332138D02*
X2383165D01*
G01X2377109Y1331941D02*
X2382917D01*
G01X2382908Y1331447D02*
X2376823D01*
G01X2376543Y1331250D02*
X2383155D01*
G01Y1330856D02*
X2376543D01*
G01X2382908Y1330659D02*
X2376823D01*
G01X2377109Y1330169D02*
X2382917D01*
G01X2383165Y1329973D02*
X2376847D01*
G01Y1328988D02*
X2383165D01*
G01X2377109Y1328791D02*
X2382917D01*
G01X2382908Y1328297D02*
X2376823D01*
G01X2376543Y1328100D02*
X2383155D01*
G01Y1327707D02*
X2376543D01*
G01X2382908Y1327510D02*
X2376823D01*
G01X2377109Y1327020D02*
X2382917D01*
G01X2383165Y1326823D02*
X2376847D01*
G01Y1325839D02*
X2383165D01*
G01X2377109Y1325642D02*
X2382917D01*
G01X2382908Y1325148D02*
X2376823D01*
G01X2376543Y1324951D02*
X2383155D01*
G01Y1324557D02*
X2376543D01*
G01X2382908Y1324360D02*
X2376823D01*
G01X2377109Y1323870D02*
X2382917D01*
G01X2383165Y1323673D02*
X2376847D01*
G01Y1322689D02*
X2383165D01*
G01X2377109Y1322492D02*
X2382917D01*
G01X2382908Y1321998D02*
X2376823D01*
G01X2376543Y1321801D02*
X2383155D01*
G01Y1321407D02*
X2376543D01*
G01X2382908Y1321211D02*
X2376823D01*
G01X2387142Y1320128D02*
X2380673D01*
G01X2382977Y1319340D02*
X2377064D01*
G01X2382908Y1318848D02*
X2376823D01*
G01X2376640Y1318750D02*
X2383383D01*
G01X2376543Y1318651D02*
X2383155D01*
G01X2376640Y1318356D02*
X2383383D01*
G01X2383155Y1318258D02*
X2376543D01*
G01X2382908Y1318061D02*
X2376823D01*
G01X2382977Y1317766D02*
X2377064D01*
G01X2382908Y1315699D02*
X2376823D01*
G01X2376543Y1315502D02*
X2383155D01*
G01Y1315108D02*
X2376543D01*
G01X2382908Y1314911D02*
X2376823D01*
G01X2382877Y1314340D02*
X2377132D01*
G01X2376706Y1313750D02*
X2383292D01*
G01X2376706Y1313356D02*
X2383292D01*
G01X2382877Y1312766D02*
X2377132D01*
G01X2382908Y1312549D02*
X2376823D01*
G01X2376543Y1312352D02*
X2383155D01*
G01Y1311959D02*
X2376543D01*
G01X2382908Y1311762D02*
X2376823D01*
G01X2382908Y1309400D02*
X2376823D01*
G01X2382877Y1309340D02*
X2377132D01*
G01X2376543Y1309203D02*
X2383155D01*
G01Y1308809D02*
X2376543D01*
G01X2376706Y1308750D02*
X2383292D01*
G01X2382908Y1308612D02*
X2376823D01*
G01X2376706Y1308356D02*
X2383292D01*
G01X2382877Y1307766D02*
X2377132D01*
G01X2382908Y1306250D02*
X2376823D01*
G01X2376543Y1306053D02*
X2383155D01*
G01Y1305659D02*
X2376543D01*
G01X2382908Y1305463D02*
X2376823D01*
G01X2382877Y1304340D02*
X2377132D01*
G01X2376706Y1303750D02*
X2383292D01*
G01X2376706Y1303356D02*
X2383292D01*
G01X2382908Y1303100D02*
X2376823D01*
G01X2376543Y1302903D02*
X2383155D01*
G01X2382877Y1302766D02*
X2377132D01*
G01X2383155Y1302510D02*
X2376543D01*
G01X2382908Y1302313D02*
X2376823D01*
G01X2382908Y1299951D02*
X2376823D01*
G01X2376543Y1299754D02*
X2383155D01*
G01Y1299360D02*
X2376543D01*
G01X2382877Y1299340D02*
X2377132D01*
G01X2382908Y1299163D02*
X2376823D01*
G01X2376706Y1298750D02*
X2383292D01*
G01X2376706Y1298356D02*
X2383292D01*
G01X2382877Y1297766D02*
X2377132D01*
G01X2382908Y1296801D02*
X2376823D01*
G01X2376543Y1296604D02*
X2383155D01*
G01Y1296211D02*
X2376543D01*
G01X2382908Y1296014D02*
X2376823D01*
G01X2382877Y1294340D02*
X2377132D01*
G01X2376706Y1293750D02*
X2383292D01*
G01X2382908Y1293651D02*
X2376823D01*
G01X2376543Y1293455D02*
X2383155D01*
G01X2376706Y1293356D02*
X2383292D01*
G01X2383155Y1293061D02*
X2376543D01*
G01X2382908Y1292864D02*
X2376823D01*
G01X2382877Y1292766D02*
X2377132D01*
G01X2382908Y1290502D02*
X2376823D01*
G01X2376543Y1290305D02*
X2383155D01*
G01Y1289911D02*
X2376543D01*
G01X2382908Y1289714D02*
X2376823D01*
G01X2382877Y1289340D02*
X2377132D01*
G01X2376706Y1288750D02*
X2383292D01*
G01X2376706Y1288356D02*
X2383292D01*
G01X2382877Y1287766D02*
X2377132D01*
G01X2377859Y1356644D02*
X2377832Y1356640D01*
X2377806Y1356629D01*
X2377782Y1356611D01*
X2377761Y1356586D01*
X2377744Y1356556D01*
X2377731Y1356522D01*
X2377723Y1356486D01*
X2377721Y1356447D01*
G01X2377859Y1353494D02*
X2377832Y1353490D01*
X2377806Y1353479D01*
X2377782Y1353461D01*
X2377761Y1353436D01*
X2377744Y1353407D01*
X2377731Y1353373D01*
X2377723Y1353336D01*
X2377721Y1353297D01*
G01X2377859Y1350344D02*
X2377832Y1350341D01*
X2377806Y1350330D01*
X2377782Y1350311D01*
X2377761Y1350287D01*
X2377744Y1350257D01*
X2377731Y1350223D01*
X2377723Y1350186D01*
X2377721Y1350148D01*
G01X2377859Y1347195D02*
X2377832Y1347191D01*
X2377806Y1347180D01*
X2377782Y1347162D01*
X2377761Y1347137D01*
X2377744Y1347107D01*
X2377731Y1347074D01*
X2377723Y1347037D01*
X2377721Y1346998D01*
G01X2377859Y1344045D02*
X2377832Y1344041D01*
X2377806Y1344030D01*
X2377782Y1344012D01*
X2377761Y1343988D01*
X2377744Y1343958D01*
X2377731Y1343924D01*
X2377723Y1343887D01*
X2377721Y1343848D01*
G01X2377859Y1340896D02*
X2377832Y1340892D01*
X2377806Y1340881D01*
X2377782Y1340863D01*
X2377761Y1340838D01*
X2377744Y1340808D01*
X2377731Y1340774D01*
X2377723Y1340738D01*
X2377721Y1340699D01*
G01X2377859Y1337746D02*
X2377832Y1337742D01*
X2377806Y1337731D01*
X2377782Y1337713D01*
X2377761Y1337688D01*
X2377744Y1337659D01*
X2377731Y1337625D01*
X2377723Y1337588D01*
X2377721Y1337549D01*
G01X2377859Y1334596D02*
X2377832Y1334593D01*
X2377806Y1334582D01*
X2377782Y1334563D01*
X2377761Y1334539D01*
X2377744Y1334509D01*
X2377731Y1334475D01*
X2377723Y1334438D01*
X2377721Y1334400D01*
G01X2377859Y1331447D02*
X2377832Y1331443D01*
X2377806Y1331432D01*
X2377782Y1331414D01*
X2377761Y1331389D01*
X2377744Y1331359D01*
X2377731Y1331326D01*
X2377723Y1331289D01*
X2377721Y1331250D01*
G01X2377859Y1328297D02*
X2377832Y1328293D01*
X2377806Y1328282D01*
X2377782Y1328264D01*
X2377761Y1328239D01*
X2377744Y1328210D01*
X2377731Y1328176D01*
X2377723Y1328139D01*
X2377721Y1328100D01*
G01X2377859Y1325148D02*
X2377832Y1325144D01*
X2377806Y1325133D01*
X2377782Y1325115D01*
X2377761Y1325090D01*
X2377744Y1325060D01*
X2377731Y1325026D01*
X2377723Y1324990D01*
X2377721Y1324951D01*
G01X2377859Y1321998D02*
X2377832Y1321994D01*
X2377806Y1321983D01*
X2377782Y1321965D01*
X2377761Y1321940D01*
X2377744Y1321911D01*
X2377731Y1321877D01*
X2377723Y1321840D01*
X2377721Y1321801D01*
G01X2377859Y1318848D02*
X2377832Y1318845D01*
X2377806Y1318833D01*
X2377782Y1318815D01*
X2377761Y1318791D01*
X2377744Y1318761D01*
X2377731Y1318727D01*
X2377723Y1318690D01*
X2377721Y1318651D01*
G01X2377859Y1315699D02*
X2377832Y1315695D01*
X2377806Y1315684D01*
X2377782Y1315666D01*
X2377761Y1315641D01*
X2377744Y1315611D01*
X2377731Y1315578D01*
X2377723Y1315541D01*
X2377721Y1315502D01*
G01X2377859Y1312549D02*
X2377832Y1312545D01*
X2377806Y1312534D01*
X2377782Y1312516D01*
X2377761Y1312491D01*
X2377744Y1312462D01*
X2377731Y1312428D01*
X2377723Y1312391D01*
X2377721Y1312352D01*
G01X2377859Y1309400D02*
X2377832Y1309396D01*
X2377806Y1309385D01*
X2377782Y1309367D01*
X2377761Y1309342D01*
X2377744Y1309312D01*
X2377731Y1309278D01*
X2377723Y1309242D01*
X2377721Y1309203D01*
G01X2377859Y1306250D02*
X2377832Y1306246D01*
X2377806Y1306235D01*
X2377782Y1306217D01*
X2377761Y1306192D01*
X2377744Y1306163D01*
X2377731Y1306129D01*
X2377723Y1306092D01*
X2377721Y1306053D01*
G01X2377859Y1303100D02*
X2377832Y1303097D01*
X2377806Y1303085D01*
X2377782Y1303067D01*
X2377761Y1303043D01*
X2377744Y1303013D01*
X2377731Y1302979D01*
X2377723Y1302942D01*
X2377721Y1302903D01*
G01X2377859Y1299951D02*
X2377832Y1299947D01*
X2377806Y1299936D01*
X2377782Y1299918D01*
X2377761Y1299893D01*
X2377744Y1299863D01*
X2377731Y1299829D01*
X2377723Y1299793D01*
X2377721Y1299754D01*
G01X2377859Y1296801D02*
X2377832Y1296797D01*
X2377806Y1296786D01*
X2377782Y1296768D01*
X2377761Y1296743D01*
X2377744Y1296714D01*
X2377731Y1296680D01*
X2377723Y1296643D01*
X2377721Y1296604D01*
G01X2377859Y1293651D02*
X2377832Y1293648D01*
X2377806Y1293637D01*
X2377782Y1293619D01*
X2377761Y1293594D01*
X2377744Y1293564D01*
X2377731Y1293530D01*
X2377723Y1293494D01*
X2377721Y1293455D01*
G01X2377859Y1290502D02*
X2377832Y1290498D01*
X2377806Y1290487D01*
X2377782Y1290469D01*
X2377761Y1290444D01*
X2377744Y1290415D01*
X2377731Y1290381D01*
X2377723Y1290344D01*
X2377721Y1290305D01*
G01X2382917Y1338240D02*
X2383044Y1338268D01*
X2383133Y1338340D01*
X2383165Y1338437D01*
G01X2382917Y1335091D02*
X2383044Y1335118D01*
X2383133Y1335191D01*
X2383165Y1335287D01*
G01X2382917Y1331941D02*
X2383044Y1331968D01*
X2383133Y1332041D01*
X2383165Y1332138D01*
G01X2382917Y1328791D02*
X2383044Y1328819D01*
X2383133Y1328891D01*
X2383165Y1328988D01*
G01X2382917Y1325642D02*
X2383044Y1325669D01*
X2383133Y1325742D01*
X2383165Y1325839D01*
G01X2382917Y1322492D02*
X2383044Y1322520D01*
X2383133Y1322592D01*
X2383165Y1322689D01*
G01X2382908Y1355856D02*
X2383035Y1355884D01*
X2383124Y1355957D01*
X2383155Y1356053D01*
G01X2382908Y1352707D02*
X2383035Y1352734D01*
X2383124Y1352807D01*
X2383155Y1352903D01*
G01X2382908Y1349557D02*
X2383035Y1349585D01*
X2383124Y1349658D01*
X2383155Y1349754D01*
G01X2382908Y1346407D02*
X2383035Y1346435D01*
X2383124Y1346508D01*
X2383155Y1346604D01*
G01X2382908Y1343258D02*
X2383035Y1343286D01*
X2383124Y1343358D01*
X2383155Y1343455D01*
G01X2382908Y1340108D02*
X2383035Y1340136D01*
X2383124Y1340209D01*
X2383155Y1340305D01*
G01X2382908Y1336959D02*
X2383035Y1336986D01*
X2383124Y1337059D01*
X2383155Y1337155D01*
G01X2382908Y1333809D02*
X2383035Y1333837D01*
X2383124Y1333910D01*
X2383155Y1334006D01*
G01X2382908Y1330659D02*
X2383035Y1330687D01*
X2383124Y1330760D01*
X2383155Y1330856D01*
G01X2382908Y1327510D02*
X2383035Y1327537D01*
X2383124Y1327610D01*
X2383155Y1327707D01*
G01X2382908Y1324360D02*
X2383035Y1324388D01*
X2383124Y1324461D01*
X2383155Y1324557D01*
G01X2382908Y1321211D02*
X2383035Y1321238D01*
X2383124Y1321311D01*
X2383155Y1321407D01*
G01X2382908Y1318061D02*
X2383035Y1318089D01*
X2383124Y1318162D01*
X2383155Y1318258D01*
G01X2382908Y1314911D02*
X2383035Y1314939D01*
X2383124Y1315012D01*
X2383155Y1315108D01*
G01X2382908Y1311762D02*
X2383035Y1311789D01*
X2383124Y1311862D01*
X2383155Y1311959D01*
G01X2382908Y1308612D02*
X2383035Y1308640D01*
X2383124Y1308713D01*
X2383155Y1308809D01*
G01X2382908Y1305463D02*
X2383035Y1305490D01*
X2383124Y1305563D01*
X2383155Y1305659D01*
G01X2382908Y1302313D02*
X2383035Y1302341D01*
X2383124Y1302414D01*
X2383155Y1302510D01*
G01X2382908Y1299163D02*
X2383035Y1299191D01*
X2383124Y1299264D01*
X2383155Y1299360D01*
G01X2382908Y1296014D02*
X2383035Y1296041D01*
X2383124Y1296114D01*
X2383155Y1296211D01*
G01X2382908Y1292864D02*
X2383035Y1292892D01*
X2383124Y1292965D01*
X2383155Y1293061D01*
G01X2382908Y1289714D02*
X2383035Y1289742D01*
X2383124Y1289815D01*
X2383155Y1289911D01*
G01X2471000Y1356280D02*
G03X2439504I-15748J0D01*
G01X2471000D02*
G03X2439504I-15748J0D01*
G01X2471000D02*
G03X2439504I-15748J0D01*
G01Y1342500D02*
G03X2471000I15748J0D01*
G01X2439504D02*
G03X2471000I15748J0D01*
G01X2439504D02*
G03X2471000I15748J0D01*
G01X2439504D02*
Y1356280D01*
G01Y1342500D02*
Y1356280D01*
G01Y1342500D02*
Y1356280D01*
G01X2380643Y1358356D02*
X2380720Y1357766D01*
G01X2383155Y1359596D02*
X2383123Y1359693D01*
X2383035Y1359766D01*
X2382908Y1359793D01*
G01X2379791Y1357766D02*
X2379518Y1358356D01*
G01X2385260Y1358750D02*
X2385123Y1358948D01*
X2384985Y1359144D01*
X2384846Y1359340D01*
G01X2380643Y1358750D02*
X2380720Y1359340D01*
G01X2378234Y1359596D02*
X2378244Y1359695D01*
X2378272Y1359767D01*
X2378310Y1359793D01*
G01X2385260Y1358750D02*
Y1358356D01*
G01X2383155Y1359203D02*
Y1359596D01*
G01X2380643Y1358750D02*
Y1358356D01*
G01X2379518D02*
Y1358750D01*
G01X2378674Y1358356D02*
Y1358750D01*
G01X2378234Y1359203D02*
Y1359596D01*
G01X2377721D02*
Y1359203D01*
G01X2376543Y1359596D02*
Y1359203D01*
G01X2377721D02*
X2377723Y1359164D01*
X2377731Y1359128D01*
X2377744Y1359094D01*
X2377761Y1359063D01*
X2377782Y1359039D01*
X2377806Y1359021D01*
X2377832Y1359010D01*
X2377859Y1359006D01*
G01X2379101Y1357766D02*
X2378674Y1358356D01*
G01X2379518Y1358750D02*
X2379791Y1359340D01*
G01X2378310Y1359006D02*
X2378272Y1359032D01*
X2378244Y1359104D01*
X2378234Y1359203D01*
G01X2379101Y1359340D02*
X2378674Y1358750D01*
G01X2384846Y1357766D02*
X2384985Y1357962D01*
X2385123Y1358159D01*
X2385260Y1358356D01*
G01X2382908Y1359793D02*
X2376823D01*
G01X2376543Y1359596D02*
X2383155D01*
G01X2384846Y1359340D02*
X2379101D01*
G01X2383155Y1359203D02*
X2376543D01*
G01X2382908Y1359006D02*
X2376823D01*
G01X2378674Y1358750D02*
X2385260D01*
G01X2378674Y1358356D02*
X2385260D01*
G01X2384846Y1357766D02*
X2379101D01*
G01X2377859Y1359793D02*
X2377832Y1359789D01*
X2377806Y1359778D01*
X2377782Y1359760D01*
X2377761Y1359736D01*
X2377744Y1359706D01*
X2377731Y1359672D01*
X2377723Y1359635D01*
X2377721Y1359596D01*
G01X2382908Y1359006D02*
X2383035Y1359034D01*
X2383124Y1359106D01*
X2383155Y1359203D01*
G01X2378674Y1413356D02*
X2378752Y1412766D01*
G01X2380643Y1398356D02*
X2380720Y1397766D01*
G01X2378752Y1407766D02*
X2378674Y1408356D01*
G01Y1403356D02*
X2378752Y1402766D01*
G01X2378674Y1393356D02*
X2378752Y1392766D01*
G01X2378674Y1388356D02*
X2378752Y1387766D01*
G01X2378674Y1383356D02*
X2378752Y1382766D01*
G01X2378674Y1378356D02*
X2378752Y1377766D01*
G01X2378674Y1373356D02*
X2378752Y1372766D01*
G01X2378674Y1368356D02*
X2378752Y1367766D01*
G01X2378674Y1363356D02*
X2378752Y1362766D01*
G01X2383155Y1413140D02*
X2383123Y1413237D01*
X2383035Y1413309D01*
X2382908Y1413337D01*
G01X2383155Y1409990D02*
X2383123Y1410087D01*
X2383035Y1410159D01*
X2382908Y1410187D01*
G01X2383155Y1406840D02*
X2383123Y1406937D01*
X2383035Y1407010D01*
X2382908Y1407037D01*
G01X2383155Y1403691D02*
X2383123Y1403788D01*
X2383035Y1403860D01*
X2382908Y1403888D01*
G01X2383155Y1397392D02*
X2383123Y1397489D01*
X2383035Y1397561D01*
X2382908Y1397588D01*
G01X2383155Y1394242D02*
X2383123Y1394339D01*
X2383035Y1394411D01*
X2382908Y1394439D01*
G01X2383155Y1391092D02*
X2383123Y1391189D01*
X2383035Y1391262D01*
X2382908Y1391289D01*
G01X2383155Y1387943D02*
X2383123Y1388040D01*
X2383035Y1388112D01*
X2382908Y1388140D01*
G01X2383155Y1384793D02*
X2383123Y1384890D01*
X2383035Y1384962D01*
X2382908Y1384990D01*
G01X2383155Y1381644D02*
X2383123Y1381741D01*
X2383035Y1381813D01*
X2382908Y1381840D01*
G01X2383155Y1378494D02*
X2383123Y1378591D01*
X2383035Y1378663D01*
X2382908Y1378691D01*
G01X2383155Y1375344D02*
X2383123Y1375441D01*
X2383035Y1375514D01*
X2382908Y1375541D01*
G01X2383155Y1369045D02*
X2383123Y1369142D01*
X2383035Y1369214D01*
X2382908Y1369242D01*
G01X2383155Y1365896D02*
X2383123Y1365993D01*
X2383035Y1366065D01*
X2382908Y1366092D01*
G01X2383155Y1362746D02*
X2383123Y1362843D01*
X2383035Y1362915D01*
X2382908Y1362943D01*
G01X2377822Y1412766D02*
X2377549Y1413356D01*
G01X2377822Y1407766D02*
X2377549Y1408356D01*
G01X2377822Y1402766D02*
X2377549Y1403356D01*
G01X2379791Y1397766D02*
X2379518Y1398356D01*
G01X2377822Y1392766D02*
X2377549Y1393356D01*
G01X2377822Y1387766D02*
X2377549Y1388356D01*
G01X2377822Y1382766D02*
X2377549Y1383356D01*
G01X2377822Y1377766D02*
X2377549Y1378356D01*
G01X2377822Y1372766D02*
X2377549Y1373356D01*
G01X2377822Y1367766D02*
X2377549Y1368356D01*
G01X2377822Y1362766D02*
X2377549Y1363356D01*
G01X2383292Y1413750D02*
X2383155Y1413948D01*
X2383017Y1414144D01*
X2382877Y1414340D01*
G01X2383292Y1408750D02*
X2383155Y1408948D01*
X2383017Y1409144D01*
X2382877Y1409340D01*
G01X2383292Y1403750D02*
X2383155Y1403948D01*
X2383017Y1404144D01*
X2382877Y1404340D01*
G01X2385260Y1398750D02*
X2385123Y1398948D01*
X2384985Y1399144D01*
X2384846Y1399340D01*
G01X2383292Y1393750D02*
X2383155Y1393948D01*
X2383017Y1394144D01*
X2382877Y1394340D01*
G01X2383292Y1388750D02*
X2383155Y1388948D01*
X2383017Y1389144D01*
X2382877Y1389340D01*
G01X2383292Y1383750D02*
X2383155Y1383948D01*
X2383017Y1384144D01*
X2382877Y1384340D01*
G01X2383292Y1378750D02*
X2383155Y1378948D01*
X2383017Y1379144D01*
X2382877Y1379340D01*
G01X2383292Y1373750D02*
X2383155Y1373948D01*
X2383017Y1374144D01*
X2382877Y1374340D01*
G01X2383292Y1368750D02*
X2383155Y1368948D01*
X2383017Y1369144D01*
X2382877Y1369340D01*
G01X2383292Y1363750D02*
X2383155Y1363948D01*
X2383017Y1364144D01*
X2382877Y1364340D01*
G01X2377132Y1412766D02*
X2376706Y1413356D01*
G01X2377132Y1407766D02*
X2376706Y1408356D01*
G01X2377132Y1402766D02*
X2376706Y1403356D01*
G01X2379101Y1397766D02*
X2378674Y1398356D01*
G01X2377132Y1392766D02*
X2376706Y1393356D01*
G01X2377132Y1387766D02*
X2376706Y1388356D01*
G01X2377132Y1382766D02*
X2376706Y1383356D01*
G01X2377132Y1377766D02*
X2376706Y1378356D01*
G01X2377132Y1372766D02*
X2376706Y1373356D01*
G01X2385173Y1422293D02*
X2387142Y1420325D01*
G01X2378234Y1362746D02*
X2378244Y1362844D01*
X2378272Y1362916D01*
X2378310Y1362943D01*
G01X2378234Y1365896D02*
X2378244Y1365994D01*
X2378272Y1366066D01*
X2378310Y1366092D01*
G01X2378234Y1369045D02*
X2378244Y1369144D01*
X2378272Y1369216D01*
X2378310Y1369242D01*
G01X2378234Y1372195D02*
X2378244Y1372293D01*
X2378272Y1372365D01*
X2378310Y1372392D01*
G01X2378234Y1375344D02*
X2378244Y1375443D01*
X2378272Y1375515D01*
X2378310Y1375541D01*
G01X2378234Y1378494D02*
X2378244Y1378592D01*
X2378272Y1378664D01*
X2378310Y1378691D01*
G01X2378234Y1381644D02*
X2378244Y1381742D01*
X2378272Y1381814D01*
X2378310Y1381840D01*
G01X2378234Y1384793D02*
X2378244Y1384892D01*
X2378272Y1384964D01*
X2378310Y1384990D01*
G01X2378234Y1387943D02*
X2378244Y1388041D01*
X2378272Y1388113D01*
X2378310Y1388140D01*
G01X2378234Y1391092D02*
X2378244Y1391191D01*
X2378272Y1391263D01*
X2378310Y1391289D01*
G01X2385260Y1398750D02*
Y1398356D01*
G01X2383292Y1363750D02*
Y1363356D01*
G01Y1368750D02*
Y1368356D01*
G01Y1373750D02*
Y1373356D01*
G01Y1378750D02*
Y1378356D01*
G01Y1383750D02*
Y1383356D01*
G01Y1388750D02*
Y1388356D01*
G01Y1393750D02*
Y1393356D01*
G01Y1403750D02*
Y1403356D01*
G01Y1408750D02*
Y1408356D01*
G01Y1413750D02*
Y1413356D01*
G01X2383155Y1412746D02*
Y1413140D01*
G01Y1409596D02*
Y1409990D01*
G01Y1403297D02*
Y1403691D01*
G01Y1406447D02*
Y1406840D01*
G01Y1400148D02*
Y1400541D01*
G01Y1393848D02*
Y1394242D01*
G01Y1396998D02*
Y1397392D01*
G01Y1390699D02*
Y1391092D01*
G01Y1384400D02*
Y1384793D01*
G01Y1387549D02*
Y1387943D01*
G01Y1381250D02*
Y1381644D01*
G01Y1378100D02*
Y1378494D01*
G01Y1374951D02*
Y1375344D01*
G01Y1371801D02*
Y1372195D01*
G01Y1365502D02*
Y1365896D01*
G01Y1368651D02*
Y1369045D01*
G01Y1362352D02*
Y1362746D01*
G01X2380643Y1398750D02*
Y1398356D01*
G01X2379518D02*
Y1398750D01*
G01X2378674Y1398356D02*
Y1398750D01*
G01Y1408356D02*
Y1408750D01*
G01Y1363750D02*
Y1363356D01*
G01Y1368750D02*
Y1368356D01*
G01Y1373750D02*
Y1373356D01*
G01Y1378750D02*
Y1378356D01*
G01Y1383750D02*
Y1383356D01*
G01Y1388750D02*
Y1388356D01*
G01Y1393750D02*
Y1393356D01*
G01Y1403750D02*
Y1403356D01*
G01Y1413750D02*
Y1413356D01*
G01X2378234Y1412746D02*
Y1413140D01*
G01Y1409596D02*
Y1409990D01*
G01Y1403297D02*
Y1403691D01*
G01Y1406447D02*
Y1406840D01*
G01Y1400148D02*
Y1400541D01*
G01Y1393848D02*
Y1394242D01*
G01Y1396998D02*
Y1397392D01*
G01Y1390699D02*
Y1391092D01*
G01Y1384400D02*
Y1384793D01*
G01Y1387549D02*
Y1387943D01*
G01Y1381250D02*
Y1381644D01*
G01Y1378100D02*
Y1378494D01*
G01Y1374951D02*
Y1375344D01*
G01Y1371801D02*
Y1372195D01*
G01Y1365502D02*
Y1365896D01*
G01Y1368651D02*
Y1369045D01*
G01Y1362352D02*
Y1362746D01*
G01X2377721D02*
Y1362352D01*
G01Y1365896D02*
Y1365502D01*
G01Y1369045D02*
Y1368651D01*
G01Y1372195D02*
Y1371801D01*
G01Y1378494D02*
Y1378100D01*
G01Y1375344D02*
Y1374951D01*
G01Y1381644D02*
Y1381250D01*
G01Y1384793D02*
Y1384400D01*
G01Y1387943D02*
Y1387549D01*
G01Y1391092D02*
Y1390699D01*
G01Y1394242D02*
Y1393848D01*
G01Y1397392D02*
Y1396998D01*
G01Y1400541D02*
Y1400148D01*
G01Y1403691D02*
Y1403297D01*
G01Y1406840D02*
Y1406447D01*
G01Y1409990D02*
Y1409596D01*
G01Y1413140D02*
Y1412746D01*
G01X2377549Y1413356D02*
Y1413750D01*
G01Y1408356D02*
Y1408750D01*
G01Y1403356D02*
Y1403750D01*
G01Y1393356D02*
Y1393750D01*
G01Y1388356D02*
Y1388750D01*
G01Y1383356D02*
Y1383750D01*
G01Y1378356D02*
Y1378750D01*
G01Y1373356D02*
Y1373750D01*
G01Y1368356D02*
Y1368750D01*
G01Y1363356D02*
Y1363750D01*
G01X2376706Y1413356D02*
Y1413750D01*
G01Y1408356D02*
Y1408750D01*
G01Y1403356D02*
Y1403750D01*
G01Y1393356D02*
Y1393750D01*
G01Y1388356D02*
Y1388750D01*
G01Y1383356D02*
Y1383750D01*
G01Y1378356D02*
Y1378750D01*
G01Y1373356D02*
Y1373750D01*
G01Y1368356D02*
Y1368750D01*
G01Y1363356D02*
Y1363750D01*
G01X2376543Y1362746D02*
Y1362352D01*
G01Y1365896D02*
Y1365502D01*
G01Y1369045D02*
Y1368651D01*
G01Y1372195D02*
Y1371801D01*
G01Y1378494D02*
Y1378100D01*
G01Y1375344D02*
Y1374951D01*
G01Y1381644D02*
Y1381250D01*
G01Y1384793D02*
Y1384400D01*
G01Y1387943D02*
Y1387549D01*
G01Y1391092D02*
Y1390699D01*
G01Y1394242D02*
Y1393848D01*
G01Y1397392D02*
Y1396998D01*
G01Y1400541D02*
Y1400148D01*
G01Y1403691D02*
Y1403297D01*
G01Y1406840D02*
Y1406447D01*
G01Y1409990D02*
Y1409596D01*
G01Y1413140D02*
Y1412746D01*
G01X2377721D02*
X2377723Y1412708D01*
X2377731Y1412671D01*
X2377744Y1412637D01*
X2377761Y1412607D01*
X2377782Y1412582D01*
X2377806Y1412564D01*
X2377832Y1412553D01*
X2377859Y1412549D01*
G01X2377721Y1409596D02*
X2377723Y1409558D01*
X2377731Y1409521D01*
X2377744Y1409487D01*
X2377761Y1409457D01*
X2377782Y1409433D01*
X2377806Y1409415D01*
X2377832Y1409403D01*
X2377859Y1409400D01*
G01X2377721Y1406447D02*
X2377723Y1406409D01*
X2377731Y1406372D01*
X2377744Y1406338D01*
X2377761Y1406308D01*
X2377782Y1406283D01*
X2377806Y1406265D01*
X2377832Y1406254D01*
X2377859Y1406250D01*
G01X2377721Y1403297D02*
X2377723Y1403259D01*
X2377731Y1403222D01*
X2377744Y1403188D01*
X2377761Y1403158D01*
X2377782Y1403134D01*
X2377806Y1403115D01*
X2377832Y1403104D01*
X2377859Y1403100D01*
G01X2377721Y1400148D02*
X2377723Y1400109D01*
X2377731Y1400073D01*
X2377744Y1400039D01*
X2377761Y1400008D01*
X2377782Y1399984D01*
X2377806Y1399966D01*
X2377832Y1399955D01*
X2377859Y1399951D01*
G01X2377721Y1396998D02*
X2377723Y1396960D01*
X2377731Y1396923D01*
X2377744Y1396889D01*
X2377761Y1396859D01*
X2377782Y1396834D01*
X2377806Y1396816D01*
X2377832Y1396805D01*
X2377859Y1396801D01*
G01X2377721Y1393848D02*
X2377723Y1393810D01*
X2377731Y1393773D01*
X2377744Y1393739D01*
X2377761Y1393709D01*
X2377782Y1393685D01*
X2377806Y1393667D01*
X2377832Y1393655D01*
X2377859Y1393651D01*
G01X2377721Y1390699D02*
X2377723Y1390660D01*
X2377731Y1390624D01*
X2377744Y1390590D01*
X2377761Y1390560D01*
X2377782Y1390535D01*
X2377806Y1390517D01*
X2377832Y1390506D01*
X2377859Y1390502D01*
G01X2377721Y1387549D02*
X2377723Y1387511D01*
X2377731Y1387474D01*
X2377744Y1387440D01*
X2377761Y1387410D01*
X2377782Y1387386D01*
X2377806Y1387367D01*
X2377832Y1387356D01*
X2377859Y1387352D01*
G01X2377721Y1384400D02*
X2377723Y1384361D01*
X2377731Y1384325D01*
X2377744Y1384291D01*
X2377761Y1384260D01*
X2377782Y1384236D01*
X2377806Y1384218D01*
X2377832Y1384207D01*
X2377859Y1384203D01*
G01X2377721Y1381250D02*
X2377723Y1381212D01*
X2377731Y1381175D01*
X2377744Y1381141D01*
X2377761Y1381111D01*
X2377782Y1381086D01*
X2377806Y1381068D01*
X2377832Y1381057D01*
X2377859Y1381053D01*
G01X2377721Y1378100D02*
X2377723Y1378062D01*
X2377731Y1378025D01*
X2377744Y1377991D01*
X2377761Y1377961D01*
X2377782Y1377937D01*
X2377806Y1377919D01*
X2377832Y1377907D01*
X2377859Y1377903D01*
G01X2377721Y1374951D02*
X2377723Y1374912D01*
X2377731Y1374876D01*
X2377744Y1374842D01*
X2377761Y1374811D01*
X2377782Y1374787D01*
X2377806Y1374769D01*
X2377832Y1374758D01*
X2377859Y1374754D01*
G01X2377721Y1371801D02*
X2377723Y1371763D01*
X2377731Y1371726D01*
X2377744Y1371692D01*
X2377761Y1371662D01*
X2377782Y1371638D01*
X2377806Y1371619D01*
X2377832Y1371608D01*
X2377859Y1371604D01*
G01X2377721Y1368651D02*
X2377723Y1368613D01*
X2377731Y1368576D01*
X2377744Y1368543D01*
X2377761Y1368512D01*
X2377782Y1368488D01*
X2377806Y1368470D01*
X2377832Y1368459D01*
X2377859Y1368455D01*
G01X2377721Y1365502D02*
X2377723Y1365464D01*
X2377731Y1365427D01*
X2377744Y1365393D01*
X2377761Y1365363D01*
X2377782Y1365338D01*
X2377806Y1365320D01*
X2377832Y1365309D01*
X2377859Y1365305D01*
G01X2377721Y1362352D02*
X2377723Y1362314D01*
X2377731Y1362277D01*
X2377744Y1362243D01*
X2377761Y1362213D01*
X2377782Y1362189D01*
X2377806Y1362171D01*
X2377832Y1362159D01*
X2377859Y1362155D01*
G01X2377132Y1367766D02*
X2376706Y1368356D01*
G01X2377132Y1362766D02*
X2376706Y1363356D01*
G01X2378310Y1412549D02*
X2378272Y1412576D01*
X2378244Y1412648D01*
X2378234Y1412746D01*
G01X2378310Y1409400D02*
X2378272Y1409426D01*
X2378244Y1409498D01*
X2378234Y1409596D01*
G01X2378310Y1406250D02*
X2378272Y1406276D01*
X2378244Y1406348D01*
X2378234Y1406447D01*
G01X2378310Y1403100D02*
X2378272Y1403127D01*
X2378244Y1403199D01*
X2378234Y1403297D01*
G01X2378310Y1399951D02*
X2378272Y1399977D01*
X2378244Y1400049D01*
X2378234Y1400148D01*
G01X2378310Y1396801D02*
X2378272Y1396827D01*
X2378244Y1396900D01*
X2378234Y1396998D01*
G01X2378310Y1393651D02*
X2378272Y1393678D01*
X2378244Y1393750D01*
X2378234Y1393848D01*
G01X2378310Y1390502D02*
X2378272Y1390528D01*
X2378244Y1390600D01*
X2378234Y1390699D01*
G01X2378310Y1387352D02*
X2378272Y1387379D01*
X2378244Y1387451D01*
X2378234Y1387549D01*
G01X2378310Y1384203D02*
X2378272Y1384229D01*
X2378244Y1384301D01*
X2378234Y1384400D01*
G01X2378310Y1381053D02*
X2378272Y1381079D01*
X2378244Y1381152D01*
X2378234Y1381250D01*
G01X2378310Y1377903D02*
X2378272Y1377930D01*
X2378244Y1378002D01*
X2378234Y1378100D01*
G01X2378310Y1374754D02*
X2378272Y1374780D01*
X2378244Y1374852D01*
X2378234Y1374951D01*
G01X2378310Y1371604D02*
X2378272Y1371631D01*
X2378244Y1371703D01*
X2378234Y1371801D01*
G01X2378310Y1368455D02*
X2378272Y1368481D01*
X2378244Y1368553D01*
X2378234Y1368651D01*
G01X2377549Y1363750D02*
X2377822Y1364340D01*
G01X2377549Y1368750D02*
X2377822Y1369340D01*
G01X2377549Y1373750D02*
X2377822Y1374340D01*
G01X2377549Y1378750D02*
X2377822Y1379340D01*
G01X2377549Y1383750D02*
X2377822Y1384340D01*
G01X2377549Y1388750D02*
X2377822Y1389340D01*
G01X2383155Y1371801D02*
X2383122Y1371702D01*
X2383034Y1371631D01*
X2382908Y1371604D01*
G01X2383155Y1400148D02*
X2383122Y1400049D01*
X2383034Y1399978D01*
X2382908Y1399951D01*
G01X2378674Y1363750D02*
X2378752Y1364340D01*
G01X2378674Y1368750D02*
X2378752Y1369340D01*
G01X2378674Y1373750D02*
X2378752Y1374340D01*
G01X2378674Y1378750D02*
X2378752Y1379340D01*
G01X2378674Y1383750D02*
X2378752Y1384340D01*
G01X2380643Y1398750D02*
X2380720Y1399340D01*
G01X2378674Y1388750D02*
X2378752Y1389340D01*
G01X2378674Y1393750D02*
X2378752Y1394340D01*
G01X2378674Y1403750D02*
X2378752Y1404340D01*
G01Y1409340D02*
X2378674Y1408750D01*
G01Y1413750D02*
X2378752Y1414340D01*
G01X2378234Y1394242D02*
X2378244Y1394340D01*
X2378272Y1394412D01*
X2378310Y1394439D01*
G01X2378234Y1397392D02*
X2378244Y1397490D01*
X2378272Y1397562D01*
X2378310Y1397588D01*
G01X2378234Y1400541D02*
X2378244Y1400640D01*
X2378272Y1400712D01*
X2378310Y1400738D01*
G01X2378234Y1403691D02*
X2378244Y1403789D01*
X2378272Y1403861D01*
X2378310Y1403888D01*
G01X2378234Y1406840D02*
X2378244Y1406939D01*
X2378272Y1407011D01*
X2378310Y1407037D01*
G01X2378234Y1409990D02*
X2378244Y1410088D01*
X2378272Y1410161D01*
X2378310Y1410187D01*
G01X2378234Y1413140D02*
X2378244Y1413238D01*
X2378272Y1413310D01*
X2378310Y1413337D01*
G01Y1365305D02*
X2378272Y1365331D01*
X2378244Y1365404D01*
X2378234Y1365502D01*
G01X2378310Y1362155D02*
X2378272Y1362182D01*
X2378244Y1362254D01*
X2378234Y1362352D01*
G01X2377132Y1364340D02*
X2376706Y1363750D01*
G01X2377132Y1369340D02*
X2376706Y1368750D01*
G01X2377132Y1374340D02*
X2376706Y1373750D01*
G01X2377132Y1379340D02*
X2376706Y1378750D01*
G01X2377132Y1384340D02*
X2376706Y1383750D01*
G01X2377132Y1389340D02*
X2376706Y1388750D01*
G01X2377132Y1394340D02*
X2376706Y1393750D01*
G01X2379101Y1399340D02*
X2378674Y1398750D01*
G01X2377132Y1404340D02*
X2376706Y1403750D01*
G01X2377132Y1409340D02*
X2376706Y1408750D01*
G01X2377132Y1414340D02*
X2376706Y1413750D01*
G01X2382877Y1362766D02*
X2383017Y1362962D01*
X2383155Y1363159D01*
X2383292Y1363356D01*
G01X2382877Y1367766D02*
X2383017Y1367962D01*
X2383155Y1368159D01*
X2383292Y1368356D01*
G01X2382877Y1372766D02*
X2383017Y1372962D01*
X2383155Y1373159D01*
X2383292Y1373356D01*
G01X2382877Y1377766D02*
X2383017Y1377962D01*
X2383155Y1378159D01*
X2383292Y1378356D01*
G01X2382877Y1382766D02*
X2383017Y1382962D01*
X2383155Y1383159D01*
X2383292Y1383356D01*
G01X2382877Y1387766D02*
X2383017Y1387962D01*
X2383155Y1388159D01*
X2383292Y1388356D01*
G01X2382877Y1392766D02*
X2383017Y1392962D01*
X2383155Y1393159D01*
X2383292Y1393356D01*
G01X2384846Y1397766D02*
X2384985Y1397962D01*
X2385123Y1398159D01*
X2385260Y1398356D01*
G01X2382877Y1402766D02*
X2383017Y1402962D01*
X2383155Y1403159D01*
X2383292Y1403356D01*
G01X2382877Y1407766D02*
X2383017Y1407962D01*
X2383155Y1408159D01*
X2383292Y1408356D01*
G01X2382877Y1412766D02*
X2383017Y1412962D01*
X2383155Y1413159D01*
X2383292Y1413356D01*
G01X2377549Y1393750D02*
X2377822Y1394340D01*
G01X2379518Y1398750D02*
X2379791Y1399340D01*
G01X2377549Y1403750D02*
X2377822Y1404340D01*
G01X2377549Y1408750D02*
X2377822Y1409340D01*
G01X2377549Y1413750D02*
X2377822Y1414340D01*
G01X2382908Y1400738D02*
X2383034Y1400711D01*
X2383124Y1400638D01*
X2383155Y1400541D01*
G01X2382908Y1372392D02*
X2383034Y1372364D01*
X2383124Y1372292D01*
X2383155Y1372195D01*
G01X2385173Y1417372D02*
X2387142Y1419340D01*
G01X2390425Y1422293D02*
X2387142D01*
G01X2382877Y1414340D02*
X2377132D01*
G01X2376706Y1413750D02*
X2383292D01*
G01X2376706Y1413356D02*
X2383292D01*
G01X2382908Y1413337D02*
X2376823D01*
G01X2376543Y1413140D02*
X2383155D01*
G01X2382877Y1412766D02*
X2377132D01*
G01X2383155Y1412746D02*
X2376543D01*
G01X2382908Y1412549D02*
X2376823D01*
G01X2382908Y1410187D02*
X2376823D01*
G01X2376543Y1409990D02*
X2383155D01*
G01Y1409596D02*
X2376543D01*
G01X2382908Y1409400D02*
X2376823D01*
G01X2382877Y1409340D02*
X2377132D01*
G01X2376706Y1408750D02*
X2383292D01*
G01X2376706Y1408356D02*
X2383292D01*
G01X2382877Y1407766D02*
X2377132D01*
G01X2382908Y1407037D02*
X2376823D01*
G01X2376543Y1406840D02*
X2383155D01*
G01Y1406447D02*
X2376543D01*
G01X2382908Y1406250D02*
X2376823D01*
G01X2382877Y1404340D02*
X2377132D01*
G01X2382908Y1403888D02*
X2376823D01*
G01X2376706Y1403750D02*
X2383292D01*
G01X2376543Y1403691D02*
X2383155D01*
G01X2376706Y1403356D02*
X2383292D01*
G01X2383155Y1403297D02*
X2376543D01*
G01X2382908Y1403100D02*
X2376823D01*
G01X2382877Y1402766D02*
X2377132D01*
G01X2382908Y1400738D02*
X2376823D01*
G01X2376543Y1400541D02*
X2383155D01*
G01Y1400148D02*
X2376543D01*
G01X2382908Y1399951D02*
X2376823D01*
G01X2384846Y1399340D02*
X2379101D01*
G01X2378674Y1398750D02*
X2385260D01*
G01X2378674Y1398356D02*
X2385260D01*
G01X2384846Y1397766D02*
X2379101D01*
G01X2382908Y1397588D02*
X2376823D01*
G01X2376543Y1397392D02*
X2383155D01*
G01Y1396998D02*
X2376543D01*
G01X2382908Y1396801D02*
X2376823D01*
G01X2382908Y1394439D02*
X2376823D01*
G01X2382877Y1394340D02*
X2377132D01*
G01X2376543Y1394242D02*
X2383155D01*
G01Y1393848D02*
X2376543D01*
G01X2376706Y1393750D02*
X2383292D01*
G01X2382908Y1393651D02*
X2376823D01*
G01X2376706Y1393356D02*
X2383292D01*
G01X2382877Y1392766D02*
X2377132D01*
G01X2382908Y1391289D02*
X2376823D01*
G01X2376543Y1391092D02*
X2383155D01*
G01Y1390699D02*
X2376543D01*
G01X2382908Y1390502D02*
X2376823D01*
G01X2382877Y1389340D02*
X2377132D01*
G01X2376706Y1388750D02*
X2383292D01*
G01X2376706Y1388356D02*
X2383292D01*
G01X2382908Y1388140D02*
X2376823D01*
G01X2376543Y1387943D02*
X2383155D01*
G01X2382877Y1387766D02*
X2377132D01*
G01X2383155Y1387549D02*
X2376543D01*
G01X2382908Y1387352D02*
X2376823D01*
G01X2382908Y1384990D02*
X2376823D01*
G01X2376543Y1384793D02*
X2383155D01*
G01Y1384400D02*
X2376543D01*
G01X2382877Y1384340D02*
X2377132D01*
G01X2382908Y1384203D02*
X2376823D01*
G01X2376706Y1383750D02*
X2383292D01*
G01X2376706Y1383356D02*
X2383292D01*
G01X2382877Y1382766D02*
X2377132D01*
G01X2382908Y1381840D02*
X2376823D01*
G01X2376543Y1381644D02*
X2383155D01*
G01Y1381250D02*
X2376543D01*
G01X2382908Y1381053D02*
X2376823D01*
G01X2382877Y1379340D02*
X2377132D01*
G01X2376706Y1378750D02*
X2383292D01*
G01X2382908Y1378691D02*
X2376823D01*
G01X2376543Y1378494D02*
X2383155D01*
G01X2376706Y1378356D02*
X2383292D01*
G01X2383155Y1378100D02*
X2376543D01*
G01X2382908Y1377903D02*
X2376823D01*
G01X2382877Y1377766D02*
X2377132D01*
G01X2382908Y1375541D02*
X2376823D01*
G01X2376543Y1375344D02*
X2383155D01*
G01Y1374951D02*
X2376543D01*
G01X2382908Y1374754D02*
X2376823D01*
G01X2382877Y1374340D02*
X2377132D01*
G01X2376706Y1373750D02*
X2383292D01*
G01X2376706Y1373356D02*
X2383292D01*
G01X2382877Y1372766D02*
X2377132D01*
G01X2382908Y1372392D02*
X2376823D01*
G01X2376543Y1372195D02*
X2383155D01*
G01Y1371801D02*
X2376543D01*
G01X2382908Y1371604D02*
X2376823D01*
G01X2382877Y1369340D02*
X2377132D01*
G01X2382908Y1369242D02*
X2376823D01*
G01X2376543Y1369045D02*
X2383155D01*
G01X2376706Y1368750D02*
X2383292D01*
G01X2383155Y1368651D02*
X2376543D01*
G01X2382908Y1368455D02*
X2376823D01*
G01X2376706Y1368356D02*
X2383292D01*
G01X2382877Y1367766D02*
X2377132D01*
G01X2382908Y1366092D02*
X2376823D01*
G01X2376543Y1365896D02*
X2383155D01*
G01Y1365502D02*
X2376543D01*
G01X2382908Y1365305D02*
X2376823D01*
G01X2382877Y1364340D02*
X2377132D01*
G01X2376706Y1363750D02*
X2383292D01*
G01X2376706Y1363356D02*
X2383292D01*
G01X2382908Y1362943D02*
X2376823D01*
G01X2382877Y1362766D02*
X2377132D01*
G01X2376543Y1362746D02*
X2383155D01*
G01Y1362352D02*
X2376543D01*
G01X2382908Y1362155D02*
X2376823D01*
G01X2377859Y1413337D02*
X2377832Y1413333D01*
X2377806Y1413322D01*
X2377782Y1413304D01*
X2377761Y1413279D01*
X2377744Y1413249D01*
X2377731Y1413215D01*
X2377723Y1413179D01*
X2377721Y1413140D01*
G01X2377859Y1410187D02*
X2377832Y1410183D01*
X2377806Y1410172D01*
X2377782Y1410154D01*
X2377761Y1410129D01*
X2377744Y1410100D01*
X2377731Y1410066D01*
X2377723Y1410029D01*
X2377721Y1409990D01*
G01X2377859Y1407037D02*
X2377832Y1407034D01*
X2377806Y1407022D01*
X2377782Y1407004D01*
X2377761Y1406980D01*
X2377744Y1406950D01*
X2377731Y1406916D01*
X2377723Y1406879D01*
X2377721Y1406840D01*
G01X2377859Y1403888D02*
X2377832Y1403884D01*
X2377806Y1403873D01*
X2377782Y1403855D01*
X2377761Y1403830D01*
X2377744Y1403800D01*
X2377731Y1403767D01*
X2377723Y1403730D01*
X2377721Y1403691D01*
G01X2377859Y1400738D02*
X2377832Y1400734D01*
X2377806Y1400723D01*
X2377782Y1400705D01*
X2377761Y1400680D01*
X2377744Y1400651D01*
X2377731Y1400617D01*
X2377723Y1400580D01*
X2377721Y1400541D01*
G01X2377859Y1397588D02*
X2377832Y1397585D01*
X2377806Y1397574D01*
X2377782Y1397556D01*
X2377761Y1397531D01*
X2377744Y1397501D01*
X2377731Y1397467D01*
X2377723Y1397431D01*
X2377721Y1397392D01*
G01X2377859Y1394439D02*
X2377832Y1394435D01*
X2377806Y1394424D01*
X2377782Y1394406D01*
X2377761Y1394381D01*
X2377744Y1394352D01*
X2377731Y1394318D01*
X2377723Y1394281D01*
X2377721Y1394242D01*
G01X2377859Y1391289D02*
X2377832Y1391286D01*
X2377806Y1391274D01*
X2377782Y1391256D01*
X2377761Y1391232D01*
X2377744Y1391202D01*
X2377731Y1391168D01*
X2377723Y1391131D01*
X2377721Y1391092D01*
G01X2377859Y1388140D02*
X2377832Y1388136D01*
X2377806Y1388125D01*
X2377782Y1388107D01*
X2377761Y1388082D01*
X2377744Y1388052D01*
X2377731Y1388018D01*
X2377723Y1387982D01*
X2377721Y1387943D01*
G01X2377859Y1384990D02*
X2377832Y1384986D01*
X2377806Y1384975D01*
X2377782Y1384957D01*
X2377761Y1384932D01*
X2377744Y1384903D01*
X2377731Y1384869D01*
X2377723Y1384832D01*
X2377721Y1384793D01*
G01X2377859Y1381840D02*
X2377832Y1381837D01*
X2377806Y1381826D01*
X2377782Y1381808D01*
X2377761Y1381783D01*
X2377744Y1381753D01*
X2377731Y1381719D01*
X2377723Y1381683D01*
X2377721Y1381644D01*
G01X2377859Y1378691D02*
X2377832Y1378687D01*
X2377806Y1378676D01*
X2377782Y1378658D01*
X2377761Y1378633D01*
X2377744Y1378604D01*
X2377731Y1378570D01*
X2377723Y1378533D01*
X2377721Y1378494D01*
G01X2377859Y1375541D02*
X2377832Y1375537D01*
X2377806Y1375526D01*
X2377782Y1375508D01*
X2377761Y1375484D01*
X2377744Y1375454D01*
X2377731Y1375420D01*
X2377723Y1375383D01*
X2377721Y1375344D01*
G01X2377859Y1372392D02*
X2377832Y1372388D01*
X2377806Y1372377D01*
X2377782Y1372359D01*
X2377761Y1372334D01*
X2377744Y1372304D01*
X2377731Y1372270D01*
X2377723Y1372234D01*
X2377721Y1372195D01*
G01X2377859Y1369242D02*
X2377832Y1369238D01*
X2377806Y1369227D01*
X2377782Y1369209D01*
X2377761Y1369184D01*
X2377744Y1369155D01*
X2377731Y1369121D01*
X2377723Y1369084D01*
X2377721Y1369045D01*
G01X2377859Y1366092D02*
X2377832Y1366089D01*
X2377806Y1366078D01*
X2377782Y1366060D01*
X2377761Y1366035D01*
X2377744Y1366005D01*
X2377731Y1365971D01*
X2377723Y1365934D01*
X2377721Y1365896D01*
G01X2377859Y1362943D02*
X2377832Y1362939D01*
X2377806Y1362928D01*
X2377782Y1362910D01*
X2377761Y1362885D01*
X2377744Y1362855D01*
X2377731Y1362822D01*
X2377723Y1362785D01*
X2377721Y1362746D01*
G01X2382908Y1412549D02*
X2383035Y1412577D01*
X2383124Y1412650D01*
X2383155Y1412746D01*
G01X2382908Y1409400D02*
X2383035Y1409427D01*
X2383124Y1409500D01*
X2383155Y1409596D01*
G01X2382908Y1406250D02*
X2383035Y1406278D01*
X2383124Y1406351D01*
X2383155Y1406447D01*
G01X2382908Y1403100D02*
X2383035Y1403128D01*
X2383124Y1403201D01*
X2383155Y1403297D01*
G01X2382908Y1396801D02*
X2383035Y1396829D01*
X2383124Y1396902D01*
X2383155Y1396998D01*
G01X2382908Y1393651D02*
X2383035Y1393679D01*
X2383124Y1393752D01*
X2383155Y1393848D01*
G01X2382908Y1390502D02*
X2383035Y1390530D01*
X2383124Y1390603D01*
X2383155Y1390699D01*
G01X2382908Y1387352D02*
X2383035Y1387380D01*
X2383124Y1387453D01*
X2383155Y1387549D01*
G01X2382908Y1384203D02*
X2383035Y1384230D01*
X2383124Y1384303D01*
X2383155Y1384400D01*
G01X2382908Y1381053D02*
X2383035Y1381081D01*
X2383124Y1381154D01*
X2383155Y1381250D01*
G01X2382908Y1377903D02*
X2383035Y1377931D01*
X2383124Y1378004D01*
X2383155Y1378100D01*
G01X2382908Y1374754D02*
X2383035Y1374782D01*
X2383124Y1374854D01*
X2383155Y1374951D01*
G01X2382908Y1368455D02*
X2383035Y1368482D01*
X2383124Y1368555D01*
X2383155Y1368651D01*
G01X2382908Y1365305D02*
X2383035Y1365333D01*
X2383124Y1365406D01*
X2383155Y1365502D01*
G01X2382908Y1362155D02*
X2383035Y1362183D01*
X2383124Y1362256D01*
X2383155Y1362352D01*
G01X2393835Y1425994D02*
X2389110Y1430640D01*
G01X2389114Y1429532D02*
X2393835Y1424891D01*
G01X2389168Y1429908D02*
X2389205Y1430232D01*
X2389199Y1430473D01*
X2389142Y1430609D01*
G01X2393835Y1424262D02*
Y1425994D01*
G01X2389110Y1422293D02*
Y1429459D01*
G01X2389168Y1429910D02*
X2389114Y1429532D01*
G01X2390425Y1422293D02*
X2393835Y1424262D01*
G01X2389142Y1430609D02*
X2389199Y1430469D01*
X2389204Y1430229D01*
G01X2377822Y1718277D02*
X2377549Y1718868D01*
G01X2377822Y1713277D02*
X2377549Y1713868D01*
G01X2377822Y1708277D02*
X2377549Y1708868D01*
G01X2377822Y1703277D02*
X2377549Y1703868D01*
G01X2377822Y1698277D02*
X2377549Y1698868D01*
G01X2377822Y1693277D02*
X2377549Y1693868D01*
G01X2383292Y1719262D02*
X2383155Y1719459D01*
X2383017Y1719656D01*
X2382877Y1719852D01*
G01X2383292Y1714262D02*
X2383155Y1714459D01*
X2383017Y1714656D01*
X2382877Y1714852D01*
G01X2383292Y1709262D02*
X2383155Y1709459D01*
X2383017Y1709656D01*
X2382877Y1709852D01*
G01X2383292Y1704262D02*
X2383155Y1704459D01*
X2383017Y1704656D01*
X2382877Y1704852D01*
G01X2383292Y1699262D02*
X2383155Y1699459D01*
X2383017Y1699656D01*
X2382877Y1699852D01*
G01X2383292Y1694262D02*
X2383155Y1694459D01*
X2383017Y1694656D01*
X2382877Y1694852D01*
G01X2377132Y1718277D02*
X2376706Y1718868D01*
G01X2377132Y1713277D02*
X2376706Y1713868D01*
G01X2377132Y1708277D02*
X2376706Y1708868D01*
G01X2377132Y1703277D02*
X2376706Y1703868D01*
G01X2377132Y1698277D02*
X2376706Y1698868D01*
G01X2377132Y1693277D02*
X2376706Y1693868D01*
G01X2387142Y1688277D02*
X2385173Y1690246D01*
G01X2378310Y1720423D02*
X2378272Y1720450D01*
X2378244Y1720522D01*
X2378234Y1720620D01*
G01X2378310Y1717274D02*
X2378272Y1717300D01*
X2378244Y1717372D01*
X2378234Y1717470D01*
G01X2378310Y1714124D02*
X2378272Y1714150D01*
X2378244Y1714222D01*
X2378234Y1714321D01*
G01X2378310Y1710974D02*
X2378272Y1711001D01*
X2378244Y1711073D01*
X2378234Y1711171D01*
G01X2378310Y1707825D02*
X2378272Y1707851D01*
X2378244Y1707923D01*
X2378234Y1708022D01*
G01X2378310Y1704675D02*
X2378272Y1704702D01*
X2378244Y1704774D01*
X2378234Y1704872D01*
G01X2378310Y1701525D02*
X2378272Y1701552D01*
X2378244Y1701624D01*
X2378234Y1701722D01*
G01X2378310Y1698376D02*
X2378272Y1698402D01*
X2378244Y1698474D01*
X2378234Y1698573D01*
G01X2378310Y1695226D02*
X2378272Y1695253D01*
X2378244Y1695325D01*
X2378234Y1695423D01*
G01X2383155Y1721014D02*
X2383123Y1721111D01*
X2383035Y1721183D01*
X2382908Y1721211D01*
G01X2383155Y1717864D02*
X2383123Y1717961D01*
X2383035Y1718033D01*
X2382908Y1718061D01*
G01X2383155Y1714714D02*
X2383123Y1714811D01*
X2383035Y1714884D01*
X2382908Y1714911D01*
G01X2383155Y1711565D02*
X2383123Y1711662D01*
X2383035Y1711734D01*
X2382908Y1711762D01*
G01X2383155Y1708415D02*
X2383123Y1708512D01*
X2383035Y1708584D01*
X2382908Y1708612D01*
G01X2383155Y1705266D02*
X2383123Y1705363D01*
X2383035Y1705435D01*
X2382908Y1705463D01*
G01X2383155Y1702116D02*
X2383123Y1702213D01*
X2383035Y1702285D01*
X2382908Y1702313D01*
G01X2383155Y1698966D02*
X2383123Y1699063D01*
X2383035Y1699136D01*
X2382908Y1699163D01*
G01X2383155Y1695817D02*
X2383123Y1695914D01*
X2383035Y1695986D01*
X2382908Y1696014D01*
G01X2378674Y1718868D02*
X2378752Y1718277D01*
G01X2378674Y1713868D02*
X2378752Y1713277D01*
G01X2378674Y1708868D02*
X2378752Y1708277D01*
G01X2378674Y1703868D02*
X2378752Y1703277D01*
G01X2378674Y1698868D02*
X2378752Y1698277D01*
G01X2378674Y1693868D02*
X2378752Y1693277D01*
G01X2383155Y1720620D02*
X2376543D01*
G01X2382908Y1720423D02*
X2376823D01*
G01X2382877Y1719852D02*
X2377132D01*
G01X2376706Y1719262D02*
X2383292D01*
G01X2376706Y1718868D02*
X2383292D01*
G01X2382877Y1718277D02*
X2377132D01*
G01X2382908Y1718061D02*
X2376823D01*
G01X2376543Y1717864D02*
X2383155D01*
G01Y1717470D02*
X2376543D01*
G01X2382908Y1717274D02*
X2376823D01*
G01X2382908Y1714911D02*
X2376823D01*
G01X2382877Y1714852D02*
X2377132D01*
G01X2376543Y1714714D02*
X2383155D01*
G01Y1714321D02*
X2376543D01*
G01X2376706Y1714262D02*
X2383292D01*
G01X2382908Y1714124D02*
X2376823D01*
G01X2376706Y1713868D02*
X2383292D01*
G01X2382877Y1713277D02*
X2377132D01*
G01X2382908Y1711762D02*
X2376823D01*
G01X2376543Y1711565D02*
X2383155D01*
G01Y1711171D02*
X2376543D01*
G01X2382908Y1710974D02*
X2376823D01*
G01X2382877Y1709852D02*
X2377132D01*
G01X2376706Y1709262D02*
X2383292D01*
G01X2376706Y1708868D02*
X2383292D01*
G01X2382908Y1708612D02*
X2376823D01*
G01X2376543Y1708415D02*
X2383155D01*
G01X2382877Y1708277D02*
X2377132D01*
G01X2383155Y1708022D02*
X2376543D01*
G01X2382908Y1707825D02*
X2376823D01*
G01X2382908Y1705463D02*
X2376823D01*
G01X2376543Y1705266D02*
X2383155D01*
G01Y1704872D02*
X2376543D01*
G01X2382877Y1704852D02*
X2377132D01*
G01X2382908Y1704675D02*
X2376823D01*
G01X2376706Y1704262D02*
X2383292D01*
G01X2376706Y1703868D02*
X2383292D01*
G01X2382877Y1703277D02*
X2377132D01*
G01X2382908Y1702313D02*
X2376823D01*
G01X2376543Y1702116D02*
X2383155D01*
G01Y1701722D02*
X2376543D01*
G01X2382908Y1701525D02*
X2376823D01*
G01X2382877Y1699852D02*
X2377132D01*
G01X2376706Y1699262D02*
X2383292D01*
G01X2382908Y1699163D02*
X2376823D01*
G01X2376543Y1698966D02*
X2383155D01*
G01X2376706Y1698868D02*
X2383292D01*
G01X2383155Y1698573D02*
X2376543D01*
G01X2382908Y1698376D02*
X2376823D01*
G01X2382877Y1698277D02*
X2377132D01*
G01X2382908Y1696014D02*
X2376823D01*
G01X2376543Y1695817D02*
X2383155D01*
G01Y1695423D02*
X2376543D01*
G01X2382908Y1695226D02*
X2376823D01*
G01X2382877Y1694852D02*
X2377132D01*
G01X2376706Y1694262D02*
X2383292D01*
G01X2376706Y1693868D02*
X2383292D01*
G01X2382877Y1693277D02*
X2377132D01*
G01X2390425Y1685325D02*
X2387142D01*
G01D02*
Y1827805D01*
G01X2386130Y1725844D02*
Y1720463D01*
G01X2386020Y1823277D02*
Y1689852D01*
G01X2385961Y1720463D02*
Y1689459D01*
G01X2385173Y1690246D02*
Y1822884D01*
G01X2383292Y1694262D02*
Y1693868D01*
G01Y1699262D02*
Y1698868D01*
G01Y1704262D02*
Y1703868D01*
G01Y1709262D02*
Y1708868D01*
G01Y1714262D02*
Y1713868D01*
G01Y1719262D02*
Y1718868D01*
G01X2383155Y1717470D02*
Y1717864D01*
G01Y1720620D02*
Y1721014D01*
G01Y1714321D02*
Y1714714D01*
G01Y1708022D02*
Y1708415D01*
G01Y1711171D02*
Y1711565D01*
G01Y1704872D02*
Y1705266D01*
G01Y1698573D02*
Y1698966D01*
G01Y1701722D02*
Y1702116D01*
G01Y1695423D02*
Y1695817D01*
G01X2378674Y1694262D02*
Y1693868D01*
G01Y1699262D02*
Y1698868D01*
G01Y1704262D02*
Y1703868D01*
G01Y1709262D02*
Y1708868D01*
G01Y1714262D02*
Y1713868D01*
G01Y1719262D02*
Y1718868D01*
G01X2378234Y1717470D02*
Y1717864D01*
G01Y1720620D02*
Y1721014D01*
G01Y1714321D02*
Y1714714D01*
G01Y1708022D02*
Y1708415D01*
G01Y1711171D02*
Y1711565D01*
G01Y1704872D02*
Y1705266D01*
G01Y1698573D02*
Y1698966D01*
G01Y1701722D02*
Y1702116D01*
G01Y1695423D02*
Y1695817D01*
G01X2377721D02*
Y1695423D01*
G01Y1698966D02*
Y1698573D01*
G01Y1702116D02*
Y1701722D01*
G01Y1705266D02*
Y1704872D01*
G01Y1708415D02*
Y1708022D01*
G01Y1711565D02*
Y1711171D01*
G01Y1714714D02*
Y1714321D01*
G01Y1717864D02*
Y1717470D01*
G01Y1721014D02*
Y1720620D01*
G01X2377549Y1718868D02*
Y1719262D01*
G01Y1713868D02*
Y1714262D01*
G01Y1708868D02*
Y1709262D01*
G01Y1703868D02*
Y1704262D01*
G01Y1698868D02*
Y1699262D01*
G01Y1693868D02*
Y1694262D01*
G01X2376706Y1718868D02*
Y1719262D01*
G01Y1713868D02*
Y1714262D01*
G01Y1708868D02*
Y1709262D01*
G01Y1703868D02*
Y1704262D01*
G01Y1698868D02*
Y1699262D01*
G01Y1693868D02*
Y1694262D01*
G01X2376543Y1695817D02*
Y1695423D01*
G01Y1698966D02*
Y1698573D01*
G01Y1702116D02*
Y1701722D01*
G01Y1705266D02*
Y1704872D01*
G01Y1708415D02*
Y1708022D01*
G01Y1711565D02*
Y1711171D01*
G01Y1714714D02*
Y1714321D01*
G01Y1717864D02*
Y1717470D01*
G01Y1721014D02*
Y1720620D01*
G01X2377721D02*
X2377723Y1720582D01*
X2377731Y1720545D01*
X2377744Y1720511D01*
X2377761Y1720481D01*
X2377782Y1720456D01*
X2377806Y1720438D01*
X2377832Y1720427D01*
X2377859Y1720423D01*
G01X2377721Y1717470D02*
X2377723Y1717432D01*
X2377731Y1717395D01*
X2377744Y1717361D01*
X2377761Y1717331D01*
X2377782Y1717307D01*
X2377806Y1717289D01*
X2377832Y1717277D01*
X2377859Y1717274D01*
G01X2377721Y1714321D02*
X2377723Y1714283D01*
X2377731Y1714246D01*
X2377744Y1714212D01*
X2377761Y1714182D01*
X2377782Y1714157D01*
X2377806Y1714139D01*
X2377832Y1714128D01*
X2377859Y1714124D01*
G01X2377721Y1711171D02*
X2377723Y1711133D01*
X2377731Y1711096D01*
X2377744Y1711062D01*
X2377761Y1711032D01*
X2377782Y1711008D01*
X2377806Y1710989D01*
X2377832Y1710978D01*
X2377859Y1710974D01*
G01X2377721Y1708022D02*
X2377723Y1707983D01*
X2377731Y1707947D01*
X2377744Y1707913D01*
X2377761Y1707882D01*
X2377782Y1707858D01*
X2377806Y1707840D01*
X2377832Y1707829D01*
X2377859Y1707825D01*
G01X2377721Y1704872D02*
X2377723Y1704834D01*
X2377731Y1704797D01*
X2377744Y1704763D01*
X2377761Y1704733D01*
X2377782Y1704708D01*
X2377806Y1704690D01*
X2377832Y1704679D01*
X2377859Y1704675D01*
G01X2377721Y1701722D02*
X2377723Y1701684D01*
X2377731Y1701647D01*
X2377744Y1701613D01*
X2377761Y1701583D01*
X2377782Y1701559D01*
X2377806Y1701541D01*
X2377832Y1701529D01*
X2377859Y1701525D01*
G01X2377721Y1698573D02*
X2377723Y1698535D01*
X2377731Y1698498D01*
X2377744Y1698464D01*
X2377761Y1698434D01*
X2377782Y1698409D01*
X2377806Y1698391D01*
X2377832Y1698380D01*
X2377859Y1698376D01*
G01X2377721Y1695423D02*
X2377723Y1695385D01*
X2377731Y1695348D01*
X2377744Y1695314D01*
X2377761Y1695284D01*
X2377782Y1695260D01*
X2377806Y1695241D01*
X2377832Y1695230D01*
X2377859Y1695226D01*
G01Y1718061D02*
X2377832Y1718057D01*
X2377806Y1718046D01*
X2377782Y1718028D01*
X2377761Y1718003D01*
X2377744Y1717974D01*
X2377731Y1717940D01*
X2377723Y1717903D01*
X2377721Y1717864D01*
G01X2377859Y1714911D02*
X2377832Y1714908D01*
X2377806Y1714896D01*
X2377782Y1714878D01*
X2377761Y1714854D01*
X2377744Y1714824D01*
X2377731Y1714790D01*
X2377723Y1714753D01*
X2377721Y1714714D01*
G01X2377859Y1711762D02*
X2377832Y1711758D01*
X2377806Y1711747D01*
X2377782Y1711729D01*
X2377761Y1711704D01*
X2377744Y1711674D01*
X2377731Y1711641D01*
X2377723Y1711604D01*
X2377721Y1711565D01*
G01X2377859Y1708612D02*
X2377832Y1708608D01*
X2377806Y1708597D01*
X2377782Y1708579D01*
X2377761Y1708554D01*
X2377744Y1708525D01*
X2377731Y1708491D01*
X2377723Y1708454D01*
X2377721Y1708415D01*
G01X2377859Y1705463D02*
X2377832Y1705459D01*
X2377806Y1705448D01*
X2377782Y1705430D01*
X2377761Y1705405D01*
X2377744Y1705375D01*
X2377731Y1705341D01*
X2377723Y1705305D01*
X2377721Y1705266D01*
G01X2377859Y1702313D02*
X2377832Y1702309D01*
X2377806Y1702298D01*
X2377782Y1702280D01*
X2377761Y1702255D01*
X2377744Y1702226D01*
X2377731Y1702192D01*
X2377723Y1702155D01*
X2377721Y1702116D01*
G01X2377859Y1699163D02*
X2377832Y1699160D01*
X2377806Y1699148D01*
X2377782Y1699130D01*
X2377761Y1699106D01*
X2377744Y1699076D01*
X2377731Y1699042D01*
X2377723Y1699005D01*
X2377721Y1698966D01*
G01X2377859Y1696014D02*
X2377832Y1696010D01*
X2377806Y1695999D01*
X2377782Y1695981D01*
X2377761Y1695956D01*
X2377744Y1695926D01*
X2377731Y1695892D01*
X2377723Y1695856D01*
X2377721Y1695817D01*
G01X2382908Y1720423D02*
X2383035Y1720451D01*
X2383124Y1720524D01*
X2383155Y1720620D01*
G01X2382908Y1717274D02*
X2383035Y1717301D01*
X2383124Y1717374D01*
X2383155Y1717470D01*
G01X2382908Y1714124D02*
X2383035Y1714152D01*
X2383124Y1714225D01*
X2383155Y1714321D01*
G01X2382908Y1710974D02*
X2383035Y1711002D01*
X2383124Y1711075D01*
X2383155Y1711171D01*
G01X2382908Y1707825D02*
X2383035Y1707852D01*
X2383124Y1707925D01*
X2383155Y1708022D01*
G01X2382908Y1704675D02*
X2383035Y1704703D01*
X2383124Y1704776D01*
X2383155Y1704872D01*
G01X2382908Y1701525D02*
X2383035Y1701553D01*
X2383124Y1701626D01*
X2383155Y1701722D01*
G01X2382908Y1698376D02*
X2383035Y1698404D01*
X2383124Y1698477D01*
X2383155Y1698573D01*
G01X2382908Y1695226D02*
X2383035Y1695254D01*
X2383124Y1695327D01*
X2383155Y1695423D01*
G01X2378674Y1694262D02*
X2378752Y1694852D01*
G01X2378674Y1699262D02*
X2378752Y1699852D01*
G01X2378674Y1704262D02*
X2378752Y1704852D01*
G01X2378674Y1709262D02*
X2378752Y1709852D01*
G01X2378674Y1714262D02*
X2378752Y1714852D01*
G01X2378674Y1719262D02*
X2378752Y1719852D01*
G01X2378234Y1698966D02*
X2378244Y1699065D01*
X2378272Y1699137D01*
X2378310Y1699163D01*
G01X2378234Y1702116D02*
X2378244Y1702214D01*
X2378272Y1702286D01*
X2378310Y1702313D01*
G01X2378234Y1714714D02*
X2378244Y1714813D01*
X2378272Y1714885D01*
X2378310Y1714911D01*
G01X2378234Y1717864D02*
X2378244Y1717962D01*
X2378272Y1718035D01*
X2378310Y1718061D01*
G01X2377549Y1694262D02*
X2377822Y1694852D01*
G01X2377549Y1699262D02*
X2377822Y1699852D01*
G01X2377549Y1704262D02*
X2377822Y1704852D01*
G01X2377549Y1709262D02*
X2377822Y1709852D01*
G01X2377549Y1714262D02*
X2377822Y1714852D01*
G01X2377549Y1719262D02*
X2377822Y1719852D01*
G01X2382877Y1693277D02*
X2383017Y1693473D01*
X2383155Y1693670D01*
X2383292Y1693868D01*
G01X2377132Y1694852D02*
X2376706Y1694262D01*
G01X2377132Y1699852D02*
X2376706Y1699262D01*
G01X2377132Y1704852D02*
X2376706Y1704262D01*
G01X2377132Y1709852D02*
X2376706Y1709262D01*
G01X2377132Y1714852D02*
X2376706Y1714262D01*
G01X2377132Y1719852D02*
X2376706Y1719262D01*
G01X2382877Y1698277D02*
X2383017Y1698473D01*
X2383155Y1698670D01*
X2383292Y1698868D01*
G01X2382877Y1703277D02*
X2383017Y1703473D01*
X2383155Y1703670D01*
X2383292Y1703868D01*
G01X2382877Y1708277D02*
X2383017Y1708473D01*
X2383155Y1708670D01*
X2383292Y1708868D01*
G01X2382877Y1713277D02*
X2383017Y1713473D01*
X2383155Y1713670D01*
X2383292Y1713868D01*
G01X2382877Y1718277D02*
X2383017Y1718473D01*
X2383155Y1718670D01*
X2383292Y1718868D01*
G01X2387142Y1687293D02*
X2385173Y1685325D01*
G01X2378310Y1696014D02*
X2378272Y1695987D01*
X2378244Y1695915D01*
X2378234Y1695817D01*
G01X2378310Y1705463D02*
X2378272Y1705436D01*
X2378244Y1705364D01*
X2378234Y1705266D01*
G01X2378310Y1708612D02*
X2378272Y1708586D01*
X2378244Y1708514D01*
X2378234Y1708415D01*
G01X2378310Y1711762D02*
X2378272Y1711735D01*
X2378244Y1711663D01*
X2378234Y1711565D01*
G01X2390425Y1685325D02*
X2393835Y1683356D01*
G01X2389169Y1677700D02*
X2389114Y1678086D01*
G01X2393835Y1683356D02*
Y1681624D01*
G01X2389110Y1678159D02*
Y1685325D01*
G01X2389142Y1677009D02*
X2389198Y1677144D01*
X2389205Y1677379D01*
X2389168Y1677708D01*
G01X2389142Y1677009D02*
X2389199Y1677149D01*
X2389204Y1677389D01*
G01X2393835Y1681624D02*
X2389110Y1676978D01*
G01X2393835Y1682727D02*
X2389114Y1678086D01*
G01X2377822Y1723277D02*
X2377549Y1723868D01*
G01X2377064Y1723277D02*
X2376640Y1723868D01*
G01X2378310Y1723573D02*
X2378272Y1723599D01*
X2378244Y1723671D01*
X2378234Y1723770D01*
G01X2383155Y1724163D02*
X2383123Y1724260D01*
X2383035Y1724332D01*
X2382908Y1724360D01*
G01X2378674Y1723868D02*
X2378752Y1723277D01*
G01X2376543Y1724163D02*
X2383155D01*
G01X2376640Y1723868D02*
X2383383D01*
G01X2383155Y1723770D02*
X2376543D01*
G01X2382908Y1723573D02*
X2376823D01*
G01X2382977Y1723277D02*
X2377064D01*
G01X2382908Y1721211D02*
X2376823D01*
G01X2376543Y1721014D02*
X2383155D01*
G01X2377859Y1724360D02*
X2377832Y1724356D01*
X2377806Y1724345D01*
X2377782Y1724327D01*
X2377761Y1724302D01*
X2377744Y1724273D01*
X2377731Y1724239D01*
X2377723Y1724202D01*
X2377721Y1724163D01*
G01X2377859Y1721211D02*
X2377832Y1721207D01*
X2377806Y1721196D01*
X2377782Y1721178D01*
X2377761Y1721153D01*
X2377744Y1721123D01*
X2377731Y1721089D01*
X2377723Y1721053D01*
X2377721Y1721014D01*
G01X2383383Y1724262D02*
Y1723868D01*
G01X2383155Y1723770D02*
Y1724163D01*
G01X2378674Y1724262D02*
Y1723868D01*
G01X2378234Y1723770D02*
Y1724163D01*
G01X2377721D02*
Y1723770D01*
G01X2377549Y1723868D02*
Y1724262D01*
G01X2376640Y1723868D02*
Y1724262D01*
G01X2376543Y1724163D02*
Y1723770D01*
G01X2377721D02*
X2377723Y1723731D01*
X2377731Y1723695D01*
X2377744Y1723661D01*
X2377761Y1723630D01*
X2377782Y1723606D01*
X2377806Y1723588D01*
X2377832Y1723577D01*
X2377859Y1723573D01*
G01X2382908D02*
X2383035Y1723600D01*
X2383124Y1723673D01*
X2383155Y1723770D01*
G01X2382977Y1723277D02*
X2383113Y1723474D01*
X2383249Y1723670D01*
X2383383Y1723868D01*
G01X2378310Y1721211D02*
X2378272Y1721184D01*
X2378244Y1721112D01*
X2378234Y1721014D01*
G01X2378310Y1724360D02*
X2378272Y1724334D01*
X2378244Y1724262D01*
X2378234Y1724163D01*
G01X2383292Y1789262D02*
X2383155Y1789459D01*
X2383017Y1789656D01*
X2382877Y1789852D01*
G01X2383292Y1784262D02*
X2383155Y1784459D01*
X2383017Y1784656D01*
X2382877Y1784852D01*
G01X2383292Y1779262D02*
X2383155Y1779459D01*
X2383017Y1779656D01*
X2382877Y1779852D01*
G01X2383292Y1774262D02*
X2383155Y1774459D01*
X2383017Y1774656D01*
X2382877Y1774852D01*
G01X2383292Y1769262D02*
X2383155Y1769459D01*
X2383017Y1769656D01*
X2382877Y1769852D01*
G01X2385260Y1764262D02*
X2385123Y1764459D01*
X2384985Y1764656D01*
X2384846Y1764852D01*
G01X2377132Y1793277D02*
X2376706Y1793868D01*
G01X2377132Y1788277D02*
X2376706Y1788868D01*
G01X2377132Y1783277D02*
X2376706Y1783868D01*
G01X2377132Y1778277D02*
X2376706Y1778868D01*
G01X2377132Y1773277D02*
X2376706Y1773868D01*
G01X2377132Y1768277D02*
X2376706Y1768868D01*
G01X2379101Y1763277D02*
X2378674Y1763868D01*
G01X2378310Y1792864D02*
X2378272Y1792891D01*
X2378244Y1792963D01*
X2378234Y1793061D01*
G01X2378310Y1789714D02*
X2378272Y1789741D01*
X2378244Y1789813D01*
X2378234Y1789911D01*
G01X2378310Y1786565D02*
X2378272Y1786591D01*
X2378244Y1786663D01*
X2378234Y1786762D01*
G01X2378310Y1783415D02*
X2378272Y1783442D01*
X2378244Y1783514D01*
X2378234Y1783612D01*
G01X2378310Y1780266D02*
X2378272Y1780292D01*
X2378244Y1780364D01*
X2378234Y1780463D01*
G01X2378310Y1777116D02*
X2378272Y1777142D01*
X2378244Y1777215D01*
X2378234Y1777313D01*
G01X2378310Y1773966D02*
X2378272Y1773993D01*
X2378244Y1774065D01*
X2378234Y1774163D01*
G01X2378310Y1770817D02*
X2378272Y1770843D01*
X2378244Y1770915D01*
X2378234Y1771014D01*
G01X2378310Y1767667D02*
X2378272Y1767694D01*
X2378244Y1767766D01*
X2378234Y1767864D01*
G01X2378310Y1764518D02*
X2378272Y1764544D01*
X2378244Y1764616D01*
X2378234Y1764714D01*
G01X2378310Y1761368D02*
X2378272Y1761394D01*
X2378244Y1761467D01*
X2378234Y1761565D01*
G01X2378310Y1758218D02*
X2378272Y1758245D01*
X2378244Y1758317D01*
X2378234Y1758415D01*
G01X2378310Y1755069D02*
X2378272Y1755095D01*
X2378244Y1755167D01*
X2378234Y1755266D01*
G01X2378310Y1751919D02*
X2378272Y1751946D01*
X2378244Y1752018D01*
X2378234Y1752116D01*
G01X2378310Y1748770D02*
X2378272Y1748796D01*
X2378244Y1748868D01*
X2378234Y1748966D01*
G01X2378310Y1745620D02*
X2378272Y1745646D01*
X2378244Y1745718D01*
X2378234Y1745817D01*
G01X2378310Y1742470D02*
X2378272Y1742497D01*
X2378244Y1742569D01*
X2378234Y1742667D01*
G01X2383155Y1793455D02*
X2383123Y1793552D01*
X2383035Y1793624D01*
X2382908Y1793651D01*
G01X2383155Y1790305D02*
X2383123Y1790402D01*
X2383035Y1790474D01*
X2382908Y1790502D01*
G01X2383155Y1787155D02*
X2383123Y1787252D01*
X2383035Y1787325D01*
X2382908Y1787352D01*
G01X2383155Y1784006D02*
X2383123Y1784103D01*
X2383035Y1784175D01*
X2382908Y1784203D01*
G01X2383155Y1780856D02*
X2383123Y1780953D01*
X2383035Y1781025D01*
X2382908Y1781053D01*
G01X2383155Y1774557D02*
X2383123Y1774654D01*
X2383035Y1774726D01*
X2382908Y1774754D01*
G01X2383155Y1771407D02*
X2383123Y1771504D01*
X2383035Y1771577D01*
X2382908Y1771604D01*
G01X2383155Y1768258D02*
X2383123Y1768355D01*
X2383035Y1768427D01*
X2382908Y1768455D01*
G01X2383155Y1765108D02*
X2383123Y1765205D01*
X2383035Y1765277D01*
X2382908Y1765305D01*
G01X2383155Y1761959D02*
X2383123Y1762056D01*
X2383035Y1762128D01*
X2382908Y1762155D01*
G01X2377822Y1793277D02*
X2377549Y1793868D01*
G01X2377822Y1788277D02*
X2377549Y1788868D01*
G01X2377822Y1783277D02*
X2377549Y1783868D01*
G01X2377822Y1778277D02*
X2377549Y1778868D01*
G01X2377822Y1773277D02*
X2377549Y1773868D01*
G01X2377822Y1768277D02*
X2377549Y1768868D01*
G01X2379791Y1763277D02*
X2379518Y1763868D01*
G01X2377822Y1758277D02*
X2377549Y1758868D01*
G01X2377822Y1753277D02*
X2377549Y1753868D01*
G01X2377822Y1748277D02*
X2377549Y1748868D01*
G01X2383383Y1749262D02*
X2383249Y1749459D01*
X2383113Y1749656D01*
X2382977Y1749852D01*
G01X2383383Y1724262D02*
X2383249Y1724459D01*
X2383113Y1724656D01*
X2382977Y1724852D01*
G01X2383292Y1759262D02*
X2383155Y1759459D01*
X2383017Y1759656D01*
X2382877Y1759852D01*
G01X2383292Y1754262D02*
X2383155Y1754459D01*
X2383017Y1754656D01*
X2382877Y1754852D01*
G01X2377064Y1748277D02*
X2376640Y1748868D01*
G01X2377132Y1758277D02*
X2376706Y1758868D01*
G01X2377132Y1753277D02*
X2376706Y1753868D01*
G01X2385173Y1726801D02*
X2387142Y1724833D01*
G01X2378310Y1739321D02*
X2378272Y1739347D01*
X2378244Y1739419D01*
X2378234Y1739518D01*
G01X2378310Y1736171D02*
X2378272Y1736198D01*
X2378244Y1736270D01*
X2378234Y1736368D01*
G01X2378310Y1733022D02*
X2378272Y1733048D01*
X2378244Y1733120D01*
X2378234Y1733218D01*
G01X2378310Y1729872D02*
X2378272Y1729898D01*
X2378244Y1729970D01*
X2378234Y1730069D01*
G01X2378310Y1726722D02*
X2378272Y1726749D01*
X2378244Y1726821D01*
X2378234Y1726919D01*
G01X2378974Y1743752D02*
X2378967Y1743756D01*
X2378961Y1743767D01*
X2378956Y1743785D01*
X2378951Y1743810D01*
X2378947Y1743839D01*
X2378944Y1743873D01*
X2378942Y1743910D01*
X2378941Y1743949D01*
G01X2378974Y1740602D02*
X2378967Y1740606D01*
X2378961Y1740617D01*
X2378956Y1740635D01*
X2378951Y1740660D01*
X2378947Y1740690D01*
X2378944Y1740724D01*
X2378942Y1740760D01*
X2378941Y1740799D01*
G01X2378974Y1737453D02*
X2378967Y1737457D01*
X2378961Y1737468D01*
X2378956Y1737486D01*
X2378951Y1737511D01*
X2378947Y1737540D01*
X2378944Y1737574D01*
X2378942Y1737611D01*
X2378941Y1737650D01*
G01X2378974Y1734303D02*
X2378967Y1734307D01*
X2378961Y1734318D01*
X2378956Y1734336D01*
X2378951Y1734361D01*
X2378947Y1734391D01*
X2378944Y1734424D01*
X2378942Y1734461D01*
X2378941Y1734500D01*
G01X2378974Y1731154D02*
X2378967Y1731157D01*
X2378961Y1731168D01*
X2378956Y1731187D01*
X2378951Y1731211D01*
X2378947Y1731241D01*
X2378944Y1731275D01*
X2378942Y1731312D01*
X2378941Y1731350D01*
G01X2378974Y1728004D02*
X2378967Y1728008D01*
X2378961Y1728019D01*
X2378956Y1728037D01*
X2378951Y1728062D01*
X2378947Y1728091D01*
X2378944Y1728125D01*
X2378942Y1728162D01*
X2378941Y1728201D01*
G01X2382908Y1777903D02*
X2383034Y1777876D01*
X2383124Y1777803D01*
X2383155Y1777707D01*
G01X2378674Y1793868D02*
X2378752Y1793277D01*
G01X2378674Y1788868D02*
X2378752Y1788277D01*
G01X2378674Y1783868D02*
X2378752Y1783277D01*
G01X2378674Y1778868D02*
X2378752Y1778277D01*
G01X2380643Y1763868D02*
X2380720Y1763277D01*
G01X2378674Y1773868D02*
X2378752Y1773277D01*
G01X2378674Y1768868D02*
X2378752Y1768277D01*
G01X2378674Y1758868D02*
X2378752Y1758277D01*
G01X2383155Y1758809D02*
X2383123Y1758906D01*
X2383035Y1758978D01*
X2382908Y1759006D01*
G01X2383155Y1755659D02*
X2383123Y1755756D01*
X2383035Y1755829D01*
X2382908Y1755856D01*
G01X2383155Y1752510D02*
X2383123Y1752607D01*
X2383035Y1752679D01*
X2382908Y1752707D01*
G01X2383155Y1749360D02*
X2383123Y1749457D01*
X2383035Y1749529D01*
X2382908Y1749557D01*
G01X2383155Y1746211D02*
X2383123Y1746308D01*
X2383035Y1746380D01*
X2382908Y1746407D01*
G01X2383155Y1743061D02*
X2383123Y1743158D01*
X2383035Y1743230D01*
X2382908Y1743258D01*
G01X2383155Y1739911D02*
X2383123Y1740008D01*
X2383035Y1740081D01*
X2382908Y1740108D01*
G01X2383155Y1736762D02*
X2383123Y1736859D01*
X2383035Y1736931D01*
X2382908Y1736959D01*
G01X2383155Y1733612D02*
X2383123Y1733709D01*
X2383035Y1733781D01*
X2382908Y1733809D01*
G01X2383155Y1730463D02*
X2383123Y1730560D01*
X2383035Y1730632D01*
X2382908Y1730659D01*
G01X2383155Y1727313D02*
X2383123Y1727410D01*
X2383035Y1727482D01*
X2382908Y1727510D01*
G01X2383165Y1744933D02*
X2383132Y1745032D01*
X2383043Y1745103D01*
X2382917Y1745130D01*
G01X2383165Y1741784D02*
X2383132Y1741883D01*
X2383043Y1741953D01*
X2382917Y1741980D01*
G01X2383165Y1738634D02*
X2383132Y1738733D01*
X2383043Y1738804D01*
X2382917Y1738831D01*
G01X2383165Y1735484D02*
X2383132Y1735583D01*
X2383043Y1735654D01*
X2382917Y1735681D01*
G01X2383165Y1732335D02*
X2383132Y1732434D01*
X2383043Y1732505D01*
X2382917Y1732532D01*
G01X2383165Y1729185D02*
X2383132Y1729284D01*
X2383043Y1729355D01*
X2382917Y1729382D01*
G01X2377937Y1743752D02*
X2377908Y1743756D01*
X2377881Y1743767D01*
X2377855Y1743785D01*
X2377832Y1743810D01*
X2377814Y1743839D01*
X2377800Y1743873D01*
X2377792Y1743910D01*
X2377789Y1743949D01*
G01X2377937Y1740602D02*
X2377908Y1740606D01*
X2377881Y1740617D01*
X2377855Y1740635D01*
X2377832Y1740660D01*
X2377814Y1740690D01*
X2377800Y1740724D01*
X2377792Y1740760D01*
X2377789Y1740799D01*
G01X2377937Y1737453D02*
X2377908Y1737457D01*
X2377881Y1737468D01*
X2377855Y1737486D01*
X2377832Y1737511D01*
X2377814Y1737540D01*
X2377800Y1737574D01*
X2377792Y1737611D01*
X2377789Y1737650D01*
G01X2377937Y1734303D02*
X2377908Y1734307D01*
X2377881Y1734318D01*
X2377855Y1734336D01*
X2377832Y1734361D01*
X2377814Y1734391D01*
X2377800Y1734424D01*
X2377792Y1734461D01*
X2377789Y1734500D01*
G01X2377937Y1731154D02*
X2377908Y1731157D01*
X2377881Y1731168D01*
X2377855Y1731187D01*
X2377832Y1731211D01*
X2377814Y1731241D01*
X2377800Y1731275D01*
X2377792Y1731312D01*
X2377789Y1731350D01*
G01X2377937Y1728004D02*
X2377908Y1728008D01*
X2377881Y1728019D01*
X2377855Y1728037D01*
X2377832Y1728062D01*
X2377814Y1728091D01*
X2377800Y1728125D01*
X2377792Y1728162D01*
X2377789Y1728201D01*
G01X2382908Y1793651D02*
X2376823D01*
G01X2376543Y1793455D02*
X2383155D01*
G01X2382877Y1793277D02*
X2377132D01*
G01X2383155Y1793061D02*
X2376543D01*
G01X2382908Y1792864D02*
X2376823D01*
G01X2382908Y1790502D02*
X2376823D01*
G01X2376543Y1790305D02*
X2383155D01*
G01Y1789911D02*
X2376543D01*
G01X2382877Y1789852D02*
X2377132D01*
G01X2382908Y1789714D02*
X2376823D01*
G01X2376706Y1789262D02*
X2383292D01*
G01X2376706Y1788868D02*
X2383292D01*
G01X2382877Y1788277D02*
X2377132D01*
G01X2382908Y1787352D02*
X2376823D01*
G01X2376543Y1787155D02*
X2383155D01*
G01Y1786762D02*
X2376543D01*
G01X2382908Y1786565D02*
X2376823D01*
G01X2382877Y1784852D02*
X2377132D01*
G01X2376706Y1784262D02*
X2383292D01*
G01X2382908Y1784203D02*
X2376823D01*
G01X2376543Y1784006D02*
X2383155D01*
G01X2376706Y1783868D02*
X2383292D01*
G01X2383155Y1783612D02*
X2376543D01*
G01X2382908Y1783415D02*
X2376823D01*
G01X2382877Y1783277D02*
X2377132D01*
G01X2382908Y1781053D02*
X2376823D01*
G01X2376543Y1780856D02*
X2383155D01*
G01Y1780463D02*
X2376543D01*
G01X2382908Y1780266D02*
X2376823D01*
G01X2382877Y1779852D02*
X2377132D01*
G01X2376706Y1779262D02*
X2383292D01*
G01X2376706Y1778868D02*
X2383292D01*
G01X2382877Y1778277D02*
X2377132D01*
G01X2382908Y1777903D02*
X2376823D01*
G01X2376543Y1777707D02*
X2383155D01*
G01Y1777313D02*
X2376543D01*
G01X2382908Y1777116D02*
X2376823D01*
G01X2382877Y1774852D02*
X2377132D01*
G01X2382908Y1774754D02*
X2376823D01*
G01X2376543Y1774557D02*
X2383155D01*
G01X2376706Y1774262D02*
X2383292D01*
G01X2383155Y1774163D02*
X2376543D01*
G01X2382908Y1773966D02*
X2376823D01*
G01X2376706Y1773868D02*
X2383292D01*
G01X2382877Y1773277D02*
X2377132D01*
G01X2382908Y1771604D02*
X2376823D01*
G01X2376543Y1771407D02*
X2383155D01*
G01Y1771014D02*
X2376543D01*
G01X2382908Y1770817D02*
X2376823D01*
G01X2382877Y1769852D02*
X2377132D01*
G01X2376706Y1769262D02*
X2383292D01*
G01X2376706Y1768868D02*
X2383292D01*
G01X2382908Y1768455D02*
X2376823D01*
G01X2382877Y1768277D02*
X2377132D01*
G01X2376543Y1768258D02*
X2383155D01*
G01Y1767864D02*
X2376543D01*
G01X2382908Y1767667D02*
X2376823D01*
G01X2382908Y1765305D02*
X2376823D01*
G01X2376543Y1765108D02*
X2383155D01*
G01X2384846Y1764852D02*
X2379101D01*
G01X2383155Y1764714D02*
X2376543D01*
G01X2382908Y1764518D02*
X2376823D01*
G01X2378674Y1764262D02*
X2385260D01*
G01X2378674Y1763868D02*
X2385260D01*
G01X2384846Y1763277D02*
X2379101D01*
G01X2382908Y1762155D02*
X2376823D01*
G01X2376543Y1761959D02*
X2383155D01*
G01Y1761565D02*
X2376543D01*
G01X2382908Y1761368D02*
X2376823D01*
G01X2382877Y1759852D02*
X2377132D01*
G01X2376706Y1759262D02*
X2383292D01*
G01X2382908Y1759006D02*
X2376823D01*
G01X2376706Y1758868D02*
X2383292D01*
G01X2376543Y1758809D02*
X2383155D01*
G01Y1758415D02*
X2376543D01*
G01X2382877Y1758277D02*
X2377132D01*
G01X2382908Y1758218D02*
X2376823D01*
G01X2382908Y1755856D02*
X2376823D01*
G01X2376543Y1755659D02*
X2383155D01*
G01Y1755266D02*
X2376543D01*
G01X2382908Y1755069D02*
X2376823D01*
G01X2382877Y1754852D02*
X2377132D01*
G01X2376706Y1754262D02*
X2383292D01*
G01X2376706Y1753868D02*
X2383292D01*
G01X2382877Y1753277D02*
X2377132D01*
G01X2382908Y1752707D02*
X2376823D01*
G01X2376543Y1752510D02*
X2383155D01*
G01Y1752116D02*
X2376543D01*
G01X2382908Y1751919D02*
X2376823D01*
G01X2382977Y1749852D02*
X2377064D01*
G01X2382908Y1749557D02*
X2376823D01*
G01X2376543Y1749360D02*
X2383155D01*
G01X2376640Y1749262D02*
X2383383D01*
G01X2383155Y1748966D02*
X2376543D01*
G01X2376640Y1748868D02*
X2383383D01*
G01X2382908Y1748770D02*
X2376823D01*
G01X2382977Y1748277D02*
X2377064D01*
G01X2380673Y1747490D02*
X2387142D01*
G01X2382908Y1746407D02*
X2376823D01*
G01X2376543Y1746211D02*
X2383155D01*
G01Y1745817D02*
X2376543D01*
G01X2382908Y1745620D02*
X2376823D01*
G01X2377109Y1745130D02*
X2382917D01*
G01X2383165Y1744933D02*
X2376847D01*
G01Y1743949D02*
X2383165D01*
G01X2377109Y1743752D02*
X2382917D01*
G01X2382908Y1743258D02*
X2376823D01*
G01X2376543Y1743061D02*
X2383155D01*
G01Y1742667D02*
X2376543D01*
G01X2382908Y1742470D02*
X2376823D01*
G01X2377109Y1741980D02*
X2382917D01*
G01X2383165Y1741784D02*
X2376847D01*
G01Y1740799D02*
X2383165D01*
G01X2377109Y1740602D02*
X2382917D01*
G01X2382908Y1740108D02*
X2376823D01*
G01X2376543Y1739911D02*
X2383155D01*
G01Y1739518D02*
X2376543D01*
G01X2382908Y1739321D02*
X2376823D01*
G01X2377109Y1738831D02*
X2382917D01*
G01X2383165Y1738634D02*
X2376847D01*
G01Y1737650D02*
X2383165D01*
G01X2377109Y1737453D02*
X2382917D01*
G01X2382908Y1736959D02*
X2376823D01*
G01X2376543Y1736762D02*
X2383155D01*
G01Y1736368D02*
X2376543D01*
G01X2382908Y1736171D02*
X2376823D01*
G01X2378674Y1753868D02*
X2378752Y1753277D01*
G01X2378674Y1748868D02*
X2378752Y1748277D01*
G01X2377109Y1735681D02*
X2382917D01*
G01X2383165Y1735484D02*
X2376847D01*
G01Y1734500D02*
X2383165D01*
G01X2377109Y1734303D02*
X2382917D01*
G01X2382908Y1733809D02*
X2376823D01*
G01X2376543Y1733612D02*
X2383155D01*
G01Y1733218D02*
X2376543D01*
G01X2382908Y1733022D02*
X2376823D01*
G01X2377109Y1732532D02*
X2382917D01*
G01X2383165Y1732335D02*
X2376847D01*
G01Y1731350D02*
X2383165D01*
G01X2377109Y1731154D02*
X2382917D01*
G01X2382908Y1730659D02*
X2376823D01*
G01X2376543Y1730463D02*
X2383155D01*
G01Y1730069D02*
X2376543D01*
G01X2382908Y1729872D02*
X2376823D01*
G01X2377109Y1729382D02*
X2382917D01*
G01X2383165Y1729185D02*
X2376847D01*
G01Y1728201D02*
X2383165D01*
G01X2377109Y1728004D02*
X2382917D01*
G01X2382908Y1727510D02*
X2376823D01*
G01X2376543Y1727313D02*
X2383155D01*
G01Y1726919D02*
X2376543D01*
G01X2382908Y1726722D02*
X2376823D01*
G01X2387142Y1725640D02*
X2380673D01*
G01X2382977Y1724852D02*
X2377064D01*
G01X2382908Y1724360D02*
X2376823D01*
G01X2376640Y1724262D02*
X2383383D01*
G01X2377859Y1793651D02*
X2377832Y1793648D01*
X2377806Y1793637D01*
X2377782Y1793619D01*
X2377761Y1793594D01*
X2377744Y1793564D01*
X2377731Y1793530D01*
X2377723Y1793494D01*
X2377721Y1793455D01*
G01X2377859Y1790502D02*
X2377832Y1790498D01*
X2377806Y1790487D01*
X2377782Y1790469D01*
X2377761Y1790444D01*
X2377744Y1790415D01*
X2377731Y1790381D01*
X2377723Y1790344D01*
X2377721Y1790305D01*
G01X2377859Y1787352D02*
X2377832Y1787349D01*
X2377806Y1787337D01*
X2377782Y1787319D01*
X2377761Y1787295D01*
X2377744Y1787265D01*
X2377731Y1787231D01*
X2377723Y1787194D01*
X2377721Y1787155D01*
G01X2377859Y1784203D02*
X2377832Y1784199D01*
X2377806Y1784188D01*
X2377782Y1784170D01*
X2377761Y1784145D01*
X2377744Y1784115D01*
X2377731Y1784081D01*
X2377723Y1784045D01*
X2377721Y1784006D01*
G01X2377859Y1781053D02*
X2377832Y1781049D01*
X2377806Y1781038D01*
X2377782Y1781020D01*
X2377761Y1780995D01*
X2377744Y1780966D01*
X2377731Y1780932D01*
X2377723Y1780895D01*
X2377721Y1780856D01*
G01X2377859Y1777903D02*
X2377832Y1777900D01*
X2377806Y1777889D01*
X2377782Y1777871D01*
X2377761Y1777846D01*
X2377744Y1777816D01*
X2377731Y1777782D01*
X2377723Y1777746D01*
X2377721Y1777707D01*
G01X2377859Y1774754D02*
X2377832Y1774750D01*
X2377806Y1774739D01*
X2377782Y1774721D01*
X2377761Y1774696D01*
X2377744Y1774667D01*
X2377731Y1774633D01*
X2377723Y1774596D01*
X2377721Y1774557D01*
G01X2377859Y1771604D02*
X2377832Y1771600D01*
X2377806Y1771589D01*
X2377782Y1771571D01*
X2377761Y1771547D01*
X2377744Y1771517D01*
X2377731Y1771483D01*
X2377723Y1771446D01*
X2377721Y1771407D01*
G01X2377859Y1768455D02*
X2377832Y1768451D01*
X2377806Y1768440D01*
X2377782Y1768422D01*
X2377761Y1768397D01*
X2377744Y1768367D01*
X2377731Y1768333D01*
X2377723Y1768297D01*
X2377721Y1768258D01*
G01X2377859Y1765305D02*
X2377832Y1765301D01*
X2377806Y1765290D01*
X2377782Y1765272D01*
X2377761Y1765247D01*
X2377744Y1765218D01*
X2377731Y1765184D01*
X2377723Y1765147D01*
X2377721Y1765108D01*
G01X2377859Y1762155D02*
X2377832Y1762152D01*
X2377806Y1762141D01*
X2377782Y1762123D01*
X2377761Y1762098D01*
X2377744Y1762068D01*
X2377731Y1762034D01*
X2377723Y1761997D01*
X2377721Y1761959D01*
G01X2377859Y1759006D02*
X2377832Y1759002D01*
X2377806Y1758991D01*
X2377782Y1758973D01*
X2377761Y1758948D01*
X2377744Y1758918D01*
X2377731Y1758885D01*
X2377723Y1758848D01*
X2377721Y1758809D01*
G01X2377859Y1755856D02*
X2377832Y1755852D01*
X2377806Y1755841D01*
X2377782Y1755823D01*
X2377761Y1755799D01*
X2377744Y1755769D01*
X2377731Y1755735D01*
X2377723Y1755698D01*
X2377721Y1755659D01*
G01X2377859Y1752707D02*
X2377832Y1752703D01*
X2377806Y1752692D01*
X2377782Y1752674D01*
X2377761Y1752649D01*
X2377744Y1752619D01*
X2377731Y1752585D01*
X2377723Y1752549D01*
X2377721Y1752510D01*
G01X2377859Y1749557D02*
X2377832Y1749553D01*
X2377806Y1749542D01*
X2377782Y1749524D01*
X2377761Y1749499D01*
X2377744Y1749470D01*
X2377731Y1749436D01*
X2377723Y1749399D01*
X2377721Y1749360D01*
G01X2377859Y1746407D02*
X2377832Y1746404D01*
X2377806Y1746393D01*
X2377782Y1746375D01*
X2377761Y1746350D01*
X2377744Y1746320D01*
X2377731Y1746286D01*
X2377723Y1746249D01*
X2377721Y1746211D01*
G01X2377859Y1743258D02*
X2377832Y1743254D01*
X2377806Y1743243D01*
X2377782Y1743225D01*
X2377761Y1743200D01*
X2377744Y1743170D01*
X2377731Y1743137D01*
X2377723Y1743100D01*
X2377721Y1743061D01*
G01X2377859Y1740108D02*
X2377832Y1740104D01*
X2377806Y1740093D01*
X2377782Y1740075D01*
X2377761Y1740051D01*
X2377744Y1740021D01*
X2377731Y1739987D01*
X2377723Y1739950D01*
X2377721Y1739911D01*
G01X2377859Y1736959D02*
X2377832Y1736955D01*
X2377806Y1736944D01*
X2377782Y1736926D01*
X2377761Y1736901D01*
X2377744Y1736871D01*
X2377731Y1736837D01*
X2377723Y1736801D01*
X2377721Y1736762D01*
G01X2377859Y1733809D02*
X2377832Y1733805D01*
X2377806Y1733794D01*
X2377782Y1733776D01*
X2377761Y1733751D01*
X2377744Y1733722D01*
X2377731Y1733688D01*
X2377723Y1733651D01*
X2377721Y1733612D01*
G01X2377859Y1730659D02*
X2377832Y1730656D01*
X2377806Y1730645D01*
X2377782Y1730626D01*
X2377761Y1730602D01*
X2377744Y1730572D01*
X2377731Y1730538D01*
X2377723Y1730501D01*
X2377721Y1730463D01*
G01X2377859Y1727510D02*
X2377832Y1727506D01*
X2377806Y1727495D01*
X2377782Y1727477D01*
X2377761Y1727452D01*
X2377744Y1727422D01*
X2377731Y1727389D01*
X2377723Y1727352D01*
X2377721Y1727313D01*
G01X2382908Y1792864D02*
X2383035Y1792892D01*
X2383124Y1792965D01*
X2383155Y1793061D01*
G01X2382908Y1789714D02*
X2383035Y1789742D01*
X2383124Y1789815D01*
X2383155Y1789911D01*
G01X2382908Y1786565D02*
X2383035Y1786593D01*
X2383124Y1786665D01*
X2383155Y1786762D01*
G01X2382908Y1783415D02*
X2383035Y1783443D01*
X2383124Y1783516D01*
X2383155Y1783612D01*
G01X2382908Y1780266D02*
X2383035Y1780293D01*
X2383124Y1780366D01*
X2383155Y1780463D01*
G01X2382908Y1773966D02*
X2383035Y1773994D01*
X2383124Y1774067D01*
X2383155Y1774163D01*
G01X2382908Y1770817D02*
X2383035Y1770845D01*
X2383124Y1770917D01*
X2383155Y1771014D01*
G01X2382908Y1767667D02*
X2383035Y1767695D01*
X2383124Y1767768D01*
X2383155Y1767864D01*
G01X2382908Y1764518D02*
X2383035Y1764545D01*
X2383124Y1764618D01*
X2383155Y1764714D01*
G01X2382908Y1761368D02*
X2383035Y1761396D01*
X2383124Y1761469D01*
X2383155Y1761565D01*
G01X2378941Y1729185D02*
X2378942Y1729223D01*
X2378943Y1729260D01*
X2378946Y1729294D01*
X2378951Y1729324D01*
X2378955Y1729349D01*
X2378961Y1729367D01*
X2378967Y1729378D01*
X2378974Y1729382D01*
G01X2378941Y1732335D02*
X2378942Y1732373D01*
X2378943Y1732410D01*
X2378946Y1732444D01*
X2378951Y1732474D01*
X2378955Y1732498D01*
X2378961Y1732516D01*
X2378967Y1732528D01*
X2378974Y1732532D01*
G01X2378941Y1735484D02*
X2378942Y1735523D01*
X2378943Y1735559D01*
X2378946Y1735593D01*
X2378951Y1735624D01*
X2378955Y1735648D01*
X2378961Y1735666D01*
X2378967Y1735677D01*
X2378974Y1735681D01*
G01X2378941Y1738634D02*
X2378942Y1738672D01*
X2378943Y1738709D01*
X2378946Y1738743D01*
X2378951Y1738773D01*
X2378955Y1738798D01*
X2378961Y1738816D01*
X2378967Y1738827D01*
X2378974Y1738831D01*
G01X2378941Y1741784D02*
X2378942Y1741822D01*
X2378943Y1741859D01*
X2378946Y1741892D01*
X2378951Y1741923D01*
X2378955Y1741947D01*
X2378961Y1741965D01*
X2378967Y1741977D01*
X2378974Y1741980D01*
G01X2378941Y1744933D02*
X2378942Y1744971D01*
X2378943Y1745008D01*
X2378946Y1745042D01*
X2378951Y1745072D01*
X2378955Y1745097D01*
X2378961Y1745115D01*
X2378967Y1745126D01*
X2378974Y1745130D01*
G01X2386130Y1752766D02*
Y1747286D01*
G01X2385961Y1725640D02*
Y1747490D01*
G01Y1823671D02*
Y1752766D01*
G01X2385260Y1764262D02*
Y1763868D01*
G01X2383383Y1749262D02*
Y1748868D01*
G01X2383292Y1754262D02*
Y1753868D01*
G01Y1759262D02*
Y1758868D01*
G01Y1769262D02*
Y1768868D01*
G01Y1774262D02*
Y1773868D01*
G01Y1779262D02*
Y1778868D01*
G01Y1784262D02*
Y1783868D01*
G01Y1789262D02*
Y1788868D01*
G01X2383165Y1729185D02*
Y1728201D01*
G01Y1735484D02*
Y1734500D01*
G01Y1732335D02*
Y1731350D01*
G01Y1738634D02*
Y1737650D01*
G01Y1741784D02*
Y1740799D01*
G01Y1744933D02*
Y1743949D01*
G01X2383155Y1793061D02*
Y1793455D01*
G01Y1789911D02*
Y1790305D01*
G01Y1786762D02*
Y1787155D01*
G01Y1783612D02*
Y1784006D01*
G01Y1777313D02*
Y1777707D01*
G01Y1780463D02*
Y1780856D01*
G01Y1774163D02*
Y1774557D01*
G01Y1771014D02*
Y1771407D01*
G01Y1767864D02*
Y1768258D01*
G01Y1764714D02*
Y1765108D01*
G01Y1761565D02*
Y1761959D01*
G01Y1755266D02*
Y1755659D01*
G01Y1758415D02*
Y1758809D01*
G01Y1752116D02*
Y1752510D01*
G01Y1745817D02*
Y1746211D01*
G01Y1748966D02*
Y1749360D01*
G01Y1742667D02*
Y1743061D01*
G01Y1739518D02*
Y1739911D01*
G01Y1736368D02*
Y1736762D01*
G01Y1733218D02*
Y1733612D01*
G01Y1730069D02*
Y1730463D01*
G01Y1726919D02*
Y1727313D01*
G01X2380673Y1726821D02*
Y1725640D01*
G01Y1747490D02*
Y1746309D01*
G01X2380643Y1764262D02*
Y1763868D01*
G01X2379518D02*
Y1764262D01*
G01X2378941Y1743949D02*
Y1744933D01*
G01Y1740799D02*
Y1741784D01*
G01Y1737650D02*
Y1738634D01*
G01Y1734500D02*
Y1735484D01*
G01Y1731350D02*
Y1732335D01*
G01Y1728201D02*
Y1729185D01*
G01X2378674Y1763868D02*
Y1764262D01*
G01Y1749262D02*
Y1748868D01*
G01Y1754262D02*
Y1753868D01*
G01Y1759262D02*
Y1758868D01*
G01Y1769262D02*
Y1768868D01*
G01Y1774262D02*
Y1773868D01*
G01Y1779262D02*
Y1778868D01*
G01Y1784262D02*
Y1783868D01*
G01Y1789262D02*
Y1788868D01*
G01X2378234Y1793061D02*
Y1793455D01*
G01Y1789911D02*
Y1790305D01*
G01Y1786762D02*
Y1787155D01*
G01Y1783612D02*
Y1784006D01*
G01Y1777313D02*
Y1777707D01*
G01Y1780463D02*
Y1780856D01*
G01Y1774163D02*
Y1774557D01*
G01Y1771014D02*
Y1771407D01*
G01Y1767864D02*
Y1768258D01*
G01Y1764714D02*
Y1765108D01*
G01Y1761565D02*
Y1761959D01*
G01Y1755266D02*
Y1755659D01*
G01Y1758415D02*
Y1758809D01*
G01Y1752116D02*
Y1752510D01*
G01Y1745817D02*
Y1746211D01*
G01Y1748966D02*
Y1749360D01*
G01Y1742667D02*
Y1743061D01*
G01Y1739518D02*
Y1739911D01*
G01Y1736368D02*
Y1736762D01*
G01Y1733218D02*
Y1733612D01*
G01Y1730069D02*
Y1730463D01*
G01Y1726919D02*
Y1727313D01*
G01X2377789Y1743949D02*
Y1744933D01*
G01Y1740799D02*
Y1741784D01*
G01Y1737650D02*
Y1738634D01*
G01Y1734500D02*
Y1735484D01*
G01Y1731350D02*
Y1732335D01*
G01Y1728201D02*
Y1729185D01*
G01X2377721Y1730463D02*
Y1730069D01*
G01Y1727313D02*
Y1726919D01*
G01Y1733612D02*
Y1733218D01*
G01Y1739911D02*
Y1739518D01*
G01Y1736762D02*
Y1736368D01*
G01Y1743061D02*
Y1742667D01*
G01Y1746211D02*
Y1745817D01*
G01Y1749360D02*
Y1748966D01*
G01Y1752510D02*
Y1752116D01*
G01Y1755659D02*
Y1755266D01*
G01Y1758809D02*
Y1758415D01*
G01Y1761959D02*
Y1761565D01*
G01Y1768258D02*
Y1767864D01*
G01Y1765108D02*
Y1764714D01*
G01Y1771407D02*
Y1771014D01*
G01Y1774557D02*
Y1774163D01*
G01Y1777707D02*
Y1777313D01*
G01Y1780856D02*
Y1780463D01*
G01Y1784006D02*
Y1783612D01*
G01Y1790305D02*
Y1789911D01*
G01Y1787155D02*
Y1786762D01*
G01Y1793455D02*
Y1793061D01*
G01X2377549Y1788868D02*
Y1789262D01*
G01Y1783868D02*
Y1784262D01*
G01Y1778868D02*
Y1779262D01*
G01Y1773868D02*
Y1774262D01*
G01Y1768868D02*
Y1769262D01*
G01Y1758868D02*
Y1759262D01*
G01Y1753868D02*
Y1754262D01*
G01Y1748868D02*
Y1749262D01*
G01X2376847Y1743949D02*
Y1744933D01*
G01Y1740799D02*
Y1741784D01*
G01Y1737650D02*
Y1738634D01*
G01Y1734500D02*
Y1735484D01*
G01Y1731350D02*
Y1732335D01*
G01Y1728201D02*
Y1729185D01*
G01X2376706Y1788868D02*
Y1789262D01*
G01Y1783868D02*
Y1784262D01*
G01Y1778868D02*
Y1779262D01*
G01Y1773868D02*
Y1774262D01*
G01Y1768868D02*
Y1769262D01*
G01Y1758868D02*
Y1759262D01*
G01Y1753868D02*
Y1754262D01*
G01X2376640Y1748868D02*
Y1749262D01*
G01X2376543Y1730463D02*
Y1730069D01*
G01Y1727313D02*
Y1726919D01*
G01Y1733612D02*
Y1733218D01*
G01Y1739911D02*
Y1739518D01*
G01Y1736762D02*
Y1736368D01*
G01Y1743061D02*
Y1742667D01*
G01Y1746211D02*
Y1745817D01*
G01Y1749360D02*
Y1748966D01*
G01Y1752510D02*
Y1752116D01*
G01Y1755659D02*
Y1755266D01*
G01Y1758809D02*
Y1758415D01*
G01Y1761959D02*
Y1761565D01*
G01Y1768258D02*
Y1767864D01*
G01Y1765108D02*
Y1764714D01*
G01Y1771407D02*
Y1771014D01*
G01Y1774557D02*
Y1774163D01*
G01Y1777707D02*
Y1777313D01*
G01Y1780856D02*
Y1780463D01*
G01Y1784006D02*
Y1783612D01*
G01Y1790305D02*
Y1789911D01*
G01Y1787155D02*
Y1786762D01*
G01Y1793455D02*
Y1793061D01*
G01X2377721D02*
X2377723Y1793023D01*
X2377731Y1792986D01*
X2377744Y1792952D01*
X2377761Y1792922D01*
X2377782Y1792897D01*
X2377806Y1792879D01*
X2377832Y1792868D01*
X2377859Y1792864D01*
G01X2377721Y1789911D02*
X2377723Y1789873D01*
X2377731Y1789836D01*
X2377744Y1789802D01*
X2377761Y1789772D01*
X2377782Y1789748D01*
X2377806Y1789730D01*
X2377832Y1789718D01*
X2377859Y1789714D01*
G01X2377721Y1786762D02*
X2377723Y1786723D01*
X2377731Y1786687D01*
X2377744Y1786653D01*
X2377761Y1786623D01*
X2377782Y1786598D01*
X2377806Y1786580D01*
X2377832Y1786569D01*
X2377859Y1786565D01*
G01X2377721Y1783612D02*
X2377723Y1783574D01*
X2377731Y1783537D01*
X2377744Y1783503D01*
X2377761Y1783473D01*
X2377782Y1783449D01*
X2377806Y1783430D01*
X2377832Y1783419D01*
X2377859Y1783415D01*
G01X2377721Y1780463D02*
X2377723Y1780424D01*
X2377731Y1780387D01*
X2377744Y1780354D01*
X2377761Y1780323D01*
X2377782Y1780299D01*
X2377806Y1780281D01*
X2377832Y1780270D01*
X2377859Y1780266D01*
G01X2377721Y1777313D02*
X2377723Y1777275D01*
X2377731Y1777238D01*
X2377744Y1777204D01*
X2377761Y1777174D01*
X2377782Y1777149D01*
X2377806Y1777131D01*
X2377832Y1777120D01*
X2377859Y1777116D01*
G01X2377721Y1774163D02*
X2377723Y1774125D01*
X2377731Y1774088D01*
X2377744Y1774054D01*
X2377761Y1774024D01*
X2377782Y1774000D01*
X2377806Y1773982D01*
X2377832Y1773970D01*
X2377859Y1773966D01*
G01X2377721Y1771014D02*
X2377723Y1770975D01*
X2377731Y1770939D01*
X2377744Y1770905D01*
X2377761Y1770874D01*
X2377782Y1770850D01*
X2377806Y1770832D01*
X2377832Y1770821D01*
X2377859Y1770817D01*
G01X2377721Y1767864D02*
X2377723Y1767826D01*
X2377731Y1767789D01*
X2377744Y1767755D01*
X2377761Y1767725D01*
X2377782Y1767701D01*
X2377806Y1767682D01*
X2377832Y1767671D01*
X2377859Y1767667D01*
G01X2377721Y1764714D02*
X2377723Y1764676D01*
X2377731Y1764639D01*
X2377744Y1764606D01*
X2377761Y1764575D01*
X2377782Y1764551D01*
X2377806Y1764533D01*
X2377832Y1764521D01*
X2377859Y1764518D01*
G01X2377721Y1761565D02*
X2377723Y1761527D01*
X2377731Y1761490D01*
X2377744Y1761456D01*
X2377761Y1761426D01*
X2377782Y1761401D01*
X2377806Y1761383D01*
X2377832Y1761372D01*
X2377859Y1761368D01*
G01X2377721Y1758415D02*
X2377723Y1758377D01*
X2377731Y1758340D01*
X2377744Y1758306D01*
X2377761Y1758276D01*
X2377782Y1758252D01*
X2377806Y1758234D01*
X2377832Y1758222D01*
X2377859Y1758218D01*
G01X2377721Y1755266D02*
X2377723Y1755227D01*
X2377731Y1755191D01*
X2377744Y1755157D01*
X2377761Y1755126D01*
X2377782Y1755102D01*
X2377806Y1755084D01*
X2377832Y1755073D01*
X2377859Y1755069D01*
G01X2377721Y1752116D02*
X2377723Y1752078D01*
X2377731Y1752041D01*
X2377744Y1752007D01*
X2377761Y1751977D01*
X2377782Y1751952D01*
X2377806Y1751934D01*
X2377832Y1751923D01*
X2377859Y1751919D01*
G01X2377721Y1748966D02*
X2377723Y1748928D01*
X2377731Y1748891D01*
X2377744Y1748857D01*
X2377761Y1748827D01*
X2377782Y1748803D01*
X2377806Y1748785D01*
X2377832Y1748773D01*
X2377859Y1748770D01*
G01X2377721Y1745817D02*
X2377723Y1745779D01*
X2377731Y1745742D01*
X2377744Y1745708D01*
X2377761Y1745678D01*
X2377782Y1745653D01*
X2377806Y1745635D01*
X2377832Y1745624D01*
X2377859Y1745620D01*
G01X2377721Y1742667D02*
X2377723Y1742629D01*
X2377731Y1742592D01*
X2377744Y1742558D01*
X2377761Y1742528D01*
X2377782Y1742504D01*
X2377806Y1742485D01*
X2377832Y1742474D01*
X2377859Y1742470D01*
G01X2377721Y1739518D02*
X2377723Y1739479D01*
X2377731Y1739443D01*
X2377744Y1739409D01*
X2377761Y1739378D01*
X2377782Y1739354D01*
X2377806Y1739336D01*
X2377832Y1739325D01*
X2377859Y1739321D01*
G01X2377721Y1736368D02*
X2377723Y1736330D01*
X2377731Y1736293D01*
X2377744Y1736259D01*
X2377761Y1736229D01*
X2377782Y1736204D01*
X2377806Y1736186D01*
X2377832Y1736175D01*
X2377859Y1736171D01*
G01X2377721Y1733218D02*
X2377723Y1733180D01*
X2377731Y1733143D01*
X2377744Y1733109D01*
X2377761Y1733079D01*
X2377782Y1733055D01*
X2377806Y1733037D01*
X2377832Y1733025D01*
X2377859Y1733022D01*
G01X2377721Y1730069D02*
X2377723Y1730031D01*
X2377731Y1729994D01*
X2377744Y1729960D01*
X2377761Y1729930D01*
X2377782Y1729905D01*
X2377806Y1729887D01*
X2377832Y1729876D01*
X2377859Y1729872D01*
G01X2377721Y1726919D02*
X2377723Y1726881D01*
X2377731Y1726844D01*
X2377744Y1726810D01*
X2377761Y1726780D01*
X2377782Y1726756D01*
X2377806Y1726737D01*
X2377832Y1726726D01*
X2377859Y1726722D01*
G01X2382917Y1743752D02*
X2383044Y1743779D01*
X2383133Y1743852D01*
X2383165Y1743949D01*
G01X2382917Y1740602D02*
X2383044Y1740630D01*
X2383133Y1740703D01*
X2383165Y1740799D01*
G01X2382917Y1737453D02*
X2383044Y1737480D01*
X2383133Y1737553D01*
X2383165Y1737650D01*
G01X2382917Y1734303D02*
X2383044Y1734331D01*
X2383133Y1734403D01*
X2383165Y1734500D01*
G01X2382917Y1731154D02*
X2383044Y1731181D01*
X2383133Y1731254D01*
X2383165Y1731350D01*
G01X2382917Y1728004D02*
X2383044Y1728031D01*
X2383133Y1728104D01*
X2383165Y1728201D01*
G01X2382908Y1758218D02*
X2383035Y1758246D01*
X2383124Y1758319D01*
X2383155Y1758415D01*
G01X2382908Y1755069D02*
X2383035Y1755097D01*
X2383124Y1755169D01*
X2383155Y1755266D01*
G01X2382908Y1751919D02*
X2383035Y1751947D01*
X2383124Y1752020D01*
X2383155Y1752116D01*
G01X2382908Y1748770D02*
X2383035Y1748797D01*
X2383124Y1748870D01*
X2383155Y1748966D01*
G01X2382908Y1745620D02*
X2383035Y1745648D01*
X2383124Y1745721D01*
X2383155Y1745817D01*
G01X2382908Y1742470D02*
X2383035Y1742498D01*
X2383124Y1742571D01*
X2383155Y1742667D01*
G01X2382908Y1739321D02*
X2383035Y1739349D01*
X2383124Y1739421D01*
X2383155Y1739518D01*
G01X2382908Y1736171D02*
X2383035Y1736199D01*
X2383124Y1736272D01*
X2383155Y1736368D01*
G01X2382908Y1733022D02*
X2383035Y1733049D01*
X2383124Y1733122D01*
X2383155Y1733218D01*
G01X2382908Y1729872D02*
X2383035Y1729900D01*
X2383124Y1729973D01*
X2383155Y1730069D01*
G01X2382908Y1726722D02*
X2383035Y1726750D01*
X2383124Y1726823D01*
X2383155Y1726919D01*
G01X2378674Y1724262D02*
X2378752Y1724852D01*
G01X2378674Y1749262D02*
X2378752Y1749852D01*
G01X2380643Y1764262D02*
X2380720Y1764852D01*
G01X2378674Y1754262D02*
X2378752Y1754852D01*
G01X2378674Y1759262D02*
X2378752Y1759852D01*
G01X2378674Y1769262D02*
X2378752Y1769852D01*
G01X2378674Y1774262D02*
X2378752Y1774852D01*
G01X2378674Y1779262D02*
X2378752Y1779852D01*
G01X2378674Y1784262D02*
X2378752Y1784852D01*
G01X2378674Y1789262D02*
X2378752Y1789852D01*
G01X2378234Y1727313D02*
X2378244Y1727411D01*
X2378272Y1727483D01*
X2378310Y1727510D01*
G01X2378234Y1730463D02*
X2378244Y1730561D01*
X2378272Y1730633D01*
X2378310Y1730659D01*
G01X2378234Y1733612D02*
X2378244Y1733710D01*
X2378272Y1733783D01*
X2378310Y1733809D01*
G01X2378234Y1736762D02*
X2378244Y1736860D01*
X2378272Y1736932D01*
X2378310Y1736959D01*
G01X2378234Y1743061D02*
X2378244Y1743159D01*
X2378272Y1743231D01*
X2378310Y1743258D01*
G01X2378234Y1746211D02*
X2378244Y1746309D01*
X2378272Y1746381D01*
X2378310Y1746407D01*
G01X2378234Y1749360D02*
X2378244Y1749458D01*
X2378272Y1749531D01*
X2378310Y1749557D01*
G01X2378234Y1752510D02*
X2378244Y1752608D01*
X2378272Y1752680D01*
X2378310Y1752707D01*
G01X2378234Y1755659D02*
X2378244Y1755758D01*
X2378272Y1755830D01*
X2378310Y1755856D01*
G01X2378234Y1758809D02*
X2378244Y1758907D01*
X2378272Y1758979D01*
X2378310Y1759006D01*
G01X2378234Y1761959D02*
X2378244Y1762057D01*
X2378272Y1762129D01*
X2378310Y1762155D01*
G01X2378234Y1765108D02*
X2378244Y1765207D01*
X2378272Y1765279D01*
X2378310Y1765305D01*
G01X2378234Y1768258D02*
X2378244Y1768356D01*
X2378272Y1768428D01*
X2378310Y1768455D01*
G01X2378234Y1771407D02*
X2378244Y1771506D01*
X2378272Y1771578D01*
X2378310Y1771604D01*
G01X2378234Y1774557D02*
X2378244Y1774655D01*
X2378272Y1774727D01*
X2378310Y1774754D01*
G01X2378234Y1777707D02*
X2378244Y1777805D01*
X2378272Y1777877D01*
X2378310Y1777903D01*
G01X2378234Y1780856D02*
X2378244Y1780955D01*
X2378272Y1781027D01*
X2378310Y1781053D01*
G01X2378234Y1784006D02*
X2378244Y1784104D01*
X2378272Y1784176D01*
X2378310Y1784203D01*
G01X2378234Y1787155D02*
X2378244Y1787254D01*
X2378272Y1787326D01*
X2378310Y1787352D01*
G01X2378234Y1790305D02*
X2378244Y1790403D01*
X2378272Y1790475D01*
X2378310Y1790502D01*
G01X2378234Y1793455D02*
X2378244Y1793553D01*
X2378272Y1793625D01*
X2378310Y1793651D01*
G01X2377789Y1729185D02*
X2377792Y1729223D01*
X2377800Y1729260D01*
X2377814Y1729294D01*
X2377832Y1729324D01*
X2377855Y1729349D01*
X2377880Y1729367D01*
X2377908Y1729378D01*
X2377937Y1729382D01*
G01X2377789Y1732335D02*
X2377792Y1732373D01*
X2377800Y1732410D01*
X2377814Y1732444D01*
X2377832Y1732474D01*
X2377855Y1732498D01*
X2377880Y1732516D01*
X2377908Y1732528D01*
X2377937Y1732532D01*
G01X2377789Y1735484D02*
X2377792Y1735523D01*
X2377800Y1735559D01*
X2377814Y1735593D01*
X2377832Y1735624D01*
X2377855Y1735648D01*
X2377880Y1735666D01*
X2377908Y1735677D01*
X2377937Y1735681D01*
G01X2377789Y1738634D02*
X2377792Y1738672D01*
X2377800Y1738709D01*
X2377814Y1738743D01*
X2377832Y1738773D01*
X2377855Y1738798D01*
X2377880Y1738816D01*
X2377908Y1738827D01*
X2377937Y1738831D01*
G01X2377789Y1741784D02*
X2377792Y1741822D01*
X2377800Y1741859D01*
X2377814Y1741892D01*
X2377832Y1741923D01*
X2377855Y1741947D01*
X2377880Y1741965D01*
X2377908Y1741977D01*
X2377937Y1741980D01*
G01X2377789Y1744933D02*
X2377792Y1744971D01*
X2377800Y1745008D01*
X2377814Y1745042D01*
X2377832Y1745072D01*
X2377855Y1745097D01*
X2377880Y1745115D01*
X2377908Y1745126D01*
X2377937Y1745130D01*
G01X2377549Y1724262D02*
X2377822Y1724852D01*
G01X2377549Y1749262D02*
X2377822Y1749852D01*
G01X2377549Y1754262D02*
X2377822Y1754852D01*
G01X2377549Y1759262D02*
X2377822Y1759852D01*
G01X2383155Y1777313D02*
X2383122Y1777214D01*
X2383034Y1777143D01*
X2382908Y1777116D01*
G01X2379518Y1764262D02*
X2379791Y1764852D01*
G01X2377549Y1769262D02*
X2377822Y1769852D01*
G01X2377549Y1774262D02*
X2377822Y1774852D01*
G01X2377549Y1779262D02*
X2377822Y1779852D01*
G01X2377549Y1784262D02*
X2377822Y1784852D01*
G01X2377549Y1789262D02*
X2377822Y1789852D01*
G01X2377132Y1754852D02*
X2376706Y1754262D01*
G01X2377132Y1759852D02*
X2376706Y1759262D01*
G01X2379101Y1764852D02*
X2378674Y1764262D01*
G01X2377132Y1769852D02*
X2376706Y1769262D01*
G01X2377132Y1774852D02*
X2376706Y1774262D01*
G01X2377132Y1779852D02*
X2376706Y1779262D01*
G01X2377132Y1784852D02*
X2376706Y1784262D01*
G01X2377132Y1789852D02*
X2376706Y1789262D01*
G01X2377064Y1724852D02*
X2376640Y1724262D01*
G01X2377064Y1749852D02*
X2376640Y1749262D01*
G01X2382877Y1753277D02*
X2383017Y1753473D01*
X2383155Y1753670D01*
X2383292Y1753868D01*
G01X2382877Y1758277D02*
X2383017Y1758473D01*
X2383155Y1758670D01*
X2383292Y1758868D01*
G01X2384846Y1763277D02*
X2384985Y1763473D01*
X2385123Y1763670D01*
X2385260Y1763868D01*
G01X2382877Y1768277D02*
X2383017Y1768473D01*
X2383155Y1768670D01*
X2383292Y1768868D01*
G01X2382877Y1773277D02*
X2383017Y1773473D01*
X2383155Y1773670D01*
X2383292Y1773868D01*
G01X2382877Y1778277D02*
X2383017Y1778473D01*
X2383155Y1778670D01*
X2383292Y1778868D01*
G01X2382877Y1783277D02*
X2383017Y1783473D01*
X2383155Y1783670D01*
X2383292Y1783868D01*
G01X2382877Y1788277D02*
X2383017Y1788473D01*
X2383155Y1788670D01*
X2383292Y1788868D01*
G01X2382877Y1793277D02*
X2383017Y1793473D01*
X2383155Y1793670D01*
X2383292Y1793868D01*
G01X2382977Y1748277D02*
X2383113Y1748474D01*
X2383249Y1748670D01*
X2383383Y1748868D01*
G01X2387142Y1748297D02*
X2385173Y1746329D01*
G01X2378310Y1740108D02*
X2378272Y1740082D01*
X2378244Y1740010D01*
X2378234Y1739911D01*
G01X2383292Y1794262D02*
X2383155Y1794459D01*
X2383017Y1794656D01*
X2382877Y1794852D01*
G01X2378310Y1796014D02*
X2378272Y1796040D01*
X2378244Y1796112D01*
X2378234Y1796211D01*
G01X2383155Y1796604D02*
X2383123Y1796701D01*
X2383035Y1796773D01*
X2382908Y1796801D01*
G01D02*
X2376823D01*
G01X2376543Y1796604D02*
X2383155D01*
G01Y1796211D02*
X2376543D01*
G01X2382908Y1796014D02*
X2376823D01*
G01X2382877Y1794852D02*
X2377132D01*
G01X2376706Y1794262D02*
X2383292D01*
G01X2376706Y1793868D02*
X2383292D01*
G01X2377859Y1796801D02*
X2377832Y1796797D01*
X2377806Y1796786D01*
X2377782Y1796768D01*
X2377761Y1796743D01*
X2377744Y1796714D01*
X2377731Y1796680D01*
X2377723Y1796643D01*
X2377721Y1796604D01*
G01X2382908Y1796014D02*
X2383035Y1796041D01*
X2383124Y1796114D01*
X2383155Y1796211D01*
G01X2383292Y1794262D02*
Y1793868D01*
G01X2383155Y1796211D02*
Y1796604D01*
G01X2378674Y1794262D02*
Y1793868D01*
G01X2378234Y1796211D02*
Y1796604D01*
G01X2377721D02*
Y1796211D01*
G01X2377549Y1793868D02*
Y1794262D01*
G01X2376706Y1793868D02*
Y1794262D01*
G01X2376543Y1796604D02*
Y1796211D01*
G01X2377721D02*
X2377723Y1796172D01*
X2377731Y1796136D01*
X2377744Y1796102D01*
X2377761Y1796071D01*
X2377782Y1796047D01*
X2377806Y1796029D01*
X2377832Y1796018D01*
X2377859Y1796014D01*
G01X2378674Y1794262D02*
X2378752Y1794852D01*
G01X2378234Y1796604D02*
X2378244Y1796703D01*
X2378272Y1796775D01*
X2378310Y1796801D01*
G01X2377549Y1794262D02*
X2377822Y1794852D01*
G01X2377132D02*
X2376706Y1794262D01*
G01X2383292Y1819262D02*
X2383155Y1819459D01*
X2383017Y1819656D01*
X2382877Y1819852D01*
G01X2383292Y1814262D02*
X2383155Y1814459D01*
X2383017Y1814656D01*
X2382877Y1814852D01*
G01X2383292Y1809262D02*
X2383155Y1809459D01*
X2383017Y1809656D01*
X2382877Y1809852D01*
G01X2385260Y1804262D02*
X2385123Y1804459D01*
X2384985Y1804656D01*
X2384846Y1804852D01*
G01X2383292Y1799262D02*
X2383155Y1799459D01*
X2383017Y1799656D01*
X2382877Y1799852D01*
G01X2377132Y1818277D02*
X2376706Y1818868D01*
G01X2377132Y1813277D02*
X2376706Y1813868D01*
G01X2377132Y1808277D02*
X2376706Y1808868D01*
G01X2379101Y1803277D02*
X2378674Y1803868D01*
G01X2377132Y1798277D02*
X2376706Y1798868D01*
G01X2385173Y1827805D02*
X2387142Y1825837D01*
G01X2378310Y1818061D02*
X2378272Y1818087D01*
X2378244Y1818159D01*
X2378234Y1818258D01*
G01X2378310Y1814911D02*
X2378272Y1814938D01*
X2378244Y1815010D01*
X2378234Y1815108D01*
G01X2378310Y1811762D02*
X2378272Y1811788D01*
X2378244Y1811860D01*
X2378234Y1811959D01*
G01X2378310Y1808612D02*
X2378272Y1808639D01*
X2378244Y1808711D01*
X2378234Y1808809D01*
G01X2378310Y1805463D02*
X2378272Y1805489D01*
X2378244Y1805561D01*
X2378234Y1805659D01*
G01X2378310Y1802313D02*
X2378272Y1802339D01*
X2378244Y1802411D01*
X2378234Y1802510D01*
G01X2378310Y1799163D02*
X2378272Y1799190D01*
X2378244Y1799262D01*
X2378234Y1799360D01*
G01X2383155Y1818651D02*
X2383123Y1818748D01*
X2383035Y1818821D01*
X2382908Y1818848D01*
G01X2383155Y1815502D02*
X2383123Y1815599D01*
X2383035Y1815671D01*
X2382908Y1815699D01*
G01X2383155Y1812352D02*
X2383123Y1812449D01*
X2383035Y1812521D01*
X2382908Y1812549D01*
G01X2383155Y1809203D02*
X2383123Y1809300D01*
X2383035Y1809372D01*
X2382908Y1809400D01*
G01X2383155Y1802903D02*
X2383123Y1803000D01*
X2383035Y1803073D01*
X2382908Y1803100D01*
G01X2383155Y1799754D02*
X2383123Y1799851D01*
X2383035Y1799923D01*
X2382908Y1799951D01*
G01X2377822Y1818277D02*
X2377549Y1818868D01*
G01X2377822Y1813277D02*
X2377549Y1813868D01*
G01X2377822Y1808277D02*
X2377549Y1808868D01*
G01X2379791Y1803277D02*
X2379518Y1803868D01*
G01X2377822Y1798277D02*
X2377549Y1798868D01*
G01X2382908Y1806250D02*
X2383034Y1806223D01*
X2383124Y1806150D01*
X2383155Y1806053D01*
G01X2390425Y1827805D02*
X2387142D01*
G01X2382877Y1819852D02*
X2377132D01*
G01X2376706Y1819262D02*
X2383292D01*
G01X2376706Y1818868D02*
X2383292D01*
G01X2382908Y1818848D02*
X2376823D01*
G01X2376543Y1818651D02*
X2383155D01*
G01X2382877Y1818277D02*
X2377132D01*
G01X2383155Y1818258D02*
X2376543D01*
G01X2382908Y1818061D02*
X2376823D01*
G01X2382908Y1815699D02*
X2376823D01*
G01X2376543Y1815502D02*
X2383155D01*
G01Y1815108D02*
X2376543D01*
G01X2382908Y1814911D02*
X2376823D01*
G01X2382877Y1814852D02*
X2377132D01*
G01X2376706Y1814262D02*
X2383292D01*
G01X2376706Y1813868D02*
X2383292D01*
G01X2382877Y1813277D02*
X2377132D01*
G01X2378674Y1818868D02*
X2378752Y1818277D01*
G01X2380643Y1803868D02*
X2380720Y1803277D01*
G01X2378752Y1813277D02*
X2378674Y1813868D01*
G01Y1808868D02*
X2378752Y1808277D01*
G01X2378674Y1798868D02*
X2378752Y1798277D01*
G01X2382908Y1812549D02*
X2376823D01*
G01X2376543Y1812352D02*
X2383155D01*
G01Y1811959D02*
X2376543D01*
G01X2382908Y1811762D02*
X2376823D01*
G01X2382877Y1809852D02*
X2377132D01*
G01X2382908Y1809400D02*
X2376823D01*
G01X2376706Y1809262D02*
X2383292D01*
G01X2376543Y1809203D02*
X2383155D01*
G01X2376706Y1808868D02*
X2383292D01*
G01X2383155Y1808809D02*
X2376543D01*
G01X2382908Y1808612D02*
X2376823D01*
G01X2382877Y1808277D02*
X2377132D01*
G01X2382908Y1806250D02*
X2376823D01*
G01X2376543Y1806053D02*
X2383155D01*
G01Y1805659D02*
X2376543D01*
G01X2382908Y1805463D02*
X2376823D01*
G01X2384846Y1804852D02*
X2379101D01*
G01X2378674Y1804262D02*
X2385260D01*
G01X2378674Y1803868D02*
X2385260D01*
G01X2384846Y1803277D02*
X2379101D01*
G01X2382908Y1803100D02*
X2376823D01*
G01X2376543Y1802903D02*
X2383155D01*
G01Y1802510D02*
X2376543D01*
G01X2382908Y1802313D02*
X2376823D01*
G01X2382908Y1799951D02*
X2376823D01*
G01X2382877Y1799852D02*
X2377132D01*
G01X2376543Y1799754D02*
X2383155D01*
G01Y1799360D02*
X2376543D01*
G01X2376706Y1799262D02*
X2383292D01*
G01X2382908Y1799163D02*
X2376823D01*
G01X2376706Y1798868D02*
X2383292D01*
G01X2382877Y1798277D02*
X2377132D01*
G01X2377859Y1818848D02*
X2377832Y1818845D01*
X2377806Y1818833D01*
X2377782Y1818815D01*
X2377761Y1818791D01*
X2377744Y1818761D01*
X2377731Y1818727D01*
X2377723Y1818690D01*
X2377721Y1818651D01*
G01X2377859Y1815699D02*
X2377832Y1815695D01*
X2377806Y1815684D01*
X2377782Y1815666D01*
X2377761Y1815641D01*
X2377744Y1815611D01*
X2377731Y1815578D01*
X2377723Y1815541D01*
X2377721Y1815502D01*
G01X2377859Y1812549D02*
X2377832Y1812545D01*
X2377806Y1812534D01*
X2377782Y1812516D01*
X2377761Y1812491D01*
X2377744Y1812462D01*
X2377731Y1812428D01*
X2377723Y1812391D01*
X2377721Y1812352D01*
G01X2377859Y1809400D02*
X2377832Y1809396D01*
X2377806Y1809385D01*
X2377782Y1809367D01*
X2377761Y1809342D01*
X2377744Y1809312D01*
X2377731Y1809278D01*
X2377723Y1809242D01*
X2377721Y1809203D01*
G01X2377859Y1806250D02*
X2377832Y1806246D01*
X2377806Y1806235D01*
X2377782Y1806217D01*
X2377761Y1806192D01*
X2377744Y1806163D01*
X2377731Y1806129D01*
X2377723Y1806092D01*
X2377721Y1806053D01*
G01X2377859Y1803100D02*
X2377832Y1803097D01*
X2377806Y1803085D01*
X2377782Y1803067D01*
X2377761Y1803043D01*
X2377744Y1803013D01*
X2377731Y1802979D01*
X2377723Y1802942D01*
X2377721Y1802903D01*
G01X2377859Y1799951D02*
X2377832Y1799947D01*
X2377806Y1799936D01*
X2377782Y1799918D01*
X2377761Y1799893D01*
X2377744Y1799863D01*
X2377731Y1799829D01*
X2377723Y1799793D01*
X2377721Y1799754D01*
G01X2382908Y1818061D02*
X2383035Y1818089D01*
X2383124Y1818162D01*
X2383155Y1818258D01*
G01X2382908Y1814911D02*
X2383035Y1814939D01*
X2383124Y1815012D01*
X2383155Y1815108D01*
G01X2382908Y1811762D02*
X2383035Y1811789D01*
X2383124Y1811862D01*
X2383155Y1811959D01*
G01X2382908Y1808612D02*
X2383035Y1808640D01*
X2383124Y1808713D01*
X2383155Y1808809D01*
G01X2382908Y1802313D02*
X2383035Y1802341D01*
X2383124Y1802414D01*
X2383155Y1802510D01*
G01X2382908Y1799163D02*
X2383035Y1799191D01*
X2383124Y1799264D01*
X2383155Y1799360D01*
G01X2385260Y1804262D02*
Y1803868D01*
G01X2383292Y1799262D02*
Y1798868D01*
G01Y1809262D02*
Y1808868D01*
G01Y1814262D02*
Y1813868D01*
G01Y1819262D02*
Y1818868D01*
G01X2383155Y1815108D02*
Y1815502D01*
G01Y1818258D02*
Y1818651D01*
G01Y1811959D02*
Y1812352D01*
G01Y1808809D02*
Y1809203D01*
G01Y1805659D02*
Y1806053D01*
G01Y1802510D02*
Y1802903D01*
G01Y1799360D02*
Y1799754D01*
G01X2380643Y1804262D02*
Y1803868D01*
G01X2379518D02*
Y1804262D01*
G01X2378674Y1803868D02*
Y1804262D01*
G01Y1813868D02*
Y1814262D01*
G01Y1799262D02*
Y1798868D01*
G01Y1809262D02*
Y1808868D01*
G01Y1819262D02*
Y1818868D01*
G01X2378234Y1815108D02*
Y1815502D01*
G01Y1818258D02*
Y1818651D01*
G01Y1811959D02*
Y1812352D01*
G01Y1808809D02*
Y1809203D01*
G01Y1805659D02*
Y1806053D01*
G01Y1802510D02*
Y1802903D01*
G01Y1799360D02*
Y1799754D01*
G01X2377721D02*
Y1799360D01*
G01Y1802903D02*
Y1802510D01*
G01Y1809203D02*
Y1808809D01*
G01Y1806053D02*
Y1805659D01*
G01Y1812352D02*
Y1811959D01*
G01Y1815502D02*
Y1815108D01*
G01Y1818651D02*
Y1818258D01*
G01X2377549Y1818868D02*
Y1819262D01*
G01Y1813868D02*
Y1814262D01*
G01Y1808868D02*
Y1809262D01*
G01Y1798868D02*
Y1799262D01*
G01X2376706Y1818868D02*
Y1819262D01*
G01Y1813868D02*
Y1814262D01*
G01Y1808868D02*
Y1809262D01*
G01Y1798868D02*
Y1799262D01*
G01X2376543Y1799754D02*
Y1799360D01*
G01Y1802903D02*
Y1802510D01*
G01Y1809203D02*
Y1808809D01*
G01Y1806053D02*
Y1805659D01*
G01Y1812352D02*
Y1811959D01*
G01Y1815502D02*
Y1815108D01*
G01Y1818651D02*
Y1818258D01*
G01X2377721D02*
X2377723Y1818220D01*
X2377731Y1818183D01*
X2377744Y1818149D01*
X2377761Y1818119D01*
X2377782Y1818094D01*
X2377806Y1818076D01*
X2377832Y1818065D01*
X2377859Y1818061D01*
G01X2377721Y1815108D02*
X2377723Y1815070D01*
X2377731Y1815033D01*
X2377744Y1814999D01*
X2377761Y1814969D01*
X2377782Y1814945D01*
X2377806Y1814926D01*
X2377832Y1814915D01*
X2377859Y1814911D01*
G01X2377721Y1811959D02*
X2377723Y1811920D01*
X2377731Y1811884D01*
X2377744Y1811850D01*
X2377761Y1811819D01*
X2377782Y1811795D01*
X2377806Y1811777D01*
X2377832Y1811766D01*
X2377859Y1811762D01*
G01X2377721Y1808809D02*
X2377723Y1808771D01*
X2377731Y1808734D01*
X2377744Y1808700D01*
X2377761Y1808670D01*
X2377782Y1808645D01*
X2377806Y1808627D01*
X2377832Y1808616D01*
X2377859Y1808612D01*
G01X2377721Y1805659D02*
X2377723Y1805621D01*
X2377731Y1805584D01*
X2377744Y1805550D01*
X2377761Y1805520D01*
X2377782Y1805496D01*
X2377806Y1805478D01*
X2377832Y1805466D01*
X2377859Y1805463D01*
G01X2377721Y1802510D02*
X2377723Y1802472D01*
X2377731Y1802435D01*
X2377744Y1802401D01*
X2377761Y1802371D01*
X2377782Y1802346D01*
X2377806Y1802328D01*
X2377832Y1802317D01*
X2377859Y1802313D01*
G01X2377721Y1799360D02*
X2377723Y1799322D01*
X2377731Y1799285D01*
X2377744Y1799251D01*
X2377761Y1799221D01*
X2377782Y1799197D01*
X2377806Y1799178D01*
X2377832Y1799167D01*
X2377859Y1799163D01*
G01X2380643Y1804262D02*
X2380720Y1804852D01*
G01X2378674Y1799262D02*
X2378752Y1799852D01*
G01X2378674Y1809262D02*
X2378752Y1809852D01*
G01Y1814852D02*
X2378674Y1814262D01*
G01Y1819262D02*
X2378752Y1819852D01*
G01X2378234Y1799754D02*
X2378244Y1799852D01*
X2378272Y1799924D01*
X2378310Y1799951D01*
G01X2378234Y1802903D02*
X2378244Y1803002D01*
X2378272Y1803074D01*
X2378310Y1803100D01*
G01X2378234Y1806053D02*
X2378244Y1806151D01*
X2378272Y1806223D01*
X2378310Y1806250D01*
G01X2378234Y1809203D02*
X2378244Y1809301D01*
X2378272Y1809373D01*
X2378310Y1809400D01*
G01X2378234Y1812352D02*
X2378244Y1812451D01*
X2378272Y1812523D01*
X2378310Y1812549D01*
G01X2378234Y1815502D02*
X2378244Y1815600D01*
X2378272Y1815672D01*
X2378310Y1815699D01*
G01X2378234Y1818651D02*
X2378244Y1818750D01*
X2378272Y1818822D01*
X2378310Y1818848D01*
G01X2383155Y1805659D02*
X2383122Y1805560D01*
X2383034Y1805489D01*
X2382908Y1805463D01*
G01X2377549Y1799262D02*
X2377822Y1799852D01*
G01X2379518Y1804262D02*
X2379791Y1804852D01*
G01X2377549Y1809262D02*
X2377822Y1809852D01*
G01X2377549Y1814262D02*
X2377822Y1814852D01*
G01X2377549Y1819262D02*
X2377822Y1819852D01*
G01X2377132Y1799852D02*
X2376706Y1799262D01*
G01X2379101Y1804852D02*
X2378674Y1804262D01*
G01X2377132Y1809852D02*
X2376706Y1809262D01*
G01X2382877Y1798277D02*
X2383017Y1798473D01*
X2383155Y1798670D01*
X2383292Y1798868D01*
G01X2384846Y1803277D02*
X2384985Y1803473D01*
X2385123Y1803670D01*
X2385260Y1803868D01*
G01X2382877Y1808277D02*
X2383017Y1808473D01*
X2383155Y1808670D01*
X2383292Y1808868D01*
G01X2382877Y1813277D02*
X2383017Y1813473D01*
X2383155Y1813670D01*
X2383292Y1813868D01*
G01X2382877Y1818277D02*
X2383017Y1818473D01*
X2383155Y1818670D01*
X2383292Y1818868D01*
G01X2377132Y1814852D02*
X2376706Y1814262D01*
G01X2377132Y1819852D02*
X2376706Y1819262D01*
G01X2385173Y1822884D02*
X2387142Y1824852D01*
G01X2393835Y1831506D02*
X2389110Y1836151D01*
G01X2389114Y1835044D02*
X2393835Y1830403D01*
G01X2389142Y1836120D02*
X2389199Y1835980D01*
X2389204Y1835741D01*
G01X2393835Y1829774D02*
Y1831506D01*
G01X2389110Y1827805D02*
Y1834970D01*
G01X2389168Y1835421D02*
X2389114Y1835044D01*
G01X2389168Y1835420D02*
X2389205Y1835743D01*
X2389199Y1835984D01*
X2389142Y1836120D01*
G01X2390425Y1827805D02*
X2393835Y1829774D01*
G01X2387572Y1982287D02*
X2388547D01*
G01X2381726Y1977234D02*
Y1985896D01*
X2378315Y1979399D01*
X2382700D01*
G01X2389521Y1977956D02*
X2388547Y1977234D01*
X2387572D01*
X2386598Y1977956D01*
X2386111Y1978678D01*
G01X2386598Y1985174D02*
X2387572Y1985896D01*
X2388547D01*
X2389521Y1985174D01*
X2390008Y1984452D01*
Y1983730D01*
X2389521Y1983009D01*
X2388547Y1982287D01*
X2389521Y1981565D01*
X2390008Y1980843D01*
X2390495Y1980121D01*
Y1979399D01*
X2389521Y1977956D01*
G01X2403650Y1977234D02*
X2403163D01*
Y1977956D01*
X2403650Y1977234D01*
G01X2411445Y1985896D02*
Y1977234D01*
G01X2419241D02*
X2419728Y1980843D01*
X2420215Y1983009D01*
X2420702Y1984452D01*
X2421189Y1985896D01*
X2417292D01*
G01X2393906Y1984452D02*
X2394393Y1985174D01*
X2395367Y1985896D01*
X2396342D01*
X2397316Y1985174D01*
X2397804Y1984452D01*
Y1983009D01*
X2397316Y1982287D01*
G01D02*
X2395367Y1980843D01*
X2394393Y1979399D01*
X2393906Y1977234D01*
X2397804D01*
G01X2385822Y2016604D02*
Y2025266D01*
X2382411Y2018770D01*
X2386796D01*
G01X2378027Y2016604D02*
Y2025266D01*
X2374616Y2018770D01*
X2379001D01*
G01X2399951Y2016604D02*
X2399464D01*
Y2017326D01*
X2399951Y2016604D01*
G01X2389169Y2083212D02*
X2389114Y2083598D01*
G01X2407746Y2025266D02*
Y2016604D01*
G01X2389110Y2083671D02*
Y2090837D01*
G01X2415541Y2016604D02*
X2416029Y2020213D01*
X2416516Y2022378D01*
G01D02*
X2417490Y2025266D01*
X2413593D01*
G01X2389142Y2082521D02*
X2389198Y2082656D01*
X2389205Y2082891D01*
X2389168Y2083220D01*
G01X2389142Y2082521D02*
X2389199Y2082661D01*
X2389204Y2082901D01*
G01X2391668Y2020213D02*
X2390694Y2018770D01*
X2390207Y2016604D01*
X2394104D01*
G01X2390207Y2023822D02*
X2390694Y2024544D01*
X2391668Y2025266D01*
X2392643D01*
X2393617Y2024544D01*
X2394104Y2023822D01*
Y2022378D01*
X2393617Y2021657D01*
X2391668Y2020213D01*
G01X2393835Y2087136D02*
X2389110Y2082490D01*
G01X2393835Y2088239D02*
X2389114Y2083598D01*
G01X2378310Y2157431D02*
X2378272Y2157457D01*
X2378244Y2157529D01*
X2378234Y2157628D01*
G01X2378310Y2154281D02*
X2378272Y2154308D01*
X2378244Y2154380D01*
X2378234Y2154478D01*
G01X2378310Y2151132D02*
X2378272Y2151158D01*
X2378244Y2151230D01*
X2378234Y2151329D01*
G01X2378310Y2147982D02*
X2378272Y2148009D01*
X2378244Y2148081D01*
X2378234Y2148179D01*
G01X2378310Y2144833D02*
X2378272Y2144859D01*
X2378244Y2144931D01*
X2378234Y2145029D01*
G01X2378310Y2141683D02*
X2378272Y2141709D01*
X2378244Y2141781D01*
X2378234Y2141880D01*
G01X2378310Y2138533D02*
X2378272Y2138560D01*
X2378244Y2138632D01*
X2378234Y2138730D01*
G01X2378310Y2135384D02*
X2378272Y2135410D01*
X2378244Y2135482D01*
X2378234Y2135581D01*
G01X2378310Y2132234D02*
X2378272Y2132261D01*
X2378244Y2132333D01*
X2378234Y2132431D01*
G01X2378310Y2129085D02*
X2378272Y2129111D01*
X2378244Y2129183D01*
X2378234Y2129281D01*
G01X2378310Y2125935D02*
X2378272Y2125961D01*
X2378244Y2126033D01*
X2378234Y2126132D01*
G01X2378310Y2122785D02*
X2378272Y2122812D01*
X2378244Y2122884D01*
X2378234Y2122982D01*
G01X2378310Y2119636D02*
X2378272Y2119662D01*
X2378244Y2119734D01*
X2378234Y2119833D01*
G01X2378310Y2116486D02*
X2378272Y2116513D01*
X2378244Y2116585D01*
X2378234Y2116683D01*
G01X2378974Y2149264D02*
X2378967Y2149268D01*
X2378961Y2149279D01*
X2378956Y2149297D01*
X2378951Y2149322D01*
X2378947Y2149351D01*
X2378944Y2149385D01*
X2378942Y2149422D01*
X2378941Y2149461D01*
G01X2378974Y2146114D02*
X2378967Y2146118D01*
X2378961Y2146129D01*
X2378956Y2146147D01*
X2378951Y2146172D01*
X2378947Y2146202D01*
X2378944Y2146235D01*
X2378942Y2146272D01*
X2378941Y2146311D01*
G01X2378974Y2142965D02*
X2378967Y2142968D01*
X2378961Y2142980D01*
X2378956Y2142998D01*
X2378951Y2143022D01*
X2378947Y2143052D01*
X2378944Y2143086D01*
X2378942Y2143123D01*
X2378941Y2143162D01*
G01X2378974Y2139815D02*
X2378967Y2139819D01*
X2378961Y2139830D01*
X2378956Y2139848D01*
X2378951Y2139873D01*
X2378947Y2139902D01*
X2378944Y2139936D01*
X2378942Y2139973D01*
X2378941Y2140012D01*
G01X2378974Y2136665D02*
X2378967Y2136669D01*
X2378961Y2136680D01*
X2378956Y2136698D01*
X2378951Y2136723D01*
X2378947Y2136753D01*
X2378944Y2136787D01*
X2378942Y2136823D01*
X2378941Y2136862D01*
G01X2378974Y2133516D02*
X2378967Y2133520D01*
X2378961Y2133531D01*
X2378956Y2133549D01*
X2378951Y2133573D01*
X2378947Y2133603D01*
X2378944Y2133637D01*
X2378942Y2133674D01*
X2378941Y2133713D01*
G01X2385173Y2132313D02*
X2387142Y2130344D01*
G01Y2093789D02*
X2385173Y2095758D01*
G01X2378310Y2113337D02*
X2378272Y2113363D01*
X2378244Y2113435D01*
X2378234Y2113533D01*
G01X2378310Y2110187D02*
X2378272Y2110213D01*
X2378244Y2110285D01*
X2378234Y2110384D01*
G01X2378310Y2107037D02*
X2378272Y2107064D01*
X2378244Y2107136D01*
X2378234Y2107234D01*
G01X2378310Y2103888D02*
X2378272Y2103914D01*
X2378244Y2103986D01*
X2378234Y2104085D01*
G01X2378310Y2100738D02*
X2378272Y2100765D01*
X2378244Y2100837D01*
X2378234Y2100935D01*
G01X2377937Y2149264D02*
X2377908Y2149268D01*
X2377881Y2149279D01*
X2377855Y2149297D01*
X2377832Y2149322D01*
X2377814Y2149351D01*
X2377800Y2149385D01*
X2377792Y2149422D01*
X2377789Y2149461D01*
G01X2377937Y2146114D02*
X2377908Y2146118D01*
X2377881Y2146129D01*
X2377855Y2146147D01*
X2377832Y2146172D01*
X2377814Y2146202D01*
X2377800Y2146235D01*
X2377792Y2146272D01*
X2377789Y2146311D01*
G01X2377937Y2142965D02*
X2377908Y2142968D01*
X2377881Y2142980D01*
X2377855Y2142998D01*
X2377832Y2143022D01*
X2377814Y2143052D01*
X2377800Y2143086D01*
X2377792Y2143123D01*
X2377789Y2143162D01*
G01X2377937Y2139815D02*
X2377908Y2139819D01*
X2377881Y2139830D01*
X2377855Y2139848D01*
X2377832Y2139873D01*
X2377814Y2139902D01*
X2377800Y2139936D01*
X2377792Y2139973D01*
X2377789Y2140012D01*
G01X2377937Y2136665D02*
X2377908Y2136669D01*
X2377881Y2136680D01*
X2377855Y2136698D01*
X2377832Y2136723D01*
X2377814Y2136753D01*
X2377800Y2136787D01*
X2377792Y2136823D01*
X2377789Y2136862D01*
G01X2377937Y2133516D02*
X2377908Y2133520D01*
X2377881Y2133531D01*
X2377855Y2133549D01*
X2377832Y2133573D01*
X2377814Y2133603D01*
X2377800Y2133637D01*
X2377792Y2133674D01*
X2377789Y2133713D01*
G01X2382908Y2157431D02*
X2376823D01*
G01X2382977Y2155364D02*
X2377064D01*
G01X2382908Y2155069D02*
X2376823D01*
G01X2376543Y2154872D02*
X2383155D01*
G01X2376640Y2154774D02*
X2383383D01*
G01X2383155Y2154478D02*
X2376543D01*
G01X2376640Y2154380D02*
X2383383D01*
G01X2382908Y2154281D02*
X2376823D01*
G01X2382977Y2153789D02*
X2377064D01*
G01X2380673Y2153002D02*
X2387142D01*
G01X2382908Y2151919D02*
X2376823D01*
G01X2376543Y2151722D02*
X2383155D01*
G01Y2151329D02*
X2376543D01*
G01X2382908Y2151132D02*
X2376823D01*
G01X2377109Y2150642D02*
X2382917D01*
G01X2383165Y2150445D02*
X2376847D01*
G01Y2149461D02*
X2383165D01*
G01X2377109Y2149264D02*
X2382917D01*
G01X2382908Y2148770D02*
X2376823D01*
G01X2376543Y2148573D02*
X2383155D01*
G01Y2148179D02*
X2376543D01*
G01X2382908Y2147982D02*
X2376823D01*
G01X2377109Y2147492D02*
X2382917D01*
G01X2383165Y2147295D02*
X2376847D01*
G01Y2146311D02*
X2383165D01*
G01X2377109Y2146114D02*
X2382917D01*
G01X2382908Y2145620D02*
X2376823D01*
G01X2376543Y2145423D02*
X2383155D01*
G01Y2145029D02*
X2376543D01*
G01X2382908Y2144833D02*
X2376823D01*
G01X2377109Y2144343D02*
X2382917D01*
G01X2383165Y2144146D02*
X2376847D01*
G01Y2143162D02*
X2383165D01*
G01X2377109Y2142965D02*
X2382917D01*
G01X2382908Y2142470D02*
X2376823D01*
G01X2376543Y2142274D02*
X2383155D01*
G01Y2141880D02*
X2376543D01*
G01X2382908Y2141683D02*
X2376823D01*
G01X2377109Y2141193D02*
X2382917D01*
G01X2383165Y2140996D02*
X2376847D01*
G01Y2140012D02*
X2383165D01*
G01X2377109Y2139815D02*
X2382917D01*
G01X2382908Y2139321D02*
X2376823D01*
G01X2376543Y2139124D02*
X2383155D01*
G01Y2138730D02*
X2376543D01*
G01X2382908Y2138533D02*
X2376823D01*
G01X2377109Y2138043D02*
X2382917D01*
G01X2383165Y2137847D02*
X2376847D01*
G01Y2136862D02*
X2383165D01*
G01X2377109Y2136665D02*
X2382917D01*
G01X2382908Y2136171D02*
X2376823D01*
G01X2376543Y2135974D02*
X2383155D01*
G01Y2135581D02*
X2376543D01*
G01X2382908Y2135384D02*
X2376823D01*
G01X2377109Y2134894D02*
X2382917D01*
G01X2383165Y2134697D02*
X2376847D01*
G01Y2133713D02*
X2383165D01*
G01X2377109Y2133516D02*
X2382917D01*
G01X2382908Y2133022D02*
X2376823D01*
G01X2376543Y2132825D02*
X2383155D01*
G01Y2132431D02*
X2376543D01*
G01X2382908Y2132234D02*
X2376823D01*
G01X2387142Y2131151D02*
X2380673D01*
G01X2382977Y2130364D02*
X2377064D01*
G01X2382908Y2129872D02*
X2376823D01*
G01X2376640Y2129774D02*
X2383383D01*
G01X2376543Y2129675D02*
X2383155D01*
G01X2376640Y2129380D02*
X2383383D01*
G01X2383155Y2129281D02*
X2376543D01*
G01X2382908Y2129085D02*
X2376823D01*
G01X2382977Y2128789D02*
X2377064D01*
G01X2382908Y2126722D02*
X2376823D01*
G01X2376543Y2126525D02*
X2383155D01*
G01Y2126132D02*
X2376543D01*
G01X2382908Y2125935D02*
X2376823D01*
G01X2382877Y2125364D02*
X2377132D01*
G01X2376706Y2124774D02*
X2383292D01*
G01X2376706Y2124380D02*
X2383292D01*
G01X2382877Y2123789D02*
X2377132D01*
G01X2382908Y2123573D02*
X2376823D01*
G01X2376543Y2123376D02*
X2383155D01*
G01Y2122982D02*
X2376543D01*
G01X2382908Y2122785D02*
X2376823D01*
G01X2383383Y2154774D02*
X2383249Y2154971D01*
X2383113Y2155168D01*
X2382977Y2155364D01*
G01X2383383Y2129774D02*
X2383249Y2129971D01*
X2383113Y2130168D01*
X2382977Y2130364D01*
G01X2383292Y2124774D02*
X2383155Y2124971D01*
X2383017Y2125168D01*
X2382877Y2125364D01*
G01X2383292Y2119774D02*
X2383155Y2119971D01*
X2383017Y2120168D01*
X2382877Y2120364D01*
G01X2383292Y2114774D02*
X2383155Y2114971D01*
X2383017Y2115168D01*
X2382877Y2115364D01*
G01X2383292Y2109774D02*
X2383155Y2109971D01*
X2383017Y2110168D01*
X2382877Y2110364D01*
G01X2383292Y2104774D02*
X2383155Y2104971D01*
X2383017Y2105168D01*
X2382877Y2105364D01*
G01X2383292Y2099774D02*
X2383155Y2099971D01*
X2383017Y2100168D01*
X2382877Y2100364D01*
G01X2377064Y2153789D02*
X2376640Y2154380D01*
G01X2377064Y2128789D02*
X2376640Y2129380D01*
G01X2377132Y2123789D02*
X2376706Y2124380D01*
G01X2377132Y2118789D02*
X2376706Y2119380D01*
G01X2377132Y2113789D02*
X2376706Y2114380D01*
G01X2377132Y2108789D02*
X2376706Y2109380D01*
G01X2377132Y2103789D02*
X2376706Y2104380D01*
G01X2377132Y2098789D02*
X2376706Y2099380D01*
G01X2382908Y2120423D02*
X2376823D01*
G01X2382877Y2120364D02*
X2377132D01*
G01X2376543Y2120226D02*
X2383155D01*
G01Y2119833D02*
X2376543D01*
G01X2376706Y2119774D02*
X2383292D01*
G01X2382908Y2119636D02*
X2376823D01*
G01X2376706Y2119380D02*
X2383292D01*
G01X2382877Y2118789D02*
X2377132D01*
G01X2382908Y2117274D02*
X2376823D01*
G01X2376543Y2117077D02*
X2383155D01*
G01Y2116683D02*
X2376543D01*
G01X2382908Y2116486D02*
X2376823D01*
G01X2382877Y2115364D02*
X2377132D01*
G01X2376706Y2114774D02*
X2383292D01*
G01X2376706Y2114380D02*
X2383292D01*
G01X2382908Y2114124D02*
X2376823D01*
G01X2376543Y2113927D02*
X2383155D01*
G01X2382877Y2113789D02*
X2377132D01*
G01X2383155Y2113533D02*
X2376543D01*
G01X2382908Y2113337D02*
X2376823D01*
G01X2382908Y2110974D02*
X2376823D01*
G01X2376543Y2110777D02*
X2383155D01*
G01Y2110384D02*
X2376543D01*
G01X2382877Y2110364D02*
X2377132D01*
G01X2382908Y2110187D02*
X2376823D01*
G01X2376706Y2109774D02*
X2383292D01*
G01X2376706Y2109380D02*
X2383292D01*
G01X2382877Y2108789D02*
X2377132D01*
G01X2382908Y2107825D02*
X2376823D01*
G01X2376543Y2107628D02*
X2383155D01*
G01Y2107234D02*
X2376543D01*
G01X2382908Y2107037D02*
X2376823D01*
G01X2382877Y2105364D02*
X2377132D01*
G01X2376706Y2104774D02*
X2383292D01*
G01X2382908Y2104675D02*
X2376823D01*
G01X2376543Y2104478D02*
X2383155D01*
G01X2376706Y2104380D02*
X2383292D01*
G01X2383155Y2104085D02*
X2376543D01*
G01X2382908Y2103888D02*
X2376823D01*
G01X2382877Y2103789D02*
X2377132D01*
G01X2382908Y2101525D02*
X2376823D01*
G01X2376543Y2101329D02*
X2383155D01*
G01Y2100935D02*
X2376543D01*
G01X2382908Y2100738D02*
X2376823D01*
G01X2382877Y2100364D02*
X2377132D01*
G01X2376706Y2099774D02*
X2383292D01*
G01X2376706Y2099380D02*
X2383292D01*
G01X2382877Y2098789D02*
X2377132D01*
G01X2390425Y2090837D02*
X2387142D01*
G01X2377859Y2155069D02*
X2377832Y2155065D01*
X2377806Y2155054D01*
X2377782Y2155036D01*
X2377761Y2155011D01*
X2377744Y2154981D01*
X2377731Y2154948D01*
X2377723Y2154911D01*
X2377721Y2154872D01*
G01X2377859Y2151919D02*
X2377832Y2151915D01*
X2377806Y2151904D01*
X2377782Y2151886D01*
X2377761Y2151862D01*
X2377744Y2151832D01*
X2377731Y2151798D01*
X2377723Y2151761D01*
X2377721Y2151722D01*
G01X2377859Y2148770D02*
X2377832Y2148766D01*
X2377806Y2148755D01*
X2377782Y2148737D01*
X2377761Y2148712D01*
X2377744Y2148682D01*
X2377731Y2148648D01*
X2377723Y2148612D01*
X2377721Y2148573D01*
G01X2377859Y2145620D02*
X2377832Y2145616D01*
X2377806Y2145605D01*
X2377782Y2145587D01*
X2377761Y2145562D01*
X2377744Y2145533D01*
X2377731Y2145499D01*
X2377723Y2145462D01*
X2377721Y2145423D01*
G01X2377859Y2142470D02*
X2377832Y2142467D01*
X2377806Y2142456D01*
X2377782Y2142437D01*
X2377761Y2142413D01*
X2377744Y2142383D01*
X2377731Y2142349D01*
X2377723Y2142312D01*
X2377721Y2142274D01*
G01X2377859Y2139321D02*
X2377832Y2139317D01*
X2377806Y2139306D01*
X2377782Y2139288D01*
X2377761Y2139263D01*
X2377744Y2139233D01*
X2377731Y2139200D01*
X2377723Y2139163D01*
X2377721Y2139124D01*
G01X2377859Y2136171D02*
X2377832Y2136167D01*
X2377806Y2136156D01*
X2377782Y2136138D01*
X2377761Y2136114D01*
X2377744Y2136084D01*
X2377731Y2136050D01*
X2377723Y2136013D01*
X2377721Y2135974D01*
G01X2377859Y2133022D02*
X2377832Y2133018D01*
X2377806Y2133007D01*
X2377782Y2132989D01*
X2377761Y2132964D01*
X2377744Y2132934D01*
X2377731Y2132900D01*
X2377723Y2132864D01*
X2377721Y2132825D01*
G01X2377859Y2129872D02*
X2377832Y2129868D01*
X2377806Y2129857D01*
X2377782Y2129839D01*
X2377761Y2129814D01*
X2377744Y2129785D01*
X2377731Y2129751D01*
X2377723Y2129714D01*
X2377721Y2129675D01*
G01X2377859Y2126722D02*
X2377832Y2126719D01*
X2377806Y2126707D01*
X2377782Y2126689D01*
X2377761Y2126665D01*
X2377744Y2126635D01*
X2377731Y2126601D01*
X2377723Y2126564D01*
X2377721Y2126525D01*
G01X2377859Y2123573D02*
X2377832Y2123569D01*
X2377806Y2123558D01*
X2377782Y2123540D01*
X2377761Y2123515D01*
X2377744Y2123485D01*
X2377731Y2123452D01*
X2377723Y2123415D01*
X2377721Y2123376D01*
G01X2377859Y2120423D02*
X2377832Y2120419D01*
X2377806Y2120408D01*
X2377782Y2120390D01*
X2377761Y2120365D01*
X2377744Y2120336D01*
X2377731Y2120302D01*
X2377723Y2120265D01*
X2377721Y2120226D01*
G01X2377859Y2117274D02*
X2377832Y2117270D01*
X2377806Y2117259D01*
X2377782Y2117241D01*
X2377761Y2117216D01*
X2377744Y2117186D01*
X2377731Y2117152D01*
X2377723Y2117116D01*
X2377721Y2117077D01*
G01X2377859Y2114124D02*
X2377832Y2114120D01*
X2377806Y2114109D01*
X2377782Y2114091D01*
X2377761Y2114066D01*
X2377744Y2114037D01*
X2377731Y2114003D01*
X2377723Y2113966D01*
X2377721Y2113927D01*
G01X2377859Y2110974D02*
X2377832Y2110971D01*
X2377806Y2110959D01*
X2377782Y2110941D01*
X2377761Y2110917D01*
X2377744Y2110887D01*
X2377731Y2110853D01*
X2377723Y2110816D01*
X2377721Y2110777D01*
G01X2382908Y2157431D02*
X2383035Y2157459D01*
X2383124Y2157532D01*
X2383155Y2157628D01*
G01X2382908Y2154281D02*
X2383035Y2154309D01*
X2383124Y2154382D01*
X2383155Y2154478D01*
G01X2377822Y2153789D02*
X2377549Y2154380D01*
G01X2377822Y2128789D02*
X2377549Y2129380D01*
G01X2377822Y2123789D02*
X2377549Y2124380D01*
G01X2377822Y2118789D02*
X2377549Y2119380D01*
G01X2377822Y2113789D02*
X2377549Y2114380D01*
G01X2377822Y2108789D02*
X2377549Y2109380D01*
G01X2377822Y2103789D02*
X2377549Y2104380D01*
G01X2377822Y2098789D02*
X2377549Y2099380D01*
G01X2377859Y2107825D02*
X2377832Y2107821D01*
X2377806Y2107810D01*
X2377782Y2107792D01*
X2377761Y2107767D01*
X2377744Y2107737D01*
X2377731Y2107704D01*
X2377723Y2107667D01*
X2377721Y2107628D01*
G01X2377859Y2104675D02*
X2377832Y2104671D01*
X2377806Y2104660D01*
X2377782Y2104642D01*
X2377761Y2104617D01*
X2377744Y2104588D01*
X2377731Y2104554D01*
X2377723Y2104517D01*
X2377721Y2104478D01*
G01X2377859Y2101525D02*
X2377832Y2101522D01*
X2377806Y2101511D01*
X2377782Y2101493D01*
X2377761Y2101468D01*
X2377744Y2101438D01*
X2377731Y2101404D01*
X2377723Y2101368D01*
X2377721Y2101329D01*
G01X2382917Y2149264D02*
X2383044Y2149291D01*
X2383133Y2149364D01*
X2383165Y2149461D01*
G01X2382917Y2146114D02*
X2383044Y2146142D01*
X2383133Y2146214D01*
X2383165Y2146311D01*
G01X2382917Y2142965D02*
X2383044Y2142992D01*
X2383133Y2143065D01*
X2383165Y2143162D01*
G01X2382917Y2139815D02*
X2383044Y2139842D01*
X2383133Y2139915D01*
X2383165Y2140012D01*
G01X2382917Y2136665D02*
X2383044Y2136693D01*
X2383133Y2136766D01*
X2383165Y2136862D01*
G01X2382917Y2133516D02*
X2383044Y2133543D01*
X2383133Y2133616D01*
X2383165Y2133713D01*
G01X2382908Y2151132D02*
X2383035Y2151160D01*
X2383124Y2151232D01*
X2383155Y2151329D01*
G01X2382908Y2147982D02*
X2383035Y2148010D01*
X2383124Y2148083D01*
X2383155Y2148179D01*
G01X2382908Y2144833D02*
X2383035Y2144860D01*
X2383124Y2144933D01*
X2383155Y2145029D01*
G01X2382908Y2141683D02*
X2383035Y2141711D01*
X2383124Y2141784D01*
X2383155Y2141880D01*
G01X2382908Y2138533D02*
X2383035Y2138561D01*
X2383124Y2138634D01*
X2383155Y2138730D01*
G01X2382908Y2135384D02*
X2383035Y2135412D01*
X2383124Y2135484D01*
X2383155Y2135581D01*
G01X2382908Y2132234D02*
X2383035Y2132262D01*
X2383124Y2132335D01*
X2383155Y2132431D01*
G01X2382908Y2129085D02*
X2383035Y2129112D01*
X2383124Y2129185D01*
X2383155Y2129281D01*
G01X2382908Y2125935D02*
X2383035Y2125963D01*
X2383124Y2126036D01*
X2383155Y2126132D01*
G01X2382908Y2122785D02*
X2383035Y2122813D01*
X2383124Y2122886D01*
X2383155Y2122982D01*
G01X2382908Y2119636D02*
X2383035Y2119663D01*
X2383124Y2119736D01*
X2383155Y2119833D01*
G01X2382908Y2116486D02*
X2383035Y2116514D01*
X2383124Y2116587D01*
X2383155Y2116683D01*
G01X2382908Y2113337D02*
X2383035Y2113364D01*
X2383124Y2113437D01*
X2383155Y2113533D01*
G01X2382908Y2110187D02*
X2383035Y2110215D01*
X2383124Y2110288D01*
X2383155Y2110384D01*
G01X2382908Y2107037D02*
X2383035Y2107065D01*
X2383124Y2107138D01*
X2383155Y2107234D01*
G01X2382908Y2103888D02*
X2383035Y2103915D01*
X2383124Y2103988D01*
X2383155Y2104085D01*
G01X2382908Y2100738D02*
X2383035Y2100766D01*
X2383124Y2100839D01*
X2383155Y2100935D01*
G01Y2154872D02*
X2383123Y2154969D01*
X2383035Y2155041D01*
X2382908Y2155069D01*
G01X2383155Y2151722D02*
X2383123Y2151819D01*
X2383035Y2151892D01*
X2382908Y2151919D01*
G01X2383155Y2148573D02*
X2383123Y2148670D01*
X2383035Y2148742D01*
X2382908Y2148770D01*
G01X2383155Y2145423D02*
X2383123Y2145520D01*
X2383035Y2145592D01*
X2382908Y2145620D01*
G01X2383155Y2142274D02*
X2383123Y2142371D01*
X2383035Y2142443D01*
X2382908Y2142470D01*
G01X2383155Y2139124D02*
X2383123Y2139221D01*
X2383035Y2139293D01*
X2382908Y2139321D01*
G01X2383155Y2135974D02*
X2383123Y2136071D01*
X2383035Y2136144D01*
X2382908Y2136171D01*
G01X2383155Y2132825D02*
X2383123Y2132922D01*
X2383035Y2132994D01*
X2382908Y2133022D01*
G01X2383155Y2129675D02*
X2383123Y2129772D01*
X2383035Y2129844D01*
X2382908Y2129872D01*
G01X2383155Y2126525D02*
X2383123Y2126623D01*
X2383035Y2126695D01*
X2382908Y2126722D01*
G01X2383155Y2123376D02*
X2383123Y2123473D01*
X2383035Y2123545D01*
X2382908Y2123573D01*
G01X2383155Y2120226D02*
X2383123Y2120323D01*
X2383035Y2120395D01*
X2382908Y2120423D01*
G01X2383155Y2117077D02*
X2383123Y2117174D01*
X2383035Y2117246D01*
X2382908Y2117274D01*
G01X2383155Y2113927D02*
X2383123Y2114024D01*
X2383035Y2114096D01*
X2382908Y2114124D01*
G01X2383155Y2110777D02*
X2383123Y2110874D01*
X2383035Y2110947D01*
X2382908Y2110974D01*
G01X2383155Y2107628D02*
X2383123Y2107725D01*
X2383035Y2107797D01*
X2382908Y2107825D01*
G01X2383155Y2104478D02*
X2383123Y2104575D01*
X2383035Y2104647D01*
X2382908Y2104675D01*
G01X2383155Y2101329D02*
X2383123Y2101426D01*
X2383035Y2101498D01*
X2382908Y2101525D01*
G01X2383165Y2150445D02*
X2383132Y2150544D01*
X2383043Y2150615D01*
X2382917Y2150642D01*
G01X2383165Y2147295D02*
X2383132Y2147394D01*
X2383043Y2147465D01*
X2382917Y2147492D01*
G01X2383165Y2144146D02*
X2383132Y2144245D01*
X2383043Y2144316D01*
X2382917Y2144343D01*
G01X2383165Y2140996D02*
X2383132Y2141095D01*
X2383043Y2141166D01*
X2382917Y2141193D01*
G01X2383165Y2137847D02*
X2383132Y2137946D01*
X2383043Y2138016D01*
X2382917Y2138043D01*
G01X2383165Y2134697D02*
X2383132Y2134796D01*
X2383043Y2134867D01*
X2382917Y2134894D01*
G01X2378674Y2154380D02*
X2378752Y2153789D01*
G01X2378674Y2129380D02*
X2378752Y2128789D01*
G01X2378674Y2124380D02*
X2378752Y2123789D01*
G01X2378674Y2119380D02*
X2378752Y2118789D01*
G01X2378674Y2114380D02*
X2378752Y2113789D01*
G01X2378674Y2109380D02*
X2378752Y2108789D01*
G01X2378674Y2104380D02*
X2378752Y2103789D01*
G01X2378674Y2099380D02*
X2378752Y2098789D01*
G01X2378941Y2134697D02*
X2378942Y2134735D01*
X2378943Y2134772D01*
X2378946Y2134806D01*
X2378951Y2134836D01*
X2378955Y2134861D01*
X2378961Y2134879D01*
X2378967Y2134890D01*
X2378974Y2134894D01*
G01X2378941Y2137847D02*
X2378942Y2137885D01*
X2378943Y2137922D01*
X2378946Y2137955D01*
X2378951Y2137986D01*
X2378955Y2138010D01*
X2378961Y2138028D01*
X2378967Y2138040D01*
X2378974Y2138043D01*
G01X2378941Y2140996D02*
X2378942Y2141034D01*
X2378943Y2141071D01*
X2378946Y2141105D01*
X2378951Y2141135D01*
X2378955Y2141160D01*
X2378961Y2141178D01*
X2378967Y2141189D01*
X2378974Y2141193D01*
G01X2378941Y2144146D02*
X2378942Y2144184D01*
X2378943Y2144221D01*
X2378946Y2144255D01*
X2378951Y2144285D01*
X2378955Y2144309D01*
X2378961Y2144327D01*
X2378967Y2144339D01*
X2378974Y2144343D01*
G01X2378941Y2147295D02*
X2378942Y2147334D01*
X2378943Y2147370D01*
X2378946Y2147404D01*
X2378951Y2147435D01*
X2378955Y2147459D01*
X2378961Y2147477D01*
X2378967Y2147488D01*
X2378974Y2147492D01*
G01X2378941Y2150445D02*
X2378942Y2150483D01*
X2378943Y2150520D01*
X2378946Y2150554D01*
X2378951Y2150584D01*
X2378955Y2150609D01*
X2378961Y2150627D01*
X2378967Y2150638D01*
X2378974Y2150642D01*
G01X2387142Y2090837D02*
Y2233317D01*
G01X2386130Y2131356D02*
Y2125974D01*
G01Y2158277D02*
Y2152798D01*
G01X2386020Y2228789D02*
Y2095364D01*
G01X2385961Y2131151D02*
Y2153002D01*
G01Y2125974D02*
Y2094970D01*
G01X2385173Y2095758D02*
Y2228396D01*
G01X2383383Y2129774D02*
Y2129380D01*
G01Y2154774D02*
Y2154380D01*
G01X2383292Y2099774D02*
Y2099380D01*
G01Y2104774D02*
Y2104380D01*
G01Y2109774D02*
Y2109380D01*
G01Y2114774D02*
Y2114380D01*
G01Y2119774D02*
Y2119380D01*
G01Y2124774D02*
Y2124380D01*
G01X2383165Y2134697D02*
Y2133713D01*
G01Y2137847D02*
Y2136862D01*
G01Y2140996D02*
Y2140012D01*
G01Y2144146D02*
Y2143162D01*
G01Y2147295D02*
Y2146311D01*
G01Y2150445D02*
Y2149461D01*
G01X2383155Y2154478D02*
Y2154872D01*
G01Y2151329D02*
Y2151722D01*
G01Y2148179D02*
Y2148573D01*
G01Y2145029D02*
Y2145423D01*
G01Y2141880D02*
Y2142274D01*
G01Y2138730D02*
Y2139124D01*
G01Y2135581D02*
Y2135974D01*
G01Y2129281D02*
Y2129675D01*
G01Y2132431D02*
Y2132825D01*
G01Y2126132D02*
Y2126525D01*
G01Y2122982D02*
Y2123376D01*
G01Y2119833D02*
Y2120226D01*
G01Y2116683D02*
Y2117077D01*
G01Y2113533D02*
Y2113927D01*
G01Y2110384D02*
Y2110777D01*
G01Y2107234D02*
Y2107628D01*
G01Y2100935D02*
Y2101329D01*
G01Y2104085D02*
Y2104478D01*
G01X2380673Y2132333D02*
Y2131151D01*
G01Y2153002D02*
Y2151821D01*
G01X2378941Y2149461D02*
Y2150445D01*
G01Y2143162D02*
Y2144146D01*
G01Y2146311D02*
Y2147295D01*
G01Y2140012D02*
Y2140996D01*
G01Y2133713D02*
Y2134697D01*
G01Y2136862D02*
Y2137847D01*
G01X2378674Y2099774D02*
Y2099380D01*
G01Y2104774D02*
Y2104380D01*
G01Y2109774D02*
Y2109380D01*
G01Y2114774D02*
Y2114380D01*
G01Y2119774D02*
Y2119380D01*
G01Y2124774D02*
Y2124380D01*
G01Y2129774D02*
Y2129380D01*
G01Y2154774D02*
Y2154380D01*
G01X2378234Y2154478D02*
Y2154872D01*
G01Y2151329D02*
Y2151722D01*
G01Y2148179D02*
Y2148573D01*
G01Y2145029D02*
Y2145423D01*
G01Y2141880D02*
Y2142274D01*
G01Y2138730D02*
Y2139124D01*
G01Y2135581D02*
Y2135974D01*
G01Y2129281D02*
Y2129675D01*
G01Y2132431D02*
Y2132825D01*
G01Y2126132D02*
Y2126525D01*
G01Y2122982D02*
Y2123376D01*
G01Y2119833D02*
Y2120226D01*
G01Y2116683D02*
Y2117077D01*
G01Y2113533D02*
Y2113927D01*
G01Y2110384D02*
Y2110777D01*
G01Y2107234D02*
Y2107628D01*
G01Y2100935D02*
Y2101329D01*
G01Y2104085D02*
Y2104478D01*
G01X2377789Y2149461D02*
Y2150445D01*
G01Y2143162D02*
Y2144146D01*
G01Y2146311D02*
Y2147295D01*
G01Y2140012D02*
Y2140996D01*
G01Y2133713D02*
Y2134697D01*
G01Y2136862D02*
Y2137847D01*
G01X2377721Y2101329D02*
Y2100935D01*
G01Y2104478D02*
Y2104085D01*
G01Y2107628D02*
Y2107234D01*
G01Y2113927D02*
Y2113533D01*
G01Y2110777D02*
Y2110384D01*
G01Y2117077D02*
Y2116683D01*
G01Y2123376D02*
Y2122982D01*
G01Y2120226D02*
Y2119833D01*
G01Y2126525D02*
Y2126132D01*
G01Y2129675D02*
Y2129281D01*
G01Y2132825D02*
Y2132431D01*
G01Y2135974D02*
Y2135581D01*
G01Y2142274D02*
Y2141880D01*
G01Y2139124D02*
Y2138730D01*
G01Y2145423D02*
Y2145029D01*
G01Y2151722D02*
Y2151329D01*
G01Y2148573D02*
Y2148179D01*
G01Y2154872D02*
Y2154478D01*
G01X2377549Y2154380D02*
Y2154774D01*
G01Y2129380D02*
Y2129774D01*
G01Y2124380D02*
Y2124774D01*
G01Y2119380D02*
Y2119774D01*
G01Y2114380D02*
Y2114774D01*
G01Y2109380D02*
Y2109774D01*
G01Y2104380D02*
Y2104774D01*
G01Y2099380D02*
Y2099774D01*
G01X2376847Y2149461D02*
Y2150445D01*
G01Y2143162D02*
Y2144146D01*
G01Y2146311D02*
Y2147295D01*
G01Y2140012D02*
Y2140996D01*
G01Y2133713D02*
Y2134697D01*
G01Y2136862D02*
Y2137847D01*
G01X2376706Y2124380D02*
Y2124774D01*
G01Y2119380D02*
Y2119774D01*
G01Y2114380D02*
Y2114774D01*
G01Y2109380D02*
Y2109774D01*
G01Y2104380D02*
Y2104774D01*
G01Y2099380D02*
Y2099774D01*
G01X2376640Y2154380D02*
Y2154774D01*
G01Y2129380D02*
Y2129774D01*
G01X2376543Y2101329D02*
Y2100935D01*
G01Y2104478D02*
Y2104085D01*
G01Y2107628D02*
Y2107234D01*
G01Y2113927D02*
Y2113533D01*
G01Y2110777D02*
Y2110384D01*
G01Y2117077D02*
Y2116683D01*
G01Y2123376D02*
Y2122982D01*
G01Y2120226D02*
Y2119833D01*
G01Y2126525D02*
Y2126132D01*
G01Y2129675D02*
Y2129281D01*
G01Y2132825D02*
Y2132431D01*
G01Y2135974D02*
Y2135581D01*
G01Y2142274D02*
Y2141880D01*
G01Y2139124D02*
Y2138730D01*
G01Y2145423D02*
Y2145029D01*
G01Y2151722D02*
Y2151329D01*
G01Y2148573D02*
Y2148179D01*
G01Y2154872D02*
Y2154478D01*
G01X2377721Y2157628D02*
X2377723Y2157590D01*
X2377731Y2157553D01*
X2377744Y2157519D01*
X2377761Y2157489D01*
X2377782Y2157464D01*
X2377806Y2157446D01*
X2377832Y2157435D01*
X2377859Y2157431D01*
G01X2377721Y2154478D02*
X2377723Y2154440D01*
X2377731Y2154403D01*
X2377744Y2154369D01*
X2377761Y2154339D01*
X2377782Y2154315D01*
X2377806Y2154297D01*
X2377832Y2154285D01*
X2377859Y2154281D01*
G01X2377721Y2151329D02*
X2377723Y2151290D01*
X2377731Y2151254D01*
X2377744Y2151220D01*
X2377761Y2151189D01*
X2377782Y2151165D01*
X2377806Y2151147D01*
X2377832Y2151136D01*
X2377859Y2151132D01*
G01X2377721Y2148179D02*
X2377723Y2148141D01*
X2377731Y2148104D01*
X2377744Y2148070D01*
X2377761Y2148040D01*
X2377782Y2148015D01*
X2377806Y2147997D01*
X2377832Y2147986D01*
X2377859Y2147982D01*
G01X2377721Y2145029D02*
X2377723Y2144991D01*
X2377731Y2144954D01*
X2377744Y2144921D01*
X2377761Y2144890D01*
X2377782Y2144866D01*
X2377806Y2144848D01*
X2377832Y2144836D01*
X2377859Y2144833D01*
G01X2377721Y2141880D02*
X2377723Y2141842D01*
X2377731Y2141805D01*
X2377744Y2141771D01*
X2377761Y2141741D01*
X2377782Y2141716D01*
X2377806Y2141698D01*
X2377832Y2141687D01*
X2377859Y2141683D01*
G01X2377721Y2138730D02*
X2377723Y2138692D01*
X2377731Y2138655D01*
X2377744Y2138621D01*
X2377761Y2138591D01*
X2377782Y2138567D01*
X2377806Y2138548D01*
X2377832Y2138537D01*
X2377859Y2138533D01*
G01X2377721Y2135581D02*
X2377723Y2135542D01*
X2377731Y2135506D01*
X2377744Y2135472D01*
X2377761Y2135441D01*
X2377782Y2135417D01*
X2377806Y2135399D01*
X2377832Y2135388D01*
X2377859Y2135384D01*
G01X2377721Y2132431D02*
X2377723Y2132393D01*
X2377731Y2132356D01*
X2377744Y2132322D01*
X2377761Y2132292D01*
X2377782Y2132267D01*
X2377806Y2132249D01*
X2377832Y2132238D01*
X2377859Y2132234D01*
G01X2377721Y2129281D02*
X2377723Y2129243D01*
X2377731Y2129206D01*
X2377744Y2129172D01*
X2377761Y2129142D01*
X2377782Y2129118D01*
X2377806Y2129100D01*
X2377832Y2129088D01*
X2377859Y2129085D01*
G01X2377721Y2126132D02*
X2377723Y2126094D01*
X2377731Y2126057D01*
X2377744Y2126023D01*
X2377761Y2125993D01*
X2377782Y2125968D01*
X2377806Y2125950D01*
X2377832Y2125939D01*
X2377859Y2125935D01*
G01X2377721Y2122982D02*
X2377723Y2122944D01*
X2377731Y2122907D01*
X2377744Y2122873D01*
X2377761Y2122843D01*
X2377782Y2122819D01*
X2377806Y2122800D01*
X2377832Y2122789D01*
X2377859Y2122785D01*
G01X2377721Y2119833D02*
X2377723Y2119794D01*
X2377731Y2119758D01*
X2377744Y2119724D01*
X2377761Y2119693D01*
X2377782Y2119669D01*
X2377806Y2119651D01*
X2377832Y2119640D01*
X2377859Y2119636D01*
G01X2377721Y2116683D02*
X2377723Y2116645D01*
X2377731Y2116608D01*
X2377744Y2116574D01*
X2377761Y2116544D01*
X2377782Y2116519D01*
X2377806Y2116501D01*
X2377832Y2116490D01*
X2377859Y2116486D01*
G01X2377721Y2113533D02*
X2377723Y2113495D01*
X2377731Y2113458D01*
X2377744Y2113424D01*
X2377761Y2113394D01*
X2377782Y2113370D01*
X2377806Y2113352D01*
X2377832Y2113340D01*
X2377859Y2113337D01*
G01X2377721Y2110384D02*
X2377723Y2110346D01*
X2377731Y2110309D01*
X2377744Y2110275D01*
X2377761Y2110245D01*
X2377782Y2110220D01*
X2377806Y2110202D01*
X2377832Y2110191D01*
X2377859Y2110187D01*
G01X2377721Y2107234D02*
X2377723Y2107196D01*
X2377731Y2107159D01*
X2377744Y2107125D01*
X2377761Y2107095D01*
X2377782Y2107071D01*
X2377806Y2107052D01*
X2377832Y2107041D01*
X2377859Y2107037D01*
G01X2377721Y2104085D02*
X2377723Y2104046D01*
X2377731Y2104010D01*
X2377744Y2103976D01*
X2377761Y2103945D01*
X2377782Y2103921D01*
X2377806Y2103903D01*
X2377832Y2103892D01*
X2377859Y2103888D01*
G01X2377721Y2100935D02*
X2377723Y2100897D01*
X2377731Y2100860D01*
X2377744Y2100826D01*
X2377761Y2100796D01*
X2377782Y2100771D01*
X2377806Y2100753D01*
X2377832Y2100742D01*
X2377859Y2100738D01*
G01X2378234Y2104478D02*
X2378244Y2104577D01*
X2378272Y2104649D01*
X2378310Y2104675D01*
G01X2378234Y2107628D02*
X2378244Y2107726D01*
X2378272Y2107798D01*
X2378310Y2107825D01*
G01X2378234Y2120226D02*
X2378244Y2120325D01*
X2378272Y2120397D01*
X2378310Y2120423D01*
G01X2378234Y2123376D02*
X2378244Y2123474D01*
X2378272Y2123546D01*
X2378310Y2123573D01*
G01X2378234Y2132825D02*
X2378244Y2132923D01*
X2378272Y2132995D01*
X2378310Y2133022D01*
G01X2378234Y2135974D02*
X2378244Y2136073D01*
X2378272Y2136145D01*
X2378310Y2136171D01*
G01X2378234Y2139124D02*
X2378244Y2139222D01*
X2378272Y2139294D01*
X2378310Y2139321D01*
G01X2377789Y2134697D02*
X2377792Y2134735D01*
X2377800Y2134772D01*
X2377814Y2134806D01*
X2377832Y2134836D01*
X2377855Y2134861D01*
X2377880Y2134879D01*
X2377908Y2134890D01*
X2377937Y2134894D01*
G01X2377789Y2137847D02*
X2377792Y2137885D01*
X2377800Y2137922D01*
X2377814Y2137955D01*
X2377832Y2137986D01*
X2377855Y2138010D01*
X2377880Y2138028D01*
X2377908Y2138040D01*
X2377937Y2138043D01*
G01X2377789Y2140996D02*
X2377792Y2141034D01*
X2377800Y2141071D01*
X2377814Y2141105D01*
X2377832Y2141135D01*
X2377855Y2141160D01*
X2377880Y2141178D01*
X2377908Y2141189D01*
X2377937Y2141193D01*
G01X2377789Y2144146D02*
X2377792Y2144184D01*
X2377800Y2144221D01*
X2377814Y2144255D01*
X2377832Y2144285D01*
X2377855Y2144309D01*
X2377880Y2144327D01*
X2377908Y2144339D01*
X2377937Y2144343D01*
G01X2377789Y2147295D02*
X2377792Y2147334D01*
X2377800Y2147370D01*
X2377814Y2147404D01*
X2377832Y2147435D01*
X2377855Y2147459D01*
X2377880Y2147477D01*
X2377908Y2147488D01*
X2377937Y2147492D01*
G01X2377789Y2150445D02*
X2377792Y2150483D01*
X2377800Y2150520D01*
X2377814Y2150554D01*
X2377832Y2150584D01*
X2377855Y2150609D01*
X2377880Y2150627D01*
X2377908Y2150638D01*
X2377937Y2150642D01*
G01X2378674Y2099774D02*
X2378752Y2100364D01*
G01X2378674Y2104774D02*
X2378752Y2105364D01*
G01X2378674Y2109774D02*
X2378752Y2110364D01*
G01X2378674Y2114774D02*
X2378752Y2115364D01*
G01X2378674Y2119774D02*
X2378752Y2120364D01*
G01X2378674Y2124774D02*
X2378752Y2125364D01*
G01X2378674Y2129774D02*
X2378752Y2130364D01*
G01X2378674Y2154774D02*
X2378752Y2155364D01*
G01X2378234Y2142274D02*
X2378244Y2142372D01*
X2378272Y2142444D01*
X2378310Y2142470D01*
G01X2378234Y2148573D02*
X2378244Y2148671D01*
X2378272Y2148743D01*
X2378310Y2148770D01*
G01X2378234Y2151722D02*
X2378244Y2151821D01*
X2378272Y2151893D01*
X2378310Y2151919D01*
G01X2378234Y2154872D02*
X2378244Y2154970D01*
X2378272Y2155042D01*
X2378310Y2155069D01*
G01X2377549Y2099774D02*
X2377822Y2100364D01*
G01X2377549Y2104774D02*
X2377822Y2105364D01*
G01X2377549Y2109774D02*
X2377822Y2110364D01*
G01X2377549Y2114774D02*
X2377822Y2115364D01*
G01X2377549Y2119774D02*
X2377822Y2120364D01*
G01X2377549Y2124774D02*
X2377822Y2125364D01*
G01X2377549Y2129774D02*
X2377822Y2130364D01*
G01X2377549Y2154774D02*
X2377822Y2155364D01*
G01X2377132Y2100364D02*
X2376706Y2099774D01*
G01X2377132Y2105364D02*
X2376706Y2104774D01*
G01X2377132Y2110364D02*
X2376706Y2109774D01*
G01X2377132Y2115364D02*
X2376706Y2114774D01*
G01X2377132Y2120364D02*
X2376706Y2119774D01*
G01X2377132Y2125364D02*
X2376706Y2124774D01*
G01X2377064Y2130364D02*
X2376640Y2129774D01*
G01X2377064Y2155364D02*
X2376640Y2154774D01*
G01X2382877Y2098789D02*
X2383017Y2098985D01*
X2383155Y2099182D01*
X2383292Y2099380D01*
G01X2382877Y2103789D02*
X2383017Y2103985D01*
X2383155Y2104182D01*
X2383292Y2104380D01*
G01X2382877Y2108789D02*
X2383017Y2108985D01*
X2383155Y2109182D01*
X2383292Y2109380D01*
G01X2382877Y2113789D02*
X2383017Y2113985D01*
X2383155Y2114182D01*
X2383292Y2114380D01*
G01X2382877Y2118789D02*
X2383017Y2118985D01*
X2383155Y2119182D01*
X2383292Y2119380D01*
G01X2382877Y2123789D02*
X2383017Y2123985D01*
X2383155Y2124182D01*
X2383292Y2124380D01*
G01X2382977Y2128789D02*
X2383113Y2128985D01*
X2383249Y2129182D01*
X2383383Y2129380D01*
G01X2382977Y2153789D02*
X2383113Y2153985D01*
X2383249Y2154182D01*
X2383383Y2154380D01*
G01X2387142Y2092805D02*
X2385173Y2090837D01*
G01X2387142Y2153809D02*
X2385173Y2151840D01*
G01X2378310Y2101525D02*
X2378272Y2101499D01*
X2378244Y2101427D01*
X2378234Y2101329D01*
G01X2378310Y2110974D02*
X2378272Y2110948D01*
X2378244Y2110876D01*
X2378234Y2110777D01*
G01X2378310Y2114124D02*
X2378272Y2114097D01*
X2378244Y2114025D01*
X2378234Y2113927D01*
G01X2378310Y2117274D02*
X2378272Y2117247D01*
X2378244Y2117175D01*
X2378234Y2117077D01*
G01X2378310Y2126722D02*
X2378272Y2126696D01*
X2378244Y2126624D01*
X2378234Y2126525D01*
G01X2378310Y2129872D02*
X2378272Y2129846D01*
X2378244Y2129773D01*
X2378234Y2129675D01*
G01X2378310Y2145620D02*
X2378272Y2145594D01*
X2378244Y2145521D01*
X2378234Y2145423D01*
G01X2393835Y2088868D02*
Y2087136D01*
G01X2390425Y2090837D02*
X2393835Y2088868D01*
G01X2378310Y2160581D02*
X2378272Y2160607D01*
X2378244Y2160679D01*
X2378234Y2160777D01*
G01X2382908Y2161368D02*
X2376823D01*
G01X2376543Y2161171D02*
X2383155D01*
G01Y2160777D02*
X2376543D01*
G01X2382908Y2160581D02*
X2376823D01*
G01X2382877Y2160364D02*
X2377132D01*
G01X2376706Y2159774D02*
X2383292D01*
G01X2376706Y2159380D02*
X2383292D01*
G01X2382877Y2158789D02*
X2377132D01*
G01X2382908Y2158218D02*
X2376823D01*
G01X2376543Y2158022D02*
X2383155D01*
G01Y2157628D02*
X2376543D01*
G01X2383292Y2159774D02*
X2383155Y2159971D01*
X2383017Y2160168D01*
X2382877Y2160364D01*
G01X2377132Y2158789D02*
X2376706Y2159380D01*
G01X2377859Y2161368D02*
X2377832Y2161364D01*
X2377806Y2161353D01*
X2377782Y2161335D01*
X2377761Y2161310D01*
X2377744Y2161281D01*
X2377731Y2161247D01*
X2377723Y2161210D01*
X2377721Y2161171D01*
G01X2377859Y2158218D02*
X2377832Y2158215D01*
X2377806Y2158204D01*
X2377782Y2158186D01*
X2377761Y2158161D01*
X2377744Y2158131D01*
X2377731Y2158097D01*
X2377723Y2158060D01*
X2377721Y2158022D01*
G01X2382908Y2160581D02*
X2383035Y2160608D01*
X2383124Y2160681D01*
X2383155Y2160777D01*
G01X2377822Y2158789D02*
X2377549Y2159380D01*
G01X2383155Y2161171D02*
X2383123Y2161268D01*
X2383035Y2161340D01*
X2382908Y2161368D01*
G01X2383155Y2158022D02*
X2383123Y2158119D01*
X2383035Y2158191D01*
X2382908Y2158218D01*
G01X2378674Y2159380D02*
X2378752Y2158789D01*
G01X2385961Y2229183D02*
Y2158277D01*
G01X2383292Y2159774D02*
Y2159380D01*
G01X2383155Y2160777D02*
Y2161171D01*
G01Y2157628D02*
Y2158022D01*
G01X2378674Y2159774D02*
Y2159380D01*
G01X2378234Y2160777D02*
Y2161171D01*
G01Y2157628D02*
Y2158022D01*
G01X2377721Y2161171D02*
Y2160777D01*
G01Y2158022D02*
Y2157628D01*
G01X2377549Y2159380D02*
Y2159774D01*
G01X2376706Y2159380D02*
Y2159774D01*
G01X2376543Y2161171D02*
Y2160777D01*
G01Y2158022D02*
Y2157628D01*
G01X2377721Y2160777D02*
X2377723Y2160739D01*
X2377731Y2160702D01*
X2377744Y2160669D01*
X2377761Y2160638D01*
X2377782Y2160614D01*
X2377806Y2160596D01*
X2377832Y2160585D01*
X2377859Y2160581D01*
G01X2378674Y2159774D02*
X2378752Y2160364D01*
G01X2378234Y2158022D02*
X2378244Y2158120D01*
X2378272Y2158192D01*
X2378310Y2158218D01*
G01X2378234Y2161171D02*
X2378244Y2161270D01*
X2378272Y2161342D01*
X2378310Y2161368D01*
G01X2377549Y2159774D02*
X2377822Y2160364D01*
G01X2377132D02*
X2376706Y2159774D01*
G01X2382877Y2158789D02*
X2383017Y2158985D01*
X2383155Y2159182D01*
X2383292Y2159380D01*
G01X2378310Y2223573D02*
X2378272Y2223599D01*
X2378244Y2223671D01*
X2378234Y2223770D01*
G01X2378310Y2220423D02*
X2378272Y2220450D01*
X2378244Y2220522D01*
X2378234Y2220620D01*
G01X2378310Y2217274D02*
X2378272Y2217300D01*
X2378244Y2217372D01*
X2378234Y2217470D01*
G01X2378310Y2214124D02*
X2378272Y2214150D01*
X2378244Y2214222D01*
X2378234Y2214321D01*
G01X2378310Y2210974D02*
X2378272Y2211001D01*
X2378244Y2211073D01*
X2378234Y2211171D01*
G01X2382908Y2211762D02*
X2383034Y2211734D01*
X2383124Y2211662D01*
X2383155Y2211565D01*
G01X2378310Y2207825D02*
X2378272Y2207851D01*
X2378244Y2207923D01*
X2378234Y2208022D01*
G01X2378310Y2204675D02*
X2378272Y2204702D01*
X2378244Y2204774D01*
X2378234Y2204872D01*
G01X2378310Y2201525D02*
X2378272Y2201552D01*
X2378244Y2201624D01*
X2378234Y2201722D01*
G01X2378310Y2198376D02*
X2378272Y2198402D01*
X2378244Y2198474D01*
X2378234Y2198573D01*
G01X2378310Y2195226D02*
X2378272Y2195253D01*
X2378244Y2195325D01*
X2378234Y2195423D01*
G01X2378310Y2192077D02*
X2378272Y2192103D01*
X2378244Y2192175D01*
X2378234Y2192274D01*
G01X2378310Y2188927D02*
X2378272Y2188953D01*
X2378244Y2189026D01*
X2378234Y2189124D01*
G01X2378310Y2185777D02*
X2378272Y2185804D01*
X2378244Y2185876D01*
X2378234Y2185974D01*
G01X2378310Y2182628D02*
X2378272Y2182654D01*
X2378244Y2182726D01*
X2378234Y2182825D01*
G01X2378310Y2179478D02*
X2378272Y2179505D01*
X2378244Y2179577D01*
X2378234Y2179675D01*
G01X2378310Y2176329D02*
X2378272Y2176355D01*
X2378244Y2176427D01*
X2378234Y2176525D01*
G01X2378310Y2173179D02*
X2378272Y2173205D01*
X2378244Y2173278D01*
X2378234Y2173376D01*
G01X2378310Y2170029D02*
X2378272Y2170056D01*
X2378244Y2170128D01*
X2378234Y2170226D01*
G01X2378310Y2166880D02*
X2378272Y2166906D01*
X2378244Y2166978D01*
X2378234Y2167077D01*
G01X2378310Y2163730D02*
X2378272Y2163757D01*
X2378244Y2163829D01*
X2378234Y2163927D01*
G01X2382908Y2183415D02*
X2383034Y2183388D01*
X2383124Y2183315D01*
X2383155Y2183218D01*
G01X2382877Y2225364D02*
X2377132D01*
G01X2376706Y2224774D02*
X2383292D01*
G01X2376706Y2224380D02*
X2383292D01*
G01X2382908Y2224360D02*
X2376823D01*
G01X2376543Y2224163D02*
X2383155D01*
G01X2382877Y2223789D02*
X2377132D01*
G01X2383155Y2223770D02*
X2376543D01*
G01X2382908Y2223573D02*
X2376823D01*
G01X2382908Y2221211D02*
X2376823D01*
G01X2376543Y2221014D02*
X2383155D01*
G01Y2220620D02*
X2376543D01*
G01X2382908Y2220423D02*
X2376823D01*
G01X2382877Y2220364D02*
X2377132D01*
G01X2376706Y2219774D02*
X2383292D01*
G01X2376706Y2219380D02*
X2383292D01*
G01X2382877Y2218789D02*
X2377132D01*
G01X2382908Y2218061D02*
X2376823D01*
G01X2376543Y2217864D02*
X2383155D01*
G01Y2217470D02*
X2376543D01*
G01X2382908Y2217274D02*
X2376823D01*
G01X2382877Y2215364D02*
X2377132D01*
G01X2382908Y2214911D02*
X2376823D01*
G01X2376706Y2214774D02*
X2383292D01*
G01X2376543Y2214714D02*
X2383155D01*
G01X2376706Y2214380D02*
X2383292D01*
G01X2383155Y2214321D02*
X2376543D01*
G01X2382908Y2214124D02*
X2376823D01*
G01X2382877Y2213789D02*
X2377132D01*
G01X2382908Y2211762D02*
X2376823D01*
G01X2376543Y2211565D02*
X2383155D01*
G01Y2211171D02*
X2376543D01*
G01X2382908Y2210974D02*
X2376823D01*
G01X2384846Y2210364D02*
X2379101D01*
G01X2378674Y2209774D02*
X2385260D01*
G01X2378674Y2209380D02*
X2385260D01*
G01X2384846Y2208789D02*
X2379101D01*
G01X2382908Y2208612D02*
X2376823D01*
G01X2376543Y2208415D02*
X2383155D01*
G01Y2208022D02*
X2376543D01*
G01X2382908Y2207825D02*
X2376823D01*
G01X2382908Y2205463D02*
X2376823D01*
G01X2382877Y2205364D02*
X2377132D01*
G01X2376543Y2205266D02*
X2383155D01*
G01Y2204872D02*
X2376543D01*
G01X2376706Y2204774D02*
X2383292D01*
G01X2382908Y2204675D02*
X2376823D01*
G01X2376706Y2204380D02*
X2383292D01*
G01X2382877Y2203789D02*
X2377132D01*
G01X2382908Y2202313D02*
X2376823D01*
G01X2376543Y2202116D02*
X2383155D01*
G01Y2201722D02*
X2376543D01*
G01X2382908Y2201525D02*
X2376823D01*
G01X2382877Y2200364D02*
X2377132D01*
G01X2376706Y2199774D02*
X2383292D01*
G01X2376706Y2199380D02*
X2383292D01*
G01X2382908Y2199163D02*
X2376823D01*
G01X2376543Y2198966D02*
X2383155D01*
G01X2382877Y2198789D02*
X2377132D01*
G01X2383155Y2198573D02*
X2376543D01*
G01X2382908Y2198376D02*
X2376823D01*
G01X2383292Y2224774D02*
X2383155Y2224971D01*
X2383017Y2225168D01*
X2382877Y2225364D01*
G01X2383292Y2219774D02*
X2383155Y2219971D01*
X2383017Y2220168D01*
X2382877Y2220364D01*
G01X2383292Y2214774D02*
X2383155Y2214971D01*
X2383017Y2215168D01*
X2382877Y2215364D01*
G01X2385260Y2209774D02*
X2385123Y2209971D01*
X2384985Y2210168D01*
X2384846Y2210364D01*
G01X2383292Y2204774D02*
X2383155Y2204971D01*
X2383017Y2205168D01*
X2382877Y2205364D01*
G01X2383292Y2199774D02*
X2383155Y2199971D01*
X2383017Y2200168D01*
X2382877Y2200364D01*
G01X2383292Y2194774D02*
X2383155Y2194971D01*
X2383017Y2195168D01*
X2382877Y2195364D01*
G01X2383292Y2189774D02*
X2383155Y2189971D01*
X2383017Y2190168D01*
X2382877Y2190364D01*
G01X2383292Y2184774D02*
X2383155Y2184971D01*
X2383017Y2185168D01*
X2382877Y2185364D01*
G01X2383292Y2179774D02*
X2383155Y2179971D01*
X2383017Y2180168D01*
X2382877Y2180364D01*
G01X2383292Y2174774D02*
X2383155Y2174971D01*
X2383017Y2175168D01*
X2382877Y2175364D01*
G01X2385260Y2169774D02*
X2385123Y2169971D01*
X2384985Y2170168D01*
X2384846Y2170364D01*
G01X2377132Y2223789D02*
X2376706Y2224380D01*
G01X2377132Y2218789D02*
X2376706Y2219380D01*
G01X2377132Y2213789D02*
X2376706Y2214380D01*
G01X2379101Y2208789D02*
X2378674Y2209380D01*
G01X2377132Y2203789D02*
X2376706Y2204380D01*
G01X2377132Y2198789D02*
X2376706Y2199380D01*
G01X2377132Y2193789D02*
X2376706Y2194380D01*
G01X2377132Y2188789D02*
X2376706Y2189380D01*
G01X2377132Y2183789D02*
X2376706Y2184380D01*
G01X2377132Y2178789D02*
X2376706Y2179380D01*
G01X2377132Y2173789D02*
X2376706Y2174380D01*
G01X2379101Y2168789D02*
X2378674Y2169380D01*
G01X2377132Y2163789D02*
X2376706Y2164380D01*
G01X2382908Y2196014D02*
X2376823D01*
G01X2376543Y2195817D02*
X2383155D01*
G01Y2195423D02*
X2376543D01*
G01X2382877Y2195364D02*
X2377132D01*
G01X2382908Y2195226D02*
X2376823D01*
G01X2376706Y2194774D02*
X2383292D01*
G01X2376706Y2194380D02*
X2383292D01*
G01X2382877Y2193789D02*
X2377132D01*
G01X2382908Y2192864D02*
X2376823D01*
G01X2376543Y2192667D02*
X2383155D01*
G01Y2192274D02*
X2376543D01*
G01X2382908Y2192077D02*
X2376823D01*
G01X2382877Y2190364D02*
X2377132D01*
G01X2376706Y2189774D02*
X2383292D01*
G01X2382908Y2189714D02*
X2376823D01*
G01X2376543Y2189518D02*
X2383155D01*
G01X2376706Y2189380D02*
X2383292D01*
G01X2383155Y2189124D02*
X2376543D01*
G01X2382908Y2188927D02*
X2376823D01*
G01X2382877Y2188789D02*
X2377132D01*
G01X2382908Y2186565D02*
X2376823D01*
G01X2376543Y2186368D02*
X2383155D01*
G01Y2185974D02*
X2376543D01*
G01X2382908Y2185777D02*
X2376823D01*
G01X2382877Y2185364D02*
X2377132D01*
G01X2376706Y2184774D02*
X2383292D01*
G01X2376706Y2184380D02*
X2383292D01*
G01X2382877Y2183789D02*
X2377132D01*
G01X2382908Y2183415D02*
X2376823D01*
G01X2376543Y2183218D02*
X2383155D01*
G01Y2182825D02*
X2376543D01*
G01X2382908Y2182628D02*
X2376823D01*
G01X2382877Y2180364D02*
X2377132D01*
G01X2382908Y2180266D02*
X2376823D01*
G01X2376543Y2180069D02*
X2383155D01*
G01X2376706Y2179774D02*
X2383292D01*
G01X2383155Y2179675D02*
X2376543D01*
G01X2382908Y2179478D02*
X2376823D01*
G01X2376706Y2179380D02*
X2383292D01*
G01X2382877Y2178789D02*
X2377132D01*
G01X2382908Y2177116D02*
X2376823D01*
G01X2376543Y2176919D02*
X2383155D01*
G01Y2176525D02*
X2376543D01*
G01X2382908Y2176329D02*
X2376823D01*
G01X2382877Y2175364D02*
X2377132D01*
G01X2376706Y2174774D02*
X2383292D01*
G01X2376706Y2174380D02*
X2383292D01*
G01X2382908Y2173966D02*
X2376823D01*
G01X2382877Y2173789D02*
X2377132D01*
G01X2376543Y2173770D02*
X2383155D01*
G01Y2173376D02*
X2376543D01*
G01X2382908Y2173179D02*
X2376823D01*
G01X2382908Y2170817D02*
X2376823D01*
G01X2376543Y2170620D02*
X2383155D01*
G01X2384846Y2170364D02*
X2379101D01*
G01X2383155Y2170226D02*
X2376543D01*
G01X2382908Y2170029D02*
X2376823D01*
G01X2378674Y2169774D02*
X2385260D01*
G01X2378674Y2169380D02*
X2385260D01*
G01X2384846Y2168789D02*
X2379101D01*
G01X2382908Y2167667D02*
X2376823D01*
G01X2376543Y2167470D02*
X2383155D01*
G01Y2167077D02*
X2376543D01*
G01X2382908Y2166880D02*
X2376823D01*
G01X2382877Y2165364D02*
X2377132D01*
G01X2376706Y2164774D02*
X2383292D01*
G01X2382908Y2164518D02*
X2376823D01*
G01X2376706Y2164380D02*
X2383292D01*
G01X2376543Y2164321D02*
X2383155D01*
G01Y2163927D02*
X2376543D01*
G01X2382877Y2163789D02*
X2377132D01*
G01X2382908Y2163730D02*
X2376823D01*
G01X2377859Y2224360D02*
X2377832Y2224356D01*
X2377806Y2224345D01*
X2377782Y2224327D01*
X2377761Y2224302D01*
X2377744Y2224273D01*
X2377731Y2224239D01*
X2377723Y2224202D01*
X2377721Y2224163D01*
G01X2377859Y2221211D02*
X2377832Y2221207D01*
X2377806Y2221196D01*
X2377782Y2221178D01*
X2377761Y2221153D01*
X2377744Y2221123D01*
X2377731Y2221089D01*
X2377723Y2221053D01*
X2377721Y2221014D01*
G01X2377859Y2218061D02*
X2377832Y2218057D01*
X2377806Y2218046D01*
X2377782Y2218028D01*
X2377761Y2218003D01*
X2377744Y2217974D01*
X2377731Y2217940D01*
X2377723Y2217903D01*
X2377721Y2217864D01*
G01X2377859Y2214911D02*
X2377832Y2214908D01*
X2377806Y2214896D01*
X2377782Y2214878D01*
X2377761Y2214854D01*
X2377744Y2214824D01*
X2377731Y2214790D01*
X2377723Y2214753D01*
X2377721Y2214714D01*
G01X2377859Y2211762D02*
X2377832Y2211758D01*
X2377806Y2211747D01*
X2377782Y2211729D01*
X2377761Y2211704D01*
X2377744Y2211674D01*
X2377731Y2211641D01*
X2377723Y2211604D01*
X2377721Y2211565D01*
G01X2377859Y2208612D02*
X2377832Y2208608D01*
X2377806Y2208597D01*
X2377782Y2208579D01*
X2377761Y2208554D01*
X2377744Y2208525D01*
X2377731Y2208491D01*
X2377723Y2208454D01*
X2377721Y2208415D01*
G01X2377859Y2205463D02*
X2377832Y2205459D01*
X2377806Y2205448D01*
X2377782Y2205430D01*
X2377761Y2205405D01*
X2377744Y2205375D01*
X2377731Y2205341D01*
X2377723Y2205305D01*
X2377721Y2205266D01*
G01X2377859Y2202313D02*
X2377832Y2202309D01*
X2377806Y2202298D01*
X2377782Y2202280D01*
X2377761Y2202255D01*
X2377744Y2202226D01*
X2377731Y2202192D01*
X2377723Y2202155D01*
X2377721Y2202116D01*
G01X2377859Y2199163D02*
X2377832Y2199160D01*
X2377806Y2199148D01*
X2377782Y2199130D01*
X2377761Y2199106D01*
X2377744Y2199076D01*
X2377731Y2199042D01*
X2377723Y2199005D01*
X2377721Y2198966D01*
G01X2377859Y2196014D02*
X2377832Y2196010D01*
X2377806Y2195999D01*
X2377782Y2195981D01*
X2377761Y2195956D01*
X2377744Y2195926D01*
X2377731Y2195892D01*
X2377723Y2195856D01*
X2377721Y2195817D01*
G01X2377859Y2192864D02*
X2377832Y2192860D01*
X2377806Y2192849D01*
X2377782Y2192831D01*
X2377761Y2192806D01*
X2377744Y2192777D01*
X2377731Y2192743D01*
X2377723Y2192706D01*
X2377721Y2192667D01*
G01X2377859Y2189714D02*
X2377832Y2189711D01*
X2377806Y2189700D01*
X2377782Y2189682D01*
X2377761Y2189657D01*
X2377744Y2189627D01*
X2377731Y2189593D01*
X2377723Y2189557D01*
X2377721Y2189518D01*
G01X2377859Y2186565D02*
X2377832Y2186561D01*
X2377806Y2186550D01*
X2377782Y2186532D01*
X2377761Y2186507D01*
X2377744Y2186478D01*
X2377731Y2186444D01*
X2377723Y2186407D01*
X2377721Y2186368D01*
G01X2383292Y2164774D02*
X2383155Y2164971D01*
X2383017Y2165168D01*
X2382877Y2165364D01*
G01X2377859Y2183415D02*
X2377832Y2183412D01*
X2377806Y2183400D01*
X2377782Y2183382D01*
X2377761Y2183358D01*
X2377744Y2183328D01*
X2377731Y2183294D01*
X2377723Y2183257D01*
X2377721Y2183218D01*
G01X2377859Y2180266D02*
X2377832Y2180262D01*
X2377806Y2180251D01*
X2377782Y2180233D01*
X2377761Y2180208D01*
X2377744Y2180178D01*
X2377731Y2180144D01*
X2377723Y2180108D01*
X2377721Y2180069D01*
G01X2377859Y2177116D02*
X2377832Y2177112D01*
X2377806Y2177101D01*
X2377782Y2177083D01*
X2377761Y2177058D01*
X2377744Y2177029D01*
X2377731Y2176995D01*
X2377723Y2176958D01*
X2377721Y2176919D01*
G01X2377859Y2173966D02*
X2377832Y2173963D01*
X2377806Y2173952D01*
X2377782Y2173934D01*
X2377761Y2173909D01*
X2377744Y2173879D01*
X2377731Y2173845D01*
X2377723Y2173809D01*
X2377721Y2173770D01*
G01X2377859Y2170817D02*
X2377832Y2170813D01*
X2377806Y2170802D01*
X2377782Y2170784D01*
X2377761Y2170759D01*
X2377744Y2170729D01*
X2377731Y2170696D01*
X2377723Y2170659D01*
X2377721Y2170620D01*
G01X2377859Y2167667D02*
X2377832Y2167663D01*
X2377806Y2167652D01*
X2377782Y2167634D01*
X2377761Y2167610D01*
X2377744Y2167580D01*
X2377731Y2167546D01*
X2377723Y2167509D01*
X2377721Y2167470D01*
G01X2377859Y2164518D02*
X2377832Y2164514D01*
X2377806Y2164503D01*
X2377782Y2164485D01*
X2377761Y2164460D01*
X2377744Y2164430D01*
X2377731Y2164396D01*
X2377723Y2164360D01*
X2377721Y2164321D01*
G01X2382908Y2223573D02*
X2383035Y2223600D01*
X2383124Y2223673D01*
X2383155Y2223770D01*
G01X2382908Y2220423D02*
X2383035Y2220451D01*
X2383124Y2220524D01*
X2383155Y2220620D01*
G01X2382908Y2217274D02*
X2383035Y2217301D01*
X2383124Y2217374D01*
X2383155Y2217470D01*
G01X2382908Y2214124D02*
X2383035Y2214152D01*
X2383124Y2214225D01*
X2383155Y2214321D01*
G01X2382908Y2207825D02*
X2383035Y2207852D01*
X2383124Y2207925D01*
X2383155Y2208022D01*
G01X2382908Y2204675D02*
X2383035Y2204703D01*
X2383124Y2204776D01*
X2383155Y2204872D01*
G01X2382908Y2201525D02*
X2383035Y2201553D01*
X2383124Y2201626D01*
X2383155Y2201722D01*
G01X2382908Y2198376D02*
X2383035Y2198404D01*
X2383124Y2198477D01*
X2383155Y2198573D01*
G01X2382908Y2195226D02*
X2383035Y2195254D01*
X2383124Y2195327D01*
X2383155Y2195423D01*
G01X2382908Y2192077D02*
X2383035Y2192104D01*
X2383124Y2192177D01*
X2383155Y2192274D01*
G01X2382908Y2188927D02*
X2383035Y2188955D01*
X2383124Y2189028D01*
X2383155Y2189124D01*
G01X2382908Y2185777D02*
X2383035Y2185805D01*
X2383124Y2185878D01*
X2383155Y2185974D01*
G01X2382908Y2179478D02*
X2383035Y2179506D01*
X2383124Y2179579D01*
X2383155Y2179675D01*
G01X2382908Y2176329D02*
X2383035Y2176356D01*
X2383124Y2176429D01*
X2383155Y2176525D01*
G01X2382908Y2173179D02*
X2383035Y2173207D01*
X2383124Y2173280D01*
X2383155Y2173376D01*
G01X2382908Y2170029D02*
X2383035Y2170057D01*
X2383124Y2170130D01*
X2383155Y2170226D01*
G01X2382908Y2166880D02*
X2383035Y2166908D01*
X2383124Y2166980D01*
X2383155Y2167077D01*
G01X2382908Y2163730D02*
X2383035Y2163758D01*
X2383124Y2163831D01*
X2383155Y2163927D01*
G01X2377822Y2223789D02*
X2377549Y2224380D01*
G01X2377822Y2218789D02*
X2377549Y2219380D01*
G01X2377822Y2213789D02*
X2377549Y2214380D01*
G01X2379791Y2208789D02*
X2379518Y2209380D01*
G01X2377822Y2203789D02*
X2377549Y2204380D01*
G01X2377822Y2198789D02*
X2377549Y2199380D01*
G01X2377822Y2193789D02*
X2377549Y2194380D01*
G01X2377822Y2188789D02*
X2377549Y2189380D01*
G01X2377822Y2183789D02*
X2377549Y2184380D01*
G01X2377822Y2178789D02*
X2377549Y2179380D01*
G01X2377822Y2173789D02*
X2377549Y2174380D01*
G01X2379791Y2168789D02*
X2379518Y2169380D01*
G01X2377822Y2163789D02*
X2377549Y2164380D01*
G01X2383155Y2224163D02*
X2383123Y2224260D01*
X2383035Y2224332D01*
X2382908Y2224360D01*
G01X2383155Y2221014D02*
X2383123Y2221111D01*
X2383035Y2221183D01*
X2382908Y2221211D01*
G01X2383155Y2217864D02*
X2383123Y2217961D01*
X2383035Y2218033D01*
X2382908Y2218061D01*
G01X2383155Y2214714D02*
X2383123Y2214811D01*
X2383035Y2214884D01*
X2382908Y2214911D01*
G01X2383155Y2208415D02*
X2383123Y2208512D01*
X2383035Y2208584D01*
X2382908Y2208612D01*
G01X2383155Y2205266D02*
X2383123Y2205363D01*
X2383035Y2205435D01*
X2382908Y2205463D01*
G01X2383155Y2202116D02*
X2383123Y2202213D01*
X2383035Y2202285D01*
X2382908Y2202313D01*
G01X2383155Y2198966D02*
X2383123Y2199063D01*
X2383035Y2199136D01*
X2382908Y2199163D01*
G01X2383155Y2195817D02*
X2383123Y2195914D01*
X2383035Y2195986D01*
X2382908Y2196014D01*
G01X2383155Y2192667D02*
X2383123Y2192764D01*
X2383035Y2192836D01*
X2382908Y2192864D01*
G01X2383155Y2189518D02*
X2383123Y2189615D01*
X2383035Y2189687D01*
X2382908Y2189714D01*
G01X2383155Y2186368D02*
X2383123Y2186465D01*
X2383035Y2186537D01*
X2382908Y2186565D01*
G01X2383155Y2180069D02*
X2383123Y2180166D01*
X2383035Y2180238D01*
X2382908Y2180266D01*
G01X2383155Y2176919D02*
X2383123Y2177016D01*
X2383035Y2177088D01*
X2382908Y2177116D01*
G01X2383155Y2173770D02*
X2383123Y2173867D01*
X2383035Y2173939D01*
X2382908Y2173966D01*
G01X2383155Y2170620D02*
X2383123Y2170717D01*
X2383035Y2170789D01*
X2382908Y2170817D01*
G01X2383155Y2167470D02*
X2383123Y2167567D01*
X2383035Y2167640D01*
X2382908Y2167667D01*
G01X2383155Y2164321D02*
X2383123Y2164418D01*
X2383035Y2164490D01*
X2382908Y2164518D01*
G01X2378674Y2224380D02*
X2378752Y2223789D01*
G01X2380643Y2209380D02*
X2380720Y2208789D01*
G01X2378752Y2218789D02*
X2378674Y2219380D01*
G01Y2214380D02*
X2378752Y2213789D01*
G01X2378674Y2204380D02*
X2378752Y2203789D01*
G01X2378674Y2199380D02*
X2378752Y2198789D01*
G01X2378674Y2194380D02*
X2378752Y2193789D01*
G01X2378674Y2189380D02*
X2378752Y2188789D01*
G01X2378674Y2184380D02*
X2378752Y2183789D01*
G01X2380643Y2169380D02*
X2380720Y2168789D01*
G01X2378674Y2179380D02*
X2378752Y2178789D01*
G01X2378674Y2174380D02*
X2378752Y2173789D01*
G01X2378674Y2164380D02*
X2378752Y2163789D01*
G01X2377721Y2223770D02*
X2377723Y2223731D01*
X2377731Y2223695D01*
X2377744Y2223661D01*
X2377761Y2223630D01*
X2377782Y2223606D01*
X2377806Y2223588D01*
X2377832Y2223577D01*
X2377859Y2223573D01*
G01X2377721Y2220620D02*
X2377723Y2220582D01*
X2377731Y2220545D01*
X2377744Y2220511D01*
X2377761Y2220481D01*
X2377782Y2220456D01*
X2377806Y2220438D01*
X2377832Y2220427D01*
X2377859Y2220423D01*
G01X2377721Y2217470D02*
X2377723Y2217432D01*
X2377731Y2217395D01*
X2377744Y2217361D01*
X2377761Y2217331D01*
X2377782Y2217307D01*
X2377806Y2217289D01*
X2377832Y2217277D01*
X2377859Y2217274D01*
G01X2377721Y2214321D02*
X2377723Y2214283D01*
X2377731Y2214246D01*
X2377744Y2214212D01*
X2377761Y2214182D01*
X2377782Y2214157D01*
X2377806Y2214139D01*
X2377832Y2214128D01*
X2377859Y2214124D01*
G01X2377721Y2211171D02*
X2377723Y2211133D01*
X2377731Y2211096D01*
X2377744Y2211062D01*
X2377761Y2211032D01*
X2377782Y2211008D01*
X2377806Y2210989D01*
X2377832Y2210978D01*
X2377859Y2210974D01*
G01X2377721Y2208022D02*
X2377723Y2207983D01*
X2377731Y2207947D01*
X2377744Y2207913D01*
X2377761Y2207882D01*
X2377782Y2207858D01*
X2377806Y2207840D01*
X2377832Y2207829D01*
X2377859Y2207825D01*
G01X2377721Y2204872D02*
X2377723Y2204834D01*
X2377731Y2204797D01*
X2377744Y2204763D01*
X2377761Y2204733D01*
X2377782Y2204708D01*
X2377806Y2204690D01*
X2377832Y2204679D01*
X2377859Y2204675D01*
G01X2377721Y2201722D02*
X2377723Y2201684D01*
X2377731Y2201647D01*
X2377744Y2201613D01*
X2377761Y2201583D01*
X2377782Y2201559D01*
X2377806Y2201541D01*
X2377832Y2201529D01*
X2377859Y2201525D01*
G01X2377721Y2198573D02*
X2377723Y2198535D01*
X2377731Y2198498D01*
X2377744Y2198464D01*
X2377761Y2198434D01*
X2377782Y2198409D01*
X2377806Y2198391D01*
X2377832Y2198380D01*
X2377859Y2198376D01*
G01X2377721Y2195423D02*
X2377723Y2195385D01*
X2377731Y2195348D01*
X2377744Y2195314D01*
X2377761Y2195284D01*
X2377782Y2195260D01*
X2377806Y2195241D01*
X2377832Y2195230D01*
X2377859Y2195226D01*
G01X2377721Y2192274D02*
X2377723Y2192235D01*
X2377731Y2192199D01*
X2377744Y2192165D01*
X2377761Y2192134D01*
X2377782Y2192110D01*
X2377806Y2192092D01*
X2377832Y2192081D01*
X2377859Y2192077D01*
G01X2377721Y2189124D02*
X2377723Y2189086D01*
X2377731Y2189049D01*
X2377744Y2189015D01*
X2377761Y2188985D01*
X2377782Y2188960D01*
X2377806Y2188942D01*
X2377832Y2188931D01*
X2377859Y2188927D01*
G01X2377721Y2185974D02*
X2377723Y2185936D01*
X2377731Y2185899D01*
X2377744Y2185865D01*
X2377761Y2185835D01*
X2377782Y2185811D01*
X2377806Y2185793D01*
X2377832Y2185781D01*
X2377859Y2185777D01*
G01X2377721Y2182825D02*
X2377723Y2182786D01*
X2377731Y2182750D01*
X2377744Y2182716D01*
X2377761Y2182686D01*
X2377782Y2182661D01*
X2377806Y2182643D01*
X2377832Y2182632D01*
X2377859Y2182628D01*
G01X2377721Y2179675D02*
X2377723Y2179637D01*
X2377731Y2179600D01*
X2377744Y2179566D01*
X2377761Y2179536D01*
X2377782Y2179512D01*
X2377806Y2179493D01*
X2377832Y2179482D01*
X2377859Y2179478D01*
G01X2385260Y2169774D02*
Y2169380D01*
G01Y2209774D02*
Y2209380D01*
G01X2383292Y2164774D02*
Y2164380D01*
G01Y2174774D02*
Y2174380D01*
G01Y2179774D02*
Y2179380D01*
G01Y2184774D02*
Y2184380D01*
G01Y2189774D02*
Y2189380D01*
G01Y2194774D02*
Y2194380D01*
G01Y2199774D02*
Y2199380D01*
G01Y2204774D02*
Y2204380D01*
G01Y2214774D02*
Y2214380D01*
G01Y2219774D02*
Y2219380D01*
G01Y2224774D02*
Y2224380D01*
G01X2383155Y2223770D02*
Y2224163D01*
G01Y2220620D02*
Y2221014D01*
G01Y2217470D02*
Y2217864D01*
G01Y2214321D02*
Y2214714D01*
G01Y2208022D02*
Y2208415D01*
G01Y2211171D02*
Y2211565D01*
G01Y2204872D02*
Y2205266D01*
G01Y2201722D02*
Y2202116D01*
G01Y2198573D02*
Y2198966D01*
G01Y2195423D02*
Y2195817D01*
G01Y2192274D02*
Y2192667D01*
G01Y2189124D02*
Y2189518D01*
G01Y2185974D02*
Y2186368D01*
G01Y2182825D02*
Y2183218D01*
G01Y2176525D02*
Y2176919D01*
G01Y2179675D02*
Y2180069D01*
G01Y2173376D02*
Y2173770D01*
G01Y2170226D02*
Y2170620D01*
G01Y2167077D02*
Y2167470D01*
G01Y2163927D02*
Y2164321D01*
G01X2380643Y2169774D02*
Y2169380D01*
G01Y2209774D02*
Y2209380D01*
G01X2379518D02*
Y2209774D01*
G01Y2169380D02*
Y2169774D01*
G01X2378674Y2209380D02*
Y2209774D01*
G01Y2169380D02*
Y2169774D01*
G01Y2219380D02*
Y2219774D01*
G01Y2164774D02*
Y2164380D01*
G01Y2174774D02*
Y2174380D01*
G01Y2179774D02*
Y2179380D01*
G01Y2184774D02*
Y2184380D01*
G01Y2189774D02*
Y2189380D01*
G01Y2194774D02*
Y2194380D01*
G01Y2199774D02*
Y2199380D01*
G01Y2204774D02*
Y2204380D01*
G01Y2214774D02*
Y2214380D01*
G01Y2224774D02*
Y2224380D01*
G01X2378234Y2223770D02*
Y2224163D01*
G01Y2220620D02*
Y2221014D01*
G01Y2217470D02*
Y2217864D01*
G01Y2214321D02*
Y2214714D01*
G01Y2208022D02*
Y2208415D01*
G01Y2211171D02*
Y2211565D01*
G01Y2204872D02*
Y2205266D01*
G01Y2201722D02*
Y2202116D01*
G01Y2198573D02*
Y2198966D01*
G01Y2195423D02*
Y2195817D01*
G01Y2192274D02*
Y2192667D01*
G01Y2189124D02*
Y2189518D01*
G01Y2185974D02*
Y2186368D01*
G01Y2182825D02*
Y2183218D01*
G01Y2176525D02*
Y2176919D01*
G01Y2179675D02*
Y2180069D01*
G01Y2173376D02*
Y2173770D01*
G01Y2170226D02*
Y2170620D01*
G01Y2167077D02*
Y2167470D01*
G01Y2163927D02*
Y2164321D01*
G01X2377721D02*
Y2163927D01*
G01Y2170620D02*
Y2170226D01*
G01Y2167470D02*
Y2167077D01*
G01Y2173770D02*
Y2173376D01*
G01Y2176919D02*
Y2176525D01*
G01Y2180069D02*
Y2179675D01*
G01Y2183218D02*
Y2182825D01*
G01Y2189518D02*
Y2189124D01*
G01Y2186368D02*
Y2185974D01*
G01Y2192667D02*
Y2192274D01*
G01Y2195817D02*
Y2195423D01*
G01Y2202116D02*
Y2201722D01*
G01Y2198966D02*
Y2198573D01*
G01Y2205266D02*
Y2204872D01*
G01Y2208415D02*
Y2208022D01*
G01Y2211565D02*
Y2211171D01*
G01Y2214714D02*
Y2214321D01*
G01Y2221014D02*
Y2220620D01*
G01Y2217864D02*
Y2217470D01*
G01Y2224163D02*
Y2223770D01*
G01X2377549Y2224380D02*
Y2224774D01*
G01Y2219380D02*
Y2219774D01*
G01Y2214380D02*
Y2214774D01*
G01Y2204380D02*
Y2204774D01*
G01Y2199380D02*
Y2199774D01*
G01Y2194380D02*
Y2194774D01*
G01Y2189380D02*
Y2189774D01*
G01Y2184380D02*
Y2184774D01*
G01Y2179380D02*
Y2179774D01*
G01Y2174380D02*
Y2174774D01*
G01Y2164380D02*
Y2164774D01*
G01X2376706Y2224380D02*
Y2224774D01*
G01Y2219380D02*
Y2219774D01*
G01Y2214380D02*
Y2214774D01*
G01Y2204380D02*
Y2204774D01*
G01Y2199380D02*
Y2199774D01*
G01Y2194380D02*
Y2194774D01*
G01Y2189380D02*
Y2189774D01*
G01Y2184380D02*
Y2184774D01*
G01Y2179380D02*
Y2179774D01*
G01Y2174380D02*
Y2174774D01*
G01Y2164380D02*
Y2164774D01*
G01X2376543Y2164321D02*
Y2163927D01*
G01Y2170620D02*
Y2170226D01*
G01Y2167470D02*
Y2167077D01*
G01Y2173770D02*
Y2173376D01*
G01Y2176919D02*
Y2176525D01*
G01Y2180069D02*
Y2179675D01*
G01Y2183218D02*
Y2182825D01*
G01Y2189518D02*
Y2189124D01*
G01Y2186368D02*
Y2185974D01*
G01Y2192667D02*
Y2192274D01*
G01Y2195817D02*
Y2195423D01*
G01Y2202116D02*
Y2201722D01*
G01Y2198966D02*
Y2198573D01*
G01Y2205266D02*
Y2204872D01*
G01Y2208415D02*
Y2208022D01*
G01Y2211565D02*
Y2211171D01*
G01Y2214714D02*
Y2214321D01*
G01Y2221014D02*
Y2220620D01*
G01Y2217864D02*
Y2217470D01*
G01Y2224163D02*
Y2223770D01*
G01X2377721Y2176525D02*
X2377723Y2176487D01*
X2377731Y2176450D01*
X2377744Y2176417D01*
X2377761Y2176386D01*
X2377782Y2176362D01*
X2377806Y2176344D01*
X2377832Y2176333D01*
X2377859Y2176329D01*
G01X2377721Y2173376D02*
X2377723Y2173338D01*
X2377731Y2173301D01*
X2377744Y2173267D01*
X2377761Y2173237D01*
X2377782Y2173212D01*
X2377806Y2173194D01*
X2377832Y2173183D01*
X2377859Y2173179D01*
G01X2377721Y2170226D02*
X2377723Y2170188D01*
X2377731Y2170151D01*
X2377744Y2170117D01*
X2377761Y2170087D01*
X2377782Y2170063D01*
X2377806Y2170045D01*
X2377832Y2170033D01*
X2377859Y2170029D01*
G01X2377721Y2167077D02*
X2377723Y2167038D01*
X2377731Y2167002D01*
X2377744Y2166968D01*
X2377761Y2166937D01*
X2377782Y2166913D01*
X2377806Y2166895D01*
X2377832Y2166884D01*
X2377859Y2166880D01*
G01X2377721Y2163927D02*
X2377723Y2163889D01*
X2377731Y2163852D01*
X2377744Y2163818D01*
X2377761Y2163788D01*
X2377782Y2163763D01*
X2377806Y2163745D01*
X2377832Y2163734D01*
X2377859Y2163730D01*
G01X2380643Y2169774D02*
X2380720Y2170364D01*
G01X2378674Y2164774D02*
X2378752Y2165364D01*
G01X2378674Y2174774D02*
X2378752Y2175364D01*
G01X2378674Y2179774D02*
X2378752Y2180364D01*
G01X2378674Y2184774D02*
X2378752Y2185364D01*
G01X2378674Y2189774D02*
X2378752Y2190364D01*
G01X2378674Y2194774D02*
X2378752Y2195364D01*
G01X2380643Y2209774D02*
X2380720Y2210364D01*
G01X2378674Y2199774D02*
X2378752Y2200364D01*
G01X2378674Y2204774D02*
X2378752Y2205364D01*
G01X2378674Y2214774D02*
X2378752Y2215364D01*
G01Y2220364D02*
X2378674Y2219774D01*
G01Y2224774D02*
X2378752Y2225364D01*
G01X2378234Y2164321D02*
X2378244Y2164419D01*
X2378272Y2164491D01*
X2378310Y2164518D01*
G01X2378234Y2167470D02*
X2378244Y2167569D01*
X2378272Y2167641D01*
X2378310Y2167667D01*
G01X2378234Y2170620D02*
X2378244Y2170718D01*
X2378272Y2170790D01*
X2378310Y2170817D01*
G01X2378234Y2173770D02*
X2378244Y2173868D01*
X2378272Y2173940D01*
X2378310Y2173966D01*
G01X2378234Y2176919D02*
X2378244Y2177018D01*
X2378272Y2177090D01*
X2378310Y2177116D01*
G01X2378234Y2180069D02*
X2378244Y2180167D01*
X2378272Y2180239D01*
X2378310Y2180266D01*
G01X2378234Y2183218D02*
X2378244Y2183317D01*
X2378272Y2183389D01*
X2378310Y2183415D01*
G01X2378234Y2186368D02*
X2378244Y2186466D01*
X2378272Y2186538D01*
X2378310Y2186565D01*
G01X2378234Y2189518D02*
X2378244Y2189616D01*
X2378272Y2189688D01*
X2378310Y2189714D01*
G01X2378234Y2192667D02*
X2378244Y2192766D01*
X2378272Y2192838D01*
X2378310Y2192864D01*
G01X2378234Y2195817D02*
X2378244Y2195915D01*
X2378272Y2195987D01*
X2378310Y2196014D01*
G01X2378234Y2198966D02*
X2378244Y2199065D01*
X2378272Y2199137D01*
X2378310Y2199163D01*
G01X2378234Y2202116D02*
X2378244Y2202214D01*
X2378272Y2202286D01*
X2378310Y2202313D01*
G01X2378234Y2205266D02*
X2378244Y2205364D01*
X2378272Y2205436D01*
X2378310Y2205463D01*
G01X2378234Y2208415D02*
X2378244Y2208514D01*
X2378272Y2208586D01*
X2378310Y2208612D01*
G01X2378234Y2211565D02*
X2378244Y2211663D01*
X2378272Y2211735D01*
X2378310Y2211762D01*
G01X2378234Y2214714D02*
X2378244Y2214813D01*
X2378272Y2214885D01*
X2378310Y2214911D01*
G01X2378234Y2217864D02*
X2378244Y2217962D01*
X2378272Y2218035D01*
X2378310Y2218061D01*
G01X2378234Y2221014D02*
X2378244Y2221112D01*
X2378272Y2221184D01*
X2378310Y2221211D01*
G01X2378234Y2224163D02*
X2378244Y2224262D01*
X2378272Y2224334D01*
X2378310Y2224360D01*
G01X2383155Y2182825D02*
X2383122Y2182726D01*
X2383034Y2182655D01*
X2382908Y2182628D01*
G01X2383155Y2211171D02*
X2383122Y2211072D01*
X2383034Y2211001D01*
X2382908Y2210974D01*
G01X2377549Y2164774D02*
X2377822Y2165364D01*
G01X2379518Y2169774D02*
X2379791Y2170364D01*
G01X2377549Y2174774D02*
X2377822Y2175364D01*
G01X2377549Y2179774D02*
X2377822Y2180364D01*
G01X2377549Y2184774D02*
X2377822Y2185364D01*
G01X2377549Y2189774D02*
X2377822Y2190364D01*
G01X2377549Y2194774D02*
X2377822Y2195364D01*
G01X2377549Y2199774D02*
X2377822Y2200364D01*
G01X2377549Y2204774D02*
X2377822Y2205364D01*
G01X2379518Y2209774D02*
X2379791Y2210364D01*
G01X2377549Y2214774D02*
X2377822Y2215364D01*
G01X2377549Y2219774D02*
X2377822Y2220364D01*
G01X2377549Y2224774D02*
X2377822Y2225364D01*
G01X2377132Y2165364D02*
X2376706Y2164774D01*
G01X2379101Y2170364D02*
X2378674Y2169774D01*
G01X2377132Y2175364D02*
X2376706Y2174774D01*
G01X2377132Y2180364D02*
X2376706Y2179774D01*
G01X2377132Y2185364D02*
X2376706Y2184774D01*
G01X2377132Y2190364D02*
X2376706Y2189774D01*
G01X2377132Y2195364D02*
X2376706Y2194774D01*
G01X2377132Y2200364D02*
X2376706Y2199774D01*
G01X2377132Y2205364D02*
X2376706Y2204774D01*
G01X2382877Y2163789D02*
X2383017Y2163985D01*
X2383155Y2164182D01*
X2383292Y2164380D01*
G01X2384846Y2168789D02*
X2384985Y2168985D01*
X2385123Y2169182D01*
X2385260Y2169380D01*
G01X2382877Y2173789D02*
X2383017Y2173985D01*
X2383155Y2174182D01*
X2383292Y2174380D01*
G01X2382877Y2178789D02*
X2383017Y2178985D01*
X2383155Y2179182D01*
X2383292Y2179380D01*
G01X2382877Y2183789D02*
X2383017Y2183985D01*
X2383155Y2184182D01*
X2383292Y2184380D01*
G01X2382877Y2188789D02*
X2383017Y2188985D01*
X2383155Y2189182D01*
X2383292Y2189380D01*
G01X2382877Y2193789D02*
X2383017Y2193985D01*
X2383155Y2194182D01*
X2383292Y2194380D01*
G01X2382877Y2198789D02*
X2383017Y2198985D01*
X2383155Y2199182D01*
X2383292Y2199380D01*
G01X2382877Y2203789D02*
X2383017Y2203985D01*
X2383155Y2204182D01*
X2383292Y2204380D01*
G01X2384846Y2208789D02*
X2384985Y2208985D01*
X2385123Y2209182D01*
X2385260Y2209380D01*
G01X2382877Y2213789D02*
X2383017Y2213985D01*
X2383155Y2214182D01*
X2383292Y2214380D01*
G01X2382877Y2218789D02*
X2383017Y2218985D01*
X2383155Y2219182D01*
X2383292Y2219380D01*
G01X2382877Y2223789D02*
X2383017Y2223985D01*
X2383155Y2224182D01*
X2383292Y2224380D01*
G01X2379101Y2210364D02*
X2378674Y2209774D01*
G01X2377132Y2215364D02*
X2376706Y2214774D01*
G01X2377132Y2220364D02*
X2376706Y2219774D01*
G01X2377132Y2225364D02*
X2376706Y2224774D01*
G01X2385173Y2228396D02*
X2387142Y2230364D01*
G01X2439504Y2163366D02*
G03X2471000I15748J0D01*
G01X2439504D02*
G03X2471000I15748J0D01*
G01X2439504D02*
G03X2471000I15748J0D01*
G01Y2177146D02*
G03X2439504I-15748J0D01*
G01X2471000D02*
G03X2439504I-15748J0D01*
G01X2471000D02*
G03X2439504I-15748J0D01*
G01Y2163366D02*
Y2177146D01*
G01Y2163366D02*
Y2177146D01*
G01Y2163366D02*
Y2177146D01*
G01X2385173Y2233317D02*
X2387142Y2231348D01*
G01X2390425Y2233317D02*
X2387142D01*
G01X2389110D02*
Y2240482D01*
G01X2390425Y2233317D02*
X2393835Y2235285D01*
G01Y2237018D02*
X2389110Y2241663D01*
G01X2389114Y2240556D02*
X2393835Y2235914D01*
G01X2389142Y2241632D02*
X2389199Y2241492D01*
X2389204Y2241252D01*
G01X2393835Y2235285D02*
Y2237018D01*
G01X2389168Y2240933D02*
X2389114Y2240556D01*
G01X2389168Y2240931D02*
X2389205Y2241255D01*
X2389199Y2241496D01*
X2389142Y2241632D01*
G01X2373007Y2437400D02*
Y2418463D01*
G01X2503553Y-33078D02*
X2504997Y-35027D01*
X2506440Y-36002D01*
X2508606Y-36489D01*
Y-32591D01*
G01X2501388Y-36489D02*
X2500666Y-36002D01*
X2499944Y-35027D01*
Y-34053D01*
X2500666Y-33078D01*
X2501388Y-32591D01*
X2502831D01*
X2503553Y-33078D01*
G01X2508606Y-26744D02*
Y-27232D01*
X2507884D01*
X2508606Y-26744D01*
G01X2510771Y-38437D02*
Y32785D01*
G01Y24124D02*
Y-38437D01*
G01X2508606Y-11154D02*
X2507884Y-12128D01*
X2507162Y-12616D01*
X2505719Y-13103D01*
X2502831D01*
X2501388Y-12616D01*
X2500666Y-12128D01*
X2499944Y-11154D01*
X2500666Y-10180D01*
X2501388Y-9692D01*
X2502831Y-9205D01*
X2505719D01*
X2507162Y-9692D01*
X2507884Y-10180D01*
X2508606Y-11154D01*
G01X2501388Y-20898D02*
X2500666Y-20411D01*
X2499944Y-19437D01*
Y-18462D01*
X2500666Y-17487D01*
X2501388Y-17000D01*
X2502831D01*
X2503553Y-17487D01*
X2504997Y-19437D01*
G01D02*
X2506440Y-20411D01*
X2508606Y-20898D01*
Y-17000D01*
G01X2510771Y61132D02*
Y32785D01*
G01Y41447D02*
Y61132D01*
G01X2629428Y24124D02*
X2506834D01*
G01X2629428Y41447D02*
X2506834D01*
G01X2447312Y170300D02*
X2453087Y173223D01*
G01X2448756Y165428D02*
X2450199Y166403D01*
X2450921D01*
G01X2457378Y189301D02*
Y186378D01*
X2460987Y185891D01*
X2460265Y186865D01*
Y187839D01*
X2460987Y188814D01*
X2461709Y189301D01*
X2463152Y189788D01*
X2464596Y189301D01*
X2465318Y188814D01*
X2466039Y187839D01*
Y186865D01*
X2465318Y185891D01*
X2464596Y185403D01*
G01X2448034Y163479D02*
Y164454D01*
G01X2444425Y189301D02*
Y186378D01*
X2448034Y185891D01*
X2447312Y186865D01*
Y187839D01*
X2448034Y188814D01*
X2448756Y189301D01*
X2450199Y189788D01*
X2451643Y189301D01*
X2452365Y188814D01*
X2453087Y187839D01*
Y186865D01*
X2452365Y185891D01*
X2451643Y185403D01*
G01X2445147Y162505D02*
X2444425Y163479D01*
Y164454D01*
X2445147Y165428D01*
X2445869Y165915D01*
X2446590D01*
X2447312Y165428D01*
X2448034Y164454D01*
X2448756Y165428D01*
G01X2450921Y197584D02*
X2452365Y196609D01*
X2453087Y195635D01*
Y194660D01*
X2452365Y193686D01*
X2451643Y193199D01*
G01X2458821Y177608D02*
X2458100Y178095D01*
X2457378Y179070D01*
Y180044D01*
X2458100Y181019D01*
X2458821Y181506D01*
X2460265D01*
X2460987Y181019D01*
X2461709Y180044D01*
X2462430Y179070D01*
X2463874Y178095D01*
X2466039Y177608D01*
Y181506D01*
G01X2445869Y177608D02*
X2445147Y178095D01*
X2444425Y179070D01*
Y180044D01*
X2445147Y181019D01*
X2445869Y181506D01*
X2447312D01*
X2448034Y181019D01*
X2448756Y180044D01*
X2449478Y179070D01*
X2450921Y178095D01*
X2453087Y177608D01*
Y181506D01*
G01X2450921Y166403D02*
X2452365Y165428D01*
X2453087Y164454D01*
Y163479D01*
X2452365Y162505D01*
X2451643Y162018D01*
G01X2453087Y170300D02*
X2447312Y173223D01*
G01X2488126Y196609D02*
X2489569Y197584D01*
X2490291D01*
X2491013Y197096D01*
X2491735Y196609D01*
X2492457Y195635D01*
Y194660D01*
X2491735Y193686D01*
X2491013Y193199D01*
G01X2485239Y177608D02*
X2484517Y178095D01*
X2483795Y179070D01*
Y180044D01*
X2484517Y181019D01*
X2485239Y181506D01*
X2486682D01*
X2487404Y181019D01*
X2488126Y180044D01*
X2488848Y179070D01*
X2490291Y178095D01*
X2492457Y177608D01*
Y181506D01*
G01X2489569Y185403D02*
X2488126Y185891D01*
X2487404Y187352D01*
X2488126Y188814D01*
X2489569Y189301D01*
X2491013Y188814D01*
X2491735Y188327D01*
X2492457Y187352D01*
X2491735Y186378D01*
X2491013Y185891D01*
X2489569Y185403D01*
X2486682D01*
X2485239Y185891D01*
X2484517Y186378D01*
X2483795Y187352D01*
X2484517Y188327D01*
X2485239Y188814D01*
G01X2445147Y193686D02*
X2444425Y194660D01*
Y195635D01*
X2445147Y196609D01*
X2445869Y197096D01*
X2446590D01*
X2447312Y196609D01*
X2448034Y195635D01*
X2448756Y196609D01*
G01X2463152Y193199D02*
X2461709Y193686D01*
X2460987Y195148D01*
X2461709Y196609D01*
X2463152Y197096D01*
X2464596Y196609D01*
X2465318Y196122D01*
X2466039Y195148D01*
X2465318Y194173D01*
X2464596Y193686D01*
X2463152Y193199D01*
X2460265D01*
X2458821Y193686D01*
X2458100Y194173D01*
X2457378Y195148D01*
X2458100Y196122D01*
X2458821Y196609D01*
G01X2448756D02*
X2450199Y197584D01*
X2450921D01*
G01X2453087Y218533D02*
X2452365Y217559D01*
X2451643Y217072D01*
X2450199Y216585D01*
X2447312D01*
X2445869Y217072D01*
X2445147Y217559D01*
X2444425Y218533D01*
X2445147Y219508D01*
X2445869Y219995D01*
X2447312Y220482D01*
X2450199D01*
X2451643Y219995D01*
X2452365Y219508D01*
X2453087Y218533D01*
G01Y202943D02*
Y202456D01*
X2452365D01*
X2453087Y202943D01*
G01X2448034Y194660D02*
Y195635D01*
G01X2444425Y212687D02*
Y209764D01*
X2448034Y209276D01*
X2447312Y210251D01*
Y211225D01*
X2448034Y212200D01*
X2448756Y212687D01*
X2450199Y213174D01*
X2451643Y212687D01*
X2452365Y212200D01*
X2453087Y211225D01*
Y210251D01*
X2452365Y209276D01*
X2451643Y208789D01*
G01X2460265Y220482D02*
X2461709Y219995D01*
X2462430Y218533D01*
X2461709Y217072D01*
X2460265Y216585D01*
X2458821Y217072D01*
X2458100Y217559D01*
X2457378Y218533D01*
X2458100Y219508D01*
X2458821Y219995D01*
X2460265Y220482D01*
X2463152D01*
X2464596Y219995D01*
X2465318Y219508D01*
X2466039Y218533D01*
X2465318Y217559D01*
X2464596Y217072D01*
G01X2466039Y210738D02*
X2462430Y211225D01*
X2460265Y211713D01*
X2458821Y212200D01*
X2457378Y212687D01*
Y208789D01*
G01X2455252Y419281D02*
Y226762D01*
G01X2484517Y193686D02*
X2483795Y194660D01*
Y195635D01*
X2484517Y196609D01*
X2485239Y197096D01*
X2485961D01*
X2486682Y196609D01*
X2487404Y195635D01*
X2488126Y196609D01*
G01X2492457Y218533D02*
X2491735Y217559D01*
X2491013Y217072D01*
X2489569Y216585D01*
X2486682D01*
X2485239Y217072D01*
X2484517Y217559D01*
X2483795Y218533D01*
X2484517Y219508D01*
X2485239Y219995D01*
X2486682Y220482D01*
X2489569D01*
X2491013Y219995D01*
X2491735Y219508D01*
X2492457Y218533D01*
G01Y202943D02*
Y202456D01*
X2491735D01*
X2492457Y202943D01*
G01X2487404Y194660D02*
Y195635D01*
G01X2483795Y212687D02*
Y209764D01*
X2487404Y209276D01*
X2486682Y210251D01*
Y211225D01*
X2487404Y212200D01*
X2488126Y212687D01*
X2489569Y213174D01*
X2491013Y212687D01*
X2491735Y212200D01*
X2492457Y211225D01*
Y210251D01*
X2491735Y209276D01*
X2491013Y208789D01*
G01X2466039Y202943D02*
Y202456D01*
X2465318D01*
X2466039Y202943D01*
G01X2468205Y313691D02*
Y226762D01*
G01X2494622Y273612D02*
Y226762D01*
G01Y1698494D02*
Y277549D01*
G01X2490685Y273612D02*
G03X2494622Y277549I0J3937D01*
G01X2472496Y317628D02*
G03I-4291J0D01*
G01X2471943Y319735D02*
X2528928Y351855D01*
G01X2472142Y317628D02*
X2521430D01*
G01X2461256Y445683D02*
G03I-984J0D01*
G01X2461155Y436988D02*
G03X2449349I-5903J0D01*
G01X2461157D02*
G03X2449346I-5906J0D01*
G01X2463126D02*
G03X2447378I-7874J0D01*
G01X2469031D02*
G03X2441472I-13780J0D01*
G01X2461155Y432855D02*
G03X2462281Y430099I3937J0D01*
G01X2448223D02*
G03X2462281I7029J-6890D01*
G01X2446197Y436988D02*
G03I-985J0D01*
G01X2451216Y445683D02*
G03I-984J0D01*
G01X2447542Y442008D02*
G03I-984J0D01*
G01X2448223Y430099D02*
G03X2449349Y432855I-2811J2757D01*
G01X2461157Y436988D02*
Y434626D01*
G01X2461155Y432855D02*
Y436988D01*
G01X2449349D02*
Y432855D01*
G01X2449346Y434626D02*
Y436988D01*
G01X2447378D02*
Y434626D01*
G01X2441472Y436988D02*
Y434626D01*
G01X2461157D02*
X2469031D01*
G01X2441472D02*
X2449346D01*
G01X2459189Y423218D02*
X2575488D01*
G01X2464930Y442008D02*
G03I-984J0D01*
G01X2466275Y436988D02*
G03I-984J0D01*
G01X2471000Y423209D02*
Y436988D01*
G01Y423209D02*
Y436988D01*
G01Y423209D02*
Y436988D01*
G01X2469031Y434626D02*
Y436988D01*
G01X2463126Y434626D02*
Y436988D01*
G01X2461256Y969305D02*
G03I-984J0D01*
G01X2461155Y960610D02*
G03X2449349I-5903J0D01*
G01X2461157D02*
G03X2449346I-5906J0D01*
G01X2463126D02*
G03X2447378I-7874J0D01*
G01X2469031D02*
G03X2441472I-13780J0D01*
G01X2461155Y956477D02*
G03X2462281Y953721I3937J0D01*
G01X2448223D02*
G03X2462281I7029J-6890D01*
G01X2446197Y960610D02*
G03I-985J0D01*
G01X2451216Y969305D02*
G03I-984J0D01*
G01X2447542Y965630D02*
G03I-984J0D01*
G01X2448223Y953721D02*
G03X2449349Y956477I-2811J2757D01*
G01X2461157Y960610D02*
Y958248D01*
G01X2461155Y956477D02*
Y960610D01*
G01X2449349D02*
Y956477D01*
G01X2449346Y958248D02*
Y960610D01*
G01X2447378D02*
Y958248D01*
G01X2441472Y960610D02*
Y958248D01*
G01X2461157D02*
X2469031D01*
G01X2441472D02*
X2449346D01*
G01X2459189Y946840D02*
X2575488D01*
G01X2464930Y965630D02*
G03I-984J0D01*
G01X2466275Y960610D02*
G03I-984J0D01*
G01X2471000Y946831D02*
Y960610D01*
G01Y946831D02*
Y960610D01*
G01Y946831D02*
Y960610D01*
G01X2469031Y958248D02*
Y960610D01*
G01X2463126Y958248D02*
Y960610D01*
G01X2461155Y1356280D02*
G03X2449349I-5903J0D01*
G01X2461157D02*
G03X2449346I-5906J0D01*
G01X2463126D02*
G03X2447378I-7874J0D01*
G01X2469031D02*
G03X2441472I-13780J0D01*
G01X2461155Y1352146D02*
G03X2462281Y1349390I3937J0D01*
G01X2448223D02*
G03X2462281I7029J-6890D01*
G01X2446197Y1356280D02*
G03I-985J0D01*
G01X2448223Y1349390D02*
G03X2449349Y1352146I-2811J2757D01*
G01X2461157Y1356280D02*
Y1353917D01*
G01X2461155Y1352146D02*
Y1356280D01*
G01X2449349D02*
Y1352146D01*
G01X2449346Y1353917D02*
Y1356280D01*
G01X2447378D02*
Y1353917D01*
G01X2441472Y1356280D02*
Y1353917D01*
G01X2461157D02*
X2469031D01*
G01X2441472D02*
X2449346D01*
G01X2459189Y1342510D02*
X2575488D01*
G01X2466275Y1356280D02*
G03I-984J0D01*
G01X2471000Y1342500D02*
Y1356280D01*
G01Y1342500D02*
Y1356280D01*
G01Y1342500D02*
Y1356280D01*
G01X2469031Y1353917D02*
Y1356280D01*
G01X2463126Y1353917D02*
Y1356280D01*
G01X2461256Y1364974D02*
G03I-984J0D01*
G01X2451216D02*
G03I-984J0D01*
G01X2447542Y1361299D02*
G03I-984J0D01*
G01X2464930D02*
G03I-984J0D01*
G01X2455119Y1719418D02*
X2455199Y1719246D01*
G01X2453938Y1719418D02*
X2454018Y1719246D01*
G01X2455119Y1709418D02*
X2455199Y1709246D01*
G01X2453938Y1709418D02*
X2454018Y1709246D01*
G01X2455197Y1719249D02*
X2455305Y1719097D01*
G01X2454016Y1719249D02*
X2454124Y1719097D01*
G01X2455197Y1709249D02*
X2455305Y1709097D01*
G01X2454016Y1709249D02*
X2454124Y1709097D01*
G01X2450973Y1710195D02*
X2450722Y1710524D01*
G01X2451224Y1710606D02*
X2451392Y1710442D01*
G01X2455436Y1718973D02*
X2455305Y1719097D01*
G01X2454255Y1718973D02*
X2454124Y1719097D01*
G01X2455436Y1708973D02*
X2455305Y1709097D01*
G01X2454255Y1708973D02*
X2454124Y1709097D01*
G01X2452230Y1709211D02*
X2452816Y1708719D01*
G01X2452146D02*
X2451559Y1709211D01*
G01X2451308Y1709949D02*
X2450973Y1710195D01*
G01X2455433Y1718975D02*
X2455583Y1718883D01*
G01X2454252Y1718975D02*
X2454401Y1718883D01*
G01X2455433Y1708975D02*
X2455583Y1708883D01*
G01X2454252Y1708975D02*
X2454401Y1708883D01*
G01X2450722Y1710524D02*
X2450638Y1710934D01*
G01X2455071Y1719602D02*
X2455120Y1719415D01*
G01X2453890Y1719602D02*
X2453939Y1719415D01*
G01X2455071Y1709602D02*
X2455120Y1709415D01*
G01X2453890Y1709602D02*
X2453939Y1709415D01*
G01X2451141Y1710852D02*
X2451224Y1710606D01*
G01X2455580Y1718885D02*
X2455742Y1718828D01*
G01X2454399Y1718885D02*
X2454561Y1718828D01*
G01X2455580Y1708885D02*
X2455742Y1708828D01*
G01X2454399Y1708885D02*
X2454561Y1708828D01*
G01X2451392Y1710442D02*
X2451643Y1710360D01*
G01X2451559Y1709867D02*
X2451308Y1709949D01*
G01X2455739Y1718828D02*
X2455907Y1718809D01*
G01X2454558Y1718828D02*
X2454726Y1718809D01*
G01X2455739Y1708828D02*
X2455907Y1708809D01*
G01X2454558Y1708828D02*
X2454726Y1708809D01*
G01X2460764Y1713061D02*
Y1708809D01*
G01Y1723061D02*
Y1718809D01*
G01X2459583Y1713061D02*
Y1708809D01*
G01Y1723061D02*
Y1718809D01*
G01X2455055Y1712077D02*
Y1709793D01*
G01Y1722077D02*
Y1719793D01*
G01X2453874Y1712077D02*
Y1709793D01*
G01Y1722077D02*
Y1719793D01*
G01X2452816Y1708719D02*
Y1708227D01*
G01Y1712902D02*
Y1710934D01*
G01X2452397Y1710852D02*
Y1712410D01*
G01X2451141D02*
Y1710852D01*
G01X2450638Y1710934D02*
Y1712410D01*
G01X2448879D02*
Y1712902D01*
G01Y1708227D02*
Y1708719D01*
G01X2455072Y1719599D02*
X2455055Y1719793D01*
G01X2455072Y1709599D02*
X2455055Y1709793D01*
G01X2453891Y1719599D02*
X2453874Y1719793D01*
G01X2453891Y1709599D02*
X2453874Y1709793D01*
G01X2455055Y1719793D02*
X2453874D01*
G01X2483598Y1718809D02*
X2454726D01*
G01X2483598Y1713061D02*
X2454726D01*
G01X2448879Y1712902D02*
X2452816D01*
G01X2452397Y1712410D02*
X2451141D01*
G01X2450638D02*
X2448879D01*
G01X2455055Y1712077D02*
X2453874D01*
G01X2451643Y1710360D02*
X2451895D01*
G01Y1709867D02*
X2451559D01*
G01X2455055Y1709793D02*
X2453874D01*
G01X2451559Y1709211D02*
X2452230D01*
G01X2483598Y1708809D02*
X2454726D01*
G01X2448879Y1708719D02*
X2452146D01*
G01X2452816Y1708227D02*
X2448879D01*
G01X2455072Y1712271D02*
X2455055Y1712077D01*
G01X2453891Y1712271D02*
X2453874Y1712077D01*
G01X2454558Y1713042D02*
X2454726Y1713061D01*
G01X2455739Y1713042D02*
X2455907Y1713061D01*
G01X2455120Y1712455D02*
X2455071Y1712268D01*
G01X2453939Y1712455D02*
X2453890Y1712268D01*
G01X2452816Y1710934D02*
X2452732Y1710524D01*
G01X2455199Y1712624D02*
X2455119Y1712452D01*
G01X2454018Y1712624D02*
X2453938Y1712452D01*
G01X2452313Y1710606D02*
X2452397Y1710852D01*
G01X2452732Y1710524D02*
X2452481Y1710195D01*
G01X2455197Y1712621D02*
X2455305Y1712773D01*
G01X2454016Y1712621D02*
X2454124Y1712773D01*
G01X2452146Y1710442D02*
X2452313Y1710606D01*
G01X2455436Y1712896D02*
X2455305Y1712773D01*
G01X2454255Y1712896D02*
X2454124Y1712773D01*
G01X2455583Y1712987D02*
X2455433Y1712895D01*
G01X2454401Y1712987D02*
X2454252Y1712895D01*
G01X2452481Y1710195D02*
X2452146Y1709949D01*
G01D02*
X2451895Y1709867D01*
G01Y1710360D02*
X2452146Y1710442D01*
G01X2455742Y1713042D02*
X2455580Y1712985D01*
G01X2454561Y1713042D02*
X2454399Y1712985D01*
G01X2497929Y1715403D02*
G03X2498323Y1715010I394J1D01*
G01Y1716860D02*
G03X2497929Y1716466I0J-394D01*
G01X2489307Y1720856D02*
G03X2488323Y1719872I0J-984D01*
G01Y1711998D02*
G03X2489307Y1711014I984J0D01*
G01X2496945D02*
G03X2497929Y1711998I0J984D01*
G01Y1719872D02*
G03X2496945Y1720856I-984J0D01*
G01X2493205Y1674872D02*
G03X2495173Y1676840I0J1968D01*
G01X2467614Y1704400D02*
G03X2465646Y1702431I1J-1969D01*
G01Y1676840D02*
G03X2467614Y1674872I1968J0D01*
G01X2480449Y1707903D02*
G03X2485921Y1702431I5472J0D01*
G01X2487732Y1689636D02*
G03I-7283J0D01*
G01D02*
G03I-7283J0D01*
G01X2488126D02*
G03I-7677J0D01*
G01X2497846Y1715053D02*
X2497881Y1714940D01*
G01X2497880Y1714942D02*
X2497935Y1714839D01*
G01X2497934Y1714840D02*
X2498008Y1714750D01*
G01X2490685Y1702431D02*
X2494622Y1698494D01*
G01X2480449Y1706368D02*
X2482417Y1704400D01*
G01X2497893Y1714715D02*
X2497833Y1714774D01*
G01X2498098Y1714675D02*
X2498008Y1714750D01*
G01X2497892Y1714716D02*
X2497960Y1714666D01*
G01X2498097Y1714676D02*
X2498200Y1714621D01*
G01X2497958Y1714667D02*
X2498032Y1714628D01*
G01X2497685Y1715167D02*
X2497701Y1715023D01*
X2497752Y1714892D01*
X2497835Y1714774D01*
G01X2498030Y1714629D02*
X2498109Y1714600D01*
G01X2498198Y1714622D02*
X2498310Y1714588D01*
G01X2498108Y1714600D02*
X2498190Y1714582D01*
G01X2497847Y1715051D02*
X2497835Y1715167D01*
G01X2498308Y1714588D02*
X2498425Y1714577D01*
G01X2498188Y1714583D02*
X2498272Y1714577D01*
G01X2497847Y1716819D02*
X2497835Y1716703D01*
G01X2501866Y1715010D02*
Y1716860D01*
G01X2501079Y1959045D02*
Y1702825D01*
G01X2497929Y1719872D02*
Y1711998D01*
G01X2497835Y1715167D02*
Y1716703D01*
G01X2497685D02*
Y1715167D01*
G01X2497421Y1744577D02*
Y1707293D01*
G01X2497269Y1714774D02*
Y1707293D01*
G01Y1724774D02*
Y1717096D01*
G01X2497142Y1744577D02*
Y1707293D01*
G01X2495173Y1704400D02*
Y1676840D01*
G01X2492079Y1718888D02*
Y1712982D01*
G01X2491275Y1718888D02*
Y1712982D01*
G01X2489520D02*
Y1718888D01*
G01X2488716D02*
Y1712982D01*
G01X2488323Y1719872D02*
Y1711998D01*
G01X2486354Y1718888D02*
Y1712982D01*
G01X2484386Y1717096D02*
Y1714774D01*
G01X2483598Y1708809D02*
Y1706900D01*
G01Y1718809D02*
Y1713061D01*
G01X2482811D02*
Y1708809D01*
G01Y1723061D02*
Y1718809D01*
G01X2481630Y1713061D02*
Y1708809D01*
G01Y1723061D02*
Y1718809D01*
G01X2480842Y1706900D02*
Y1708061D01*
G01X2480449Y1707903D02*
Y1883514D01*
G01Y1885777D02*
Y1704400D01*
G01X2479183Y1713061D02*
Y1708809D01*
G01Y1723061D02*
Y1718809D01*
G01X2478002Y1713061D02*
Y1708809D01*
G01Y1723061D02*
Y1718809D01*
G01X2476821Y1713061D02*
Y1708809D01*
G01Y1723061D02*
Y1718809D01*
G01X2472884Y1713061D02*
Y1708809D01*
G01Y1723061D02*
Y1718809D01*
G01X2472281Y1713061D02*
Y1708809D01*
G01Y1723061D02*
Y1718809D01*
G01X2471678Y1713061D02*
Y1708809D01*
G01Y1723061D02*
Y1718809D01*
G01X2469583Y1674872D02*
Y1704400D01*
G01X2465646Y1702431D02*
Y1676840D01*
G01X2462556Y1713061D02*
Y1708809D01*
G01Y1723061D02*
Y1718809D01*
G01X2461953Y1713061D02*
Y1708809D01*
G01Y1723061D02*
Y1718809D01*
G01X2496945Y1720856D02*
X2480449D01*
G01Y1718888D02*
X2492079D01*
G01X2501079D02*
X2497929D01*
G01X2534012Y1717293D02*
X2498272D01*
G01X2501079Y1717096D02*
X2480449D01*
G01X2540449Y1716860D02*
X2498323D01*
G01X2497835Y1716703D02*
X2497685D01*
G01X2497835Y1715167D02*
X2497685D01*
G01X2540449Y1715010D02*
X2498323D01*
G01X2501079Y1714774D02*
X2480449D01*
G01X2534012Y1714577D02*
X2498272D01*
G01X2480449Y1712982D02*
X2492079D01*
G01X2501079D02*
X2497929D01*
G01X2496945Y1711014D02*
X2480449D01*
G01X2501079Y1708061D02*
X2480449D01*
G01X2534012Y1707293D02*
X2480449D01*
G01X2501079Y1706900D02*
X2480842D01*
G01X2540449Y1706860D02*
X2501079D01*
G01X2480449Y1704400D02*
X2467614D01*
G01X2495173D02*
X2482417D01*
G01X2535724Y1702825D02*
X2501079D01*
G01X2490685Y1702431D02*
X2485921D01*
G01X2540449Y1696919D02*
X2495173D01*
G01X2540449Y1694951D02*
X2495173D01*
G01X2467614Y1674872D02*
X2493205D01*
G01X2498188Y1717287D02*
X2498272Y1717293D01*
G01X2498308Y1717282D02*
X2498425Y1717293D01*
G01X2497142Y1707293D02*
X2493205Y1706900D01*
G01X2498190Y1717287D02*
X2498108Y1717270D01*
G01X2497881Y1716930D02*
X2497846Y1716817D01*
G01X2497935Y1717031D02*
X2497880Y1716928D01*
G01X2497835Y1717096D02*
X2497752Y1716978D01*
X2497701Y1716847D01*
X2497685Y1716703D01*
G01X2497934Y1717029D02*
X2498008Y1717120D01*
G01X2497893Y1717155D02*
X2497833Y1717096D01*
G01X2480842Y1706900D02*
X2480449Y1706506D01*
G01X2497960Y1717203D02*
X2497892Y1717154D01*
G01X2498098Y1717195D02*
X2498008Y1717120D01*
G01X2498200Y1717249D02*
X2498097Y1717193D01*
G01X2498032Y1717242D02*
X2497958Y1717202D01*
G01X2498310Y1717282D02*
X2498198Y1717248D01*
G01X2498109Y1717270D02*
X2498030Y1717241D01*
G01X2483598Y1723061D02*
X2454726D01*
G01X2455055Y1722077D02*
X2453874D01*
G01X2454558Y1723042D02*
X2454726Y1723061D01*
G01X2455739Y1723042D02*
X2455907Y1723061D01*
G01X2455072Y1722271D02*
X2455055Y1722077D01*
G01X2453891Y1722271D02*
X2453874Y1722077D01*
G01X2455120Y1722455D02*
X2455071Y1722268D01*
G01X2453939Y1722455D02*
X2453890Y1722268D01*
G01X2455199Y1722624D02*
X2455119Y1722452D01*
G01X2454018Y1722624D02*
X2453938Y1722452D01*
G01X2455197Y1722621D02*
X2455305Y1722773D01*
G01X2454016Y1722621D02*
X2454124Y1722773D01*
G01X2455436Y1722896D02*
X2455305Y1722773D01*
G01X2454255Y1722896D02*
X2454124Y1722773D01*
G01X2455583Y1722987D02*
X2455433Y1722895D01*
G01X2454401Y1722987D02*
X2454252Y1722895D01*
G01X2455742Y1723042D02*
X2455580Y1722985D01*
G01X2454561Y1723042D02*
X2454399Y1722985D01*
G01X2454255Y1788973D02*
X2454124Y1789097D01*
G01X2455436Y1778973D02*
X2455305Y1779097D01*
G01X2454255Y1778973D02*
X2454124Y1779097D01*
G01X2455433Y1788975D02*
X2455580Y1788885D01*
X2455742Y1788828D01*
G01X2455119Y1789418D02*
X2455199Y1789246D01*
G01X2453938Y1789418D02*
X2454018Y1789246D01*
G01X2455119Y1779418D02*
X2455199Y1779246D01*
G01X2453938Y1779418D02*
X2454018Y1779246D01*
G01X2455119Y1769418D02*
X2455199Y1769246D01*
G01X2453938Y1769418D02*
X2454018Y1769246D01*
G01X2455119Y1759418D02*
X2455199Y1759246D01*
G01X2453938Y1759418D02*
X2454018Y1759246D01*
G01X2455119Y1749418D02*
X2455199Y1749246D01*
G01X2453938Y1749418D02*
X2454018Y1749246D01*
G01X2455119Y1739418D02*
X2455199Y1739246D01*
G01X2453938Y1739418D02*
X2454018Y1739246D01*
G01X2455119Y1729418D02*
X2455199Y1729246D01*
G01X2453938Y1729418D02*
X2454018Y1729246D01*
G01X2455197Y1789249D02*
X2455305Y1789097D01*
G01X2454016Y1789249D02*
X2454124Y1789097D01*
G01X2455197Y1779249D02*
X2455305Y1779097D01*
G01X2454016Y1779249D02*
X2454124Y1779097D01*
G01X2455197Y1769249D02*
X2455305Y1769097D01*
G01X2454016Y1769249D02*
X2454124Y1769097D01*
G01X2455197Y1759249D02*
X2455305Y1759097D01*
G01X2454016Y1759249D02*
X2454124Y1759097D01*
G01X2455197Y1749249D02*
X2455305Y1749097D01*
G01X2454016Y1749249D02*
X2454124Y1749097D01*
G01X2455197Y1739249D02*
X2455305Y1739097D01*
G01X2454016Y1739249D02*
X2454124Y1739097D01*
G01X2455197Y1729249D02*
X2455305Y1729097D01*
G01X2454016Y1729249D02*
X2454124Y1729097D01*
G01X2455436Y1768973D02*
X2455305Y1769097D01*
G01X2454255Y1768973D02*
X2454124Y1769097D01*
G01X2455436Y1758973D02*
X2455305Y1759097D01*
G01X2454255Y1758973D02*
X2454124Y1759097D01*
G01X2455436Y1748973D02*
X2455305Y1749097D01*
G01X2454255Y1748973D02*
X2454124Y1749097D01*
G01X2455436Y1738973D02*
X2455305Y1739097D01*
G01X2454255Y1738973D02*
X2454124Y1739097D01*
G01X2455436Y1728973D02*
X2455305Y1729097D01*
G01X2454255Y1728973D02*
X2454124Y1729097D01*
G01X2454252Y1788975D02*
X2454401Y1788883D01*
G01X2455433Y1778975D02*
X2455583Y1778883D01*
G01X2454252Y1778975D02*
X2454401Y1778883D01*
G01X2455433Y1768975D02*
X2455583Y1768883D01*
G01X2454252Y1768975D02*
X2454401Y1768883D01*
G01X2455433Y1758975D02*
X2455583Y1758883D01*
G01X2454252Y1758975D02*
X2454401Y1758883D01*
G01X2455433Y1748975D02*
X2455583Y1748883D01*
G01X2454252Y1748975D02*
X2454401Y1748883D01*
G01X2455433Y1738975D02*
X2455583Y1738883D01*
G01X2454252Y1738975D02*
X2454401Y1738883D01*
G01X2455433Y1728975D02*
X2455583Y1728883D01*
G01X2454252Y1728975D02*
X2454401Y1728883D01*
G01X2455583Y1788883D02*
X2455436Y1788973D01*
X2455305Y1789097D01*
G01X2454399Y1788885D02*
X2454561Y1788828D01*
G01X2455580Y1778885D02*
X2455742Y1778828D01*
G01X2454399Y1778885D02*
X2454561Y1778828D01*
G01X2455580Y1768885D02*
X2455742Y1768828D01*
G01X2454399Y1768885D02*
X2454561Y1768828D01*
G01X2455580Y1758885D02*
X2455742Y1758828D01*
G01X2454399Y1758885D02*
X2454561Y1758828D01*
G01X2455071Y1789602D02*
X2455120Y1789415D01*
G01X2453890Y1789602D02*
X2453939Y1789415D01*
G01X2455071Y1779602D02*
X2455120Y1779415D01*
G01X2453890Y1779602D02*
X2453939Y1779415D01*
G01X2455071Y1769602D02*
X2455120Y1769415D01*
G01X2453890Y1769602D02*
X2453939Y1769415D01*
G01X2455071Y1759602D02*
X2455120Y1759415D01*
G01X2453890Y1759602D02*
X2453939Y1759415D01*
G01X2455071Y1749602D02*
X2455120Y1749415D01*
G01X2453890Y1749602D02*
X2453939Y1749415D01*
G01X2455071Y1739602D02*
X2455120Y1739415D01*
G01X2453890Y1739602D02*
X2453939Y1739415D01*
G01X2455071Y1729602D02*
X2455120Y1729415D01*
G01X2453890Y1729602D02*
X2453939Y1729415D01*
G01X2455580Y1748885D02*
X2455742Y1748828D01*
G01X2454399Y1748885D02*
X2454561Y1748828D01*
G01X2455580Y1738885D02*
X2455742Y1738828D01*
G01X2454399Y1738885D02*
X2454561Y1738828D01*
G01X2455580Y1728885D02*
X2455742Y1728828D01*
G01X2454399Y1728885D02*
X2454561Y1728828D01*
G01X2455739Y1788828D02*
X2455907Y1788809D01*
G01X2454558Y1788828D02*
X2454726Y1788809D01*
G01X2455739Y1778828D02*
X2455907Y1778809D01*
G01X2454558Y1778828D02*
X2454726Y1778809D01*
G01X2455739Y1768828D02*
X2455907Y1768809D01*
G01X2454558Y1768828D02*
X2454726Y1768809D01*
G01X2455739Y1758828D02*
X2455907Y1758809D01*
G01X2454558Y1758828D02*
X2454726Y1758809D01*
G01X2455739Y1748828D02*
X2455907Y1748809D01*
G01X2454558Y1748828D02*
X2454726Y1748809D01*
G01X2455739Y1738828D02*
X2455907Y1738809D01*
G01X2454558Y1738828D02*
X2454726Y1738809D01*
G01X2455739Y1728828D02*
X2455907Y1728809D01*
G01X2454558Y1728828D02*
X2454726Y1728809D01*
G01X2483598Y1793061D02*
X2454726D01*
G01X2455055Y1792077D02*
X2453874D01*
G01X2455055Y1789793D02*
X2453874D01*
G01X2483598Y1788809D02*
X2454726D01*
G01X2483598Y1783061D02*
X2454726D01*
G01X2455055Y1782077D02*
X2453874D01*
G01X2455055Y1779793D02*
X2453874D01*
G01X2483598Y1778809D02*
X2454726D01*
G01X2483598Y1773061D02*
X2454726D01*
G01X2455055Y1772077D02*
X2453874D01*
G01X2455055Y1769793D02*
X2453874D01*
G01X2483598Y1768809D02*
X2454726D01*
G01X2483598Y1763061D02*
X2454726D01*
G01X2455055Y1762077D02*
X2453874D01*
G01X2455055Y1759793D02*
X2453874D01*
G01X2483598Y1758809D02*
X2454726D01*
G01X2483598Y1753061D02*
X2454726D01*
G01X2455055Y1752077D02*
X2453874D01*
G01X2455055Y1749793D02*
X2453874D01*
G01X2483598Y1748809D02*
X2454726D01*
G01X2483598Y1743061D02*
X2454726D01*
G01X2455055Y1742077D02*
X2453874D01*
G01X2455055Y1739793D02*
X2453874D01*
G01X2483598Y1738809D02*
X2454726D01*
G01X2460764Y1733061D02*
Y1728809D01*
G01Y1743061D02*
Y1738809D01*
G01Y1753061D02*
Y1748809D01*
G01Y1763061D02*
Y1758809D01*
G01Y1773061D02*
Y1768809D01*
G01Y1783061D02*
Y1778809D01*
G01Y1793061D02*
Y1788809D01*
G01X2459583Y1733061D02*
Y1728809D01*
G01Y1743061D02*
Y1738809D01*
G01Y1753061D02*
Y1748809D01*
G01Y1763061D02*
Y1758809D01*
G01Y1773061D02*
Y1768809D01*
G01Y1783061D02*
Y1778809D01*
G01Y1793061D02*
Y1788809D01*
G01X2455055Y1732077D02*
Y1729793D01*
G01Y1742077D02*
Y1739793D01*
G01Y1752077D02*
Y1749793D01*
G01Y1762077D02*
Y1759793D01*
G01Y1772077D02*
Y1769793D01*
G01Y1782077D02*
Y1779793D01*
G01Y1792077D02*
Y1789793D01*
G01X2453874Y1732077D02*
Y1729793D01*
G01Y1742077D02*
Y1739793D01*
G01Y1752077D02*
Y1749793D01*
G01Y1762077D02*
Y1759793D01*
G01Y1772077D02*
Y1769793D01*
G01Y1782077D02*
Y1779793D01*
G01Y1792077D02*
Y1789793D01*
G01X2455072Y1789599D02*
X2455055Y1789793D01*
G01X2455072Y1779599D02*
X2455055Y1779793D01*
G01X2453891Y1789599D02*
X2453874Y1789793D01*
G01X2455072Y1769599D02*
X2455055Y1769793D01*
G01X2453891Y1779599D02*
X2453874Y1779793D01*
G01X2455072Y1759599D02*
X2455055Y1759793D01*
G01X2453891Y1769599D02*
X2453874Y1769793D01*
G01X2455072Y1749599D02*
X2455055Y1749793D01*
G01X2453891Y1759599D02*
X2453874Y1759793D01*
G01X2455072Y1739599D02*
X2455055Y1739793D01*
G01X2453891Y1749599D02*
X2453874Y1749793D01*
G01X2455072Y1729599D02*
X2455055Y1729793D01*
G01X2453891Y1739599D02*
X2453874Y1739793D01*
G01X2453891Y1729599D02*
X2453874Y1729793D01*
G01X2483598Y1733061D02*
X2454726D01*
G01X2455055Y1732077D02*
X2453874D01*
G01X2455055Y1729793D02*
X2453874D01*
G01X2483598Y1728809D02*
X2454726D01*
G01X2454558Y1793042D02*
X2454726Y1793061D01*
G01X2455739Y1793042D02*
X2455907Y1793061D01*
G01X2454558Y1783042D02*
X2454726Y1783061D01*
G01X2455739Y1783042D02*
X2455907Y1783061D01*
G01X2454558Y1773042D02*
X2454726Y1773061D01*
G01X2455739Y1773042D02*
X2455907Y1773061D01*
G01X2454558Y1763042D02*
X2454726Y1763061D01*
G01X2455739Y1763042D02*
X2455907Y1763061D01*
G01X2454558Y1753042D02*
X2454726Y1753061D01*
G01X2455739Y1753042D02*
X2455907Y1753061D01*
G01X2454558Y1743042D02*
X2454726Y1743061D01*
G01X2455739Y1743042D02*
X2455907Y1743061D01*
G01X2454558Y1733042D02*
X2454726Y1733061D01*
G01X2455739Y1733042D02*
X2455907Y1733061D01*
G01X2455072Y1732271D02*
X2455055Y1732077D01*
G01X2455072Y1742271D02*
X2455055Y1742077D01*
G01X2453891Y1732271D02*
X2453874Y1732077D01*
G01X2455072Y1752271D02*
X2455055Y1752077D01*
G01X2453891Y1742271D02*
X2453874Y1742077D01*
G01X2455072Y1762271D02*
X2455055Y1762077D01*
G01X2453891Y1752271D02*
X2453874Y1752077D01*
G01X2455072Y1772271D02*
X2455055Y1772077D01*
G01X2453891Y1762271D02*
X2453874Y1762077D01*
G01X2455072Y1782271D02*
X2455055Y1782077D01*
G01X2453891Y1772271D02*
X2453874Y1772077D01*
G01X2455072Y1792271D02*
X2455055Y1792077D01*
G01X2453891Y1782271D02*
X2453874Y1782077D01*
G01X2453891Y1792271D02*
X2453874Y1792077D01*
G01X2455120Y1732455D02*
X2455071Y1732268D01*
G01X2453939Y1732455D02*
X2453890Y1732268D01*
G01X2455120Y1752455D02*
X2455071Y1752268D01*
G01X2453939Y1752455D02*
X2453890Y1752268D01*
G01X2455120Y1762455D02*
X2455071Y1762268D01*
G01X2453939Y1762455D02*
X2453890Y1762268D01*
G01X2455120Y1772455D02*
X2455071Y1772268D01*
G01X2453939Y1772455D02*
X2453890Y1772268D01*
G01X2455120Y1782455D02*
X2455071Y1782268D01*
G01X2453939Y1782455D02*
X2453890Y1782268D01*
G01X2455120Y1792455D02*
X2455071Y1792268D01*
G01X2453939Y1792455D02*
X2453890Y1792268D01*
G01X2455199Y1732624D02*
X2455119Y1732452D01*
G01X2454018Y1732624D02*
X2453938Y1732452D01*
G01X2455119Y1742452D02*
X2455197Y1742621D01*
X2455305Y1742773D01*
G01X2453938Y1742452D02*
X2454016Y1742621D01*
X2454124Y1742773D01*
G01X2455199Y1742624D02*
X2455120Y1742455D01*
X2455071Y1742268D01*
G01X2454018Y1742624D02*
X2453939Y1742455D01*
X2453890Y1742268D01*
G01X2455199Y1752624D02*
X2455119Y1752452D01*
G01X2454018Y1752624D02*
X2453938Y1752452D01*
G01X2455199Y1762624D02*
X2455119Y1762452D01*
G01X2454018Y1762624D02*
X2453938Y1762452D01*
G01X2455199Y1772624D02*
X2455119Y1772452D01*
G01X2454018Y1772624D02*
X2453938Y1772452D01*
G01X2455199Y1782624D02*
X2455119Y1782452D01*
G01X2454018Y1782624D02*
X2453938Y1782452D01*
G01X2455199Y1792624D02*
X2455119Y1792452D01*
G01X2454018Y1792624D02*
X2453938Y1792452D01*
G01X2455197Y1732621D02*
X2455305Y1732773D01*
G01X2454016Y1732621D02*
X2454124Y1732773D01*
G01X2455197Y1752621D02*
X2455305Y1752773D01*
G01X2454016Y1752621D02*
X2454124Y1752773D01*
G01X2455197Y1762621D02*
X2455305Y1762773D01*
G01X2454016Y1762621D02*
X2454124Y1762773D01*
G01X2455197Y1772621D02*
X2455305Y1772773D01*
G01X2454016Y1772621D02*
X2454124Y1772773D01*
G01X2455197Y1782621D02*
X2455305Y1782773D01*
G01X2454016Y1782621D02*
X2454124Y1782773D01*
G01X2455197Y1792621D02*
X2455305Y1792773D01*
G01X2454016Y1792621D02*
X2454124Y1792773D01*
G01X2455436Y1742896D02*
X2455305Y1742773D01*
G01X2454255Y1742896D02*
X2454124Y1742773D01*
G01X2455436Y1752896D02*
X2455305Y1752773D01*
G01X2454255Y1752896D02*
X2454124Y1752773D01*
G01X2455436Y1762896D02*
X2455305Y1762773D01*
G01X2454255Y1762896D02*
X2454124Y1762773D01*
G01X2455436Y1772896D02*
X2455305Y1772773D01*
G01X2454255Y1772896D02*
X2454124Y1772773D01*
G01X2455436Y1782896D02*
X2455305Y1782773D01*
G01X2454255Y1782896D02*
X2454124Y1782773D01*
G01X2455436Y1792896D02*
X2455305Y1792773D01*
G01X2454255Y1792896D02*
X2454124Y1792773D01*
G01X2455433Y1732895D02*
X2455580Y1732985D01*
G01X2454252Y1732895D02*
X2454399Y1732985D01*
G01X2455583Y1732987D02*
X2455436Y1732896D01*
X2455305Y1732773D01*
G01X2454401Y1732987D02*
X2454255Y1732896D01*
X2454124Y1732773D01*
G01X2455583Y1742987D02*
X2455433Y1742895D01*
G01X2454401Y1742987D02*
X2454252Y1742895D01*
G01X2455583Y1752987D02*
X2455433Y1752895D01*
G01X2454401Y1752987D02*
X2454252Y1752895D01*
G01X2455583Y1762987D02*
X2455433Y1762895D01*
G01X2454401Y1762987D02*
X2454252Y1762895D01*
G01X2455583Y1772987D02*
X2455433Y1772895D01*
G01X2454401Y1772987D02*
X2454252Y1772895D01*
G01X2455583Y1782987D02*
X2455433Y1782895D01*
G01X2454401Y1782987D02*
X2454252Y1782895D01*
G01X2455583Y1792987D02*
X2455433Y1792895D01*
G01X2454401Y1792987D02*
X2454252Y1792895D01*
G01X2455742Y1733042D02*
X2455580Y1732985D01*
G01X2454561Y1733042D02*
X2454399Y1732985D01*
G01X2455742Y1743042D02*
X2455580Y1742985D01*
G01X2454561Y1743042D02*
X2454399Y1742985D01*
G01X2455742Y1753042D02*
X2455580Y1752985D01*
G01X2454561Y1753042D02*
X2454399Y1752985D01*
G01X2455742Y1763042D02*
X2455580Y1762985D01*
G01X2454561Y1763042D02*
X2454399Y1762985D01*
G01X2455742Y1773042D02*
X2455580Y1772985D01*
G01X2454561Y1773042D02*
X2454399Y1772985D01*
G01X2455742Y1783042D02*
X2455580Y1782985D01*
G01X2454561Y1783042D02*
X2454399Y1782985D01*
G01X2455742Y1793042D02*
X2455580Y1792985D01*
G01X2454561Y1793042D02*
X2454399Y1792985D01*
G01X2483598Y1728809D02*
Y1723061D01*
G01X2501079Y1723809D02*
X2480449D01*
G01X2497929Y1775403D02*
G03X2498323Y1775010I394J1D01*
G01Y1776860D02*
G03X2497929Y1776466I0J-394D01*
G01X2496945Y1791014D02*
G03X2497929Y1791998I0J984D01*
G01Y1779872D02*
G03X2496945Y1780856I-984J0D01*
G01Y1771014D02*
G03X2497929Y1771998I0J984D01*
G01X2488323Y1791998D02*
G03X2489307Y1791014I984J0D01*
G01Y1780856D02*
G03X2488323Y1779872I0J-984D01*
G01Y1771998D02*
G03X2489307Y1771014I984J0D01*
G01X2497929Y1755403D02*
G03X2498323Y1755010I394J1D01*
G01Y1756860D02*
G03X2497929Y1756466I0J-394D01*
G01X2498323Y1766860D02*
G03X2497929Y1766466I0J-394D01*
G01Y1765403D02*
G03X2498323Y1765010I394J1D01*
G01X2496945Y1751014D02*
G03X2497929Y1751998I0J984D01*
G01Y1759872D02*
G03X2496945Y1760856I-984J0D01*
G01X2498323Y1736860D02*
G03X2497929Y1736466I0J-394D01*
G01Y1735403D02*
G03X2498323Y1735010I394J1D01*
G01Y1726860D02*
G03X2497929Y1726466I0J-394D01*
G01Y1725403D02*
G03X2498323Y1725010I394J1D01*
G01X2497929Y1739872D02*
G03X2496945Y1740856I-984J0D01*
G01Y1731014D02*
G03X2497929Y1731998I0J984D01*
G01X2489307Y1760856D02*
G03X2488323Y1759872I0J-984D01*
G01Y1751998D02*
G03X2489307Y1751014I984J0D01*
G01X2488323Y1731998D02*
G03X2489307Y1731014I984J0D01*
G01Y1740856D02*
G03X2488323Y1739872I0J-984D01*
G01X2497880Y1774942D02*
X2497935Y1774839D01*
G01X2497880Y1764942D02*
X2497935Y1764839D01*
G01X2497934Y1774840D02*
X2498008Y1774750D01*
G01X2497934Y1764840D02*
X2498008Y1764750D01*
G01X2497934Y1754840D02*
X2498008Y1754750D01*
G01X2497934Y1734840D02*
X2498008Y1734750D01*
G01X2480449Y1785364D02*
X2480842Y1784970D01*
G01X2480449Y1745364D02*
X2480842Y1744970D01*
G01X2497893Y1774715D02*
X2497833Y1774774D01*
G01X2497893Y1764715D02*
X2497833Y1764774D01*
G01X2497893Y1754715D02*
X2497833Y1754774D01*
G01X2497893Y1734715D02*
X2497833Y1734774D01*
G01X2498098Y1774675D02*
X2498008Y1774750D01*
G01X2498098Y1764675D02*
X2498008Y1764750D01*
G01X2498098Y1754675D02*
X2498008Y1754750D01*
G01X2497892Y1774716D02*
X2497960Y1774666D01*
G01X2497892Y1764716D02*
X2497960Y1764666D01*
G01X2497892Y1754716D02*
X2497960Y1754666D01*
G01X2497846Y1775053D02*
X2497881Y1774940D01*
G01X2497846Y1765053D02*
X2497881Y1764940D01*
G01X2497846Y1755053D02*
X2497881Y1754940D01*
G01X2497846Y1735053D02*
X2497881Y1734940D01*
G01X2497846Y1725053D02*
X2497881Y1724940D01*
G01X2497880Y1754942D02*
X2497935Y1754839D01*
G01X2497880Y1734942D02*
X2497935Y1734839D01*
G01X2497880Y1724942D02*
X2497935Y1724839D01*
G01X2497934Y1724840D02*
X2498008Y1724750D01*
G01X2497893Y1724715D02*
X2497833Y1724774D01*
G01X2498098Y1734675D02*
X2498008Y1734750D01*
G01X2498098Y1724675D02*
X2498008Y1724750D01*
G01X2497892Y1734716D02*
X2497960Y1734666D01*
G01X2497892Y1724716D02*
X2497960Y1724666D01*
G01X2498097Y1774676D02*
X2498200Y1774621D01*
G01X2497958Y1774667D02*
X2498032Y1774628D01*
G01X2498097Y1764676D02*
X2498200Y1764621D01*
G01X2497958Y1764667D02*
X2498032Y1764628D01*
G01X2498097Y1754676D02*
X2498200Y1754621D01*
G01X2497958Y1754667D02*
X2498032Y1754628D01*
G01X2498097Y1734676D02*
X2498200Y1734621D01*
G01X2497958Y1734667D02*
X2498032Y1734628D01*
G01X2498097Y1724676D02*
X2498200Y1724621D01*
G01X2497958Y1724667D02*
X2498032Y1724628D01*
G01X2498030Y1774629D02*
X2498109Y1774600D01*
G01X2498030Y1764629D02*
X2498109Y1764600D01*
G01X2498030Y1754629D02*
X2498109Y1754600D01*
G01X2498198Y1774622D02*
X2498310Y1774588D01*
G01X2498198Y1764622D02*
X2498310Y1764588D01*
G01X2497685Y1775167D02*
X2497701Y1775023D01*
X2497752Y1774892D01*
X2497835Y1774774D01*
G01X2497685Y1765167D02*
X2497701Y1765023D01*
X2497752Y1764892D01*
X2497835Y1764774D01*
G01X2497685Y1755167D02*
X2497701Y1755023D01*
X2497752Y1754892D01*
X2497835Y1754774D01*
G01X2497685Y1735167D02*
X2497701Y1735023D01*
X2497752Y1734892D01*
X2497835Y1734774D01*
G01X2497685Y1725167D02*
X2497701Y1725023D01*
X2497752Y1724892D01*
X2497835Y1724774D01*
G01X2498030Y1734629D02*
X2498109Y1734600D01*
G01X2498030Y1724629D02*
X2498109Y1724600D01*
G01X2498198Y1754622D02*
X2498310Y1754588D01*
G01X2498198Y1734622D02*
X2498310Y1734588D01*
G01X2498198Y1724622D02*
X2498310Y1724588D01*
G01X2498108Y1774600D02*
X2498190Y1774582D01*
G01X2498108Y1764600D02*
X2498190Y1764582D01*
G01X2498108Y1754600D02*
X2498190Y1754582D01*
G01X2498108Y1734600D02*
X2498190Y1734582D01*
G01X2498108Y1724600D02*
X2498190Y1724582D01*
G01X2497142Y1784577D02*
X2493205Y1784970D01*
G01X2498308Y1774588D02*
X2498425Y1774577D01*
G01X2498308Y1764588D02*
X2498425Y1764577D01*
G01X2497847Y1775051D02*
X2497835Y1775167D01*
G01X2497847Y1765051D02*
X2497835Y1765167D01*
G01X2497847Y1755051D02*
X2497835Y1755167D01*
G01X2497847Y1735051D02*
X2497835Y1735167D01*
G01X2497847Y1725051D02*
X2497835Y1725167D01*
G01X2498308Y1754588D02*
X2498425Y1754577D01*
G01X2497142Y1744577D02*
X2493205Y1744970D01*
G01X2498308Y1734588D02*
X2498425Y1734577D01*
G01X2498308Y1724588D02*
X2498425Y1724577D01*
G01X2498188Y1774583D02*
X2498272Y1774577D01*
G01X2498188Y1764583D02*
X2498272Y1764577D01*
G01X2498188Y1754583D02*
X2498272Y1754577D01*
G01X2498188Y1734583D02*
X2498272Y1734577D01*
G01X2498188Y1724583D02*
X2498272Y1724577D01*
G01X2480449Y1792982D02*
X2492079D01*
G01X2501079D02*
X2497929D01*
G01X2496945Y1791014D02*
X2480449D01*
G01X2501079Y1788061D02*
X2480449D01*
G01X2534012Y1787293D02*
X2480449D01*
G01X2501079Y1786900D02*
X2480842D01*
G01X2540449Y1786860D02*
X2501079D01*
G01X2540449Y1785010D02*
X2501079D01*
G01Y1784970D02*
X2480842D01*
G01X2534012Y1784577D02*
X2480449D01*
G01X2501079Y1783809D02*
X2480449D01*
G01X2496945Y1780856D02*
X2480449D01*
G01Y1778888D02*
X2492079D01*
G01X2501079D02*
X2497929D01*
G01X2534012Y1777293D02*
X2498272D01*
G01X2501079Y1777096D02*
X2480449D01*
G01X2540449Y1776860D02*
X2498323D01*
G01X2497835Y1776703D02*
X2497685D01*
G01X2497835Y1775167D02*
X2497685D01*
G01X2540449Y1775010D02*
X2498323D01*
G01X2501079Y1774774D02*
X2480449D01*
G01X2534012Y1774577D02*
X2498272D01*
G01X2480449Y1772982D02*
X2492079D01*
G01X2501079D02*
X2497929D01*
G01X2496945Y1771014D02*
X2480449D01*
G01X2501079Y1768061D02*
X2480449D01*
G01X2534012Y1767293D02*
X2498272D01*
G01X2501079Y1767096D02*
X2480449D01*
G01X2540449Y1766860D02*
X2498323D01*
G01X2497835Y1766703D02*
X2497685D01*
G01X2497835Y1765167D02*
X2497685D01*
G01X2540449Y1765010D02*
X2498323D01*
G01X2501079Y1764774D02*
X2480449D01*
G01X2534012Y1764577D02*
X2498272D01*
G01X2501079Y1763809D02*
X2480449D01*
G01X2496945Y1760856D02*
X2480449D01*
G01Y1758888D02*
X2492079D01*
G01X2501079D02*
X2497929D01*
G01X2534012Y1757293D02*
X2498272D01*
G01X2501079Y1757096D02*
X2480449D01*
G01X2540449Y1756860D02*
X2498323D01*
G01X2497835Y1756703D02*
X2497685D01*
G01X2497835Y1755167D02*
X2497685D01*
G01X2540449Y1755010D02*
X2498323D01*
G01X2501079Y1754774D02*
X2480449D01*
G01X2534012Y1754577D02*
X2498272D01*
G01X2480449Y1752982D02*
X2492079D01*
G01X2501079D02*
X2497929D01*
G01X2496945Y1751014D02*
X2480449D01*
G01X2501079Y1748061D02*
X2480449D01*
G01X2534012Y1747293D02*
X2480449D01*
G01X2501079Y1746900D02*
X2480842D01*
G01X2540449Y1746860D02*
X2501079D01*
G01X2540449Y1745010D02*
X2501079D01*
G01Y1744970D02*
X2480842D01*
G01X2534012Y1744577D02*
X2480449D01*
G01X2501079Y1743809D02*
X2480449D01*
G01X2496945Y1740856D02*
X2480449D01*
G01Y1738888D02*
X2492079D01*
G01X2501079D02*
X2497929D01*
G01X2534012Y1737293D02*
X2498272D01*
G01X2501079Y1737096D02*
X2480449D01*
G01X2540449Y1736860D02*
X2498323D01*
G01X2497835Y1736703D02*
X2497685D01*
G01X2498188Y1777287D02*
X2498272Y1777293D01*
G01X2497847Y1726819D02*
X2497835Y1726703D01*
G01X2497847Y1736819D02*
X2497835Y1736703D01*
G01X2497847Y1756819D02*
X2497835Y1756703D01*
G01X2497847Y1766819D02*
X2497835Y1766703D01*
G01X2497847Y1776819D02*
X2497835Y1776703D01*
G01X2501866Y1775010D02*
Y1776860D01*
G01Y1755010D02*
Y1756860D01*
G01Y1735010D02*
Y1736860D01*
G01Y1726860D02*
Y1725010D01*
G01Y1766860D02*
Y1765010D01*
G01X2497929Y1726466D02*
Y1725403D01*
G01Y1739872D02*
Y1731998D01*
G01Y1759872D02*
Y1751998D01*
G01Y1766466D02*
Y1765403D01*
G01Y1779872D02*
Y1771998D01*
G01Y1799872D02*
Y1791998D01*
G01X2497835Y1726703D02*
Y1725167D01*
G01Y1736703D02*
Y1735167D01*
G01Y1756703D02*
Y1755167D01*
G01Y1766703D02*
Y1765167D01*
G01Y1776703D02*
Y1775167D01*
G01X2497685Y1765167D02*
Y1766703D01*
G01Y1726703D02*
Y1725167D01*
G01Y1736703D02*
Y1735167D01*
G01Y1756703D02*
Y1755167D01*
G01Y1776703D02*
Y1775167D01*
G01X2497421Y1784577D02*
Y1747293D01*
G01Y1824577D02*
Y1787293D01*
G01X2497269Y1734774D02*
Y1727096D01*
G01Y1744577D02*
Y1737096D01*
G01Y1754774D02*
Y1747293D01*
G01Y1764774D02*
Y1757096D01*
G01Y1774774D02*
Y1767096D01*
G01Y1784577D02*
Y1777096D01*
G01Y1794774D02*
Y1787293D01*
G01X2497142Y1784577D02*
Y1747293D01*
G01Y1824577D02*
Y1787293D01*
G01X2492079Y1738888D02*
Y1732982D01*
G01Y1758888D02*
Y1752982D01*
G01Y1778888D02*
Y1772982D01*
G01Y1798888D02*
Y1792982D01*
G01X2491275Y1738888D02*
Y1732982D01*
G01Y1758888D02*
Y1752982D01*
G01Y1778888D02*
Y1772982D01*
G01Y1798888D02*
Y1792982D01*
G01X2489520Y1752982D02*
Y1758888D01*
G01Y1738888D02*
Y1732982D01*
G01Y1778888D02*
Y1772982D01*
G01Y1798888D02*
Y1792982D01*
G01X2488716Y1738888D02*
Y1732982D01*
G01Y1758888D02*
Y1752982D01*
G01Y1778888D02*
Y1772982D01*
G01Y1798888D02*
Y1792982D01*
G01X2488323Y1739872D02*
Y1731998D01*
G01Y1759872D02*
Y1751998D01*
G01Y1779872D02*
Y1771998D01*
G01Y1799872D02*
Y1791998D01*
G01X2486354Y1738888D02*
Y1732982D01*
G01Y1758888D02*
Y1752982D01*
G01Y1778888D02*
Y1772982D01*
G01Y1798888D02*
Y1792982D01*
G01X2484386Y1727096D02*
Y1724774D01*
G01Y1737096D02*
Y1734774D01*
G01Y1757096D02*
Y1754774D01*
G01Y1767096D02*
Y1764774D01*
G01Y1777096D02*
Y1774774D01*
G01X2483598Y1738809D02*
Y1733061D01*
G01Y1744970D02*
Y1743061D01*
G01Y1748809D02*
Y1746900D01*
G01Y1758809D02*
Y1753061D01*
G01Y1768809D02*
Y1763061D01*
G01Y1778809D02*
Y1773061D01*
G01Y1784970D02*
Y1783061D01*
G01Y1788809D02*
Y1786900D01*
G01Y1798809D02*
Y1793061D01*
G01X2482811Y1733061D02*
Y1728809D01*
G01Y1743061D02*
Y1738809D01*
G01Y1753061D02*
Y1748809D01*
G01Y1763061D02*
Y1758809D01*
G01Y1773061D02*
Y1768809D01*
G01Y1783061D02*
Y1778809D01*
G01Y1793061D02*
Y1788809D01*
G01X2481630Y1733061D02*
Y1728809D01*
G01Y1743061D02*
Y1738809D01*
G01Y1753061D02*
Y1748809D01*
G01Y1763061D02*
Y1758809D01*
G01Y1773061D02*
Y1768809D01*
G01Y1783061D02*
Y1778809D01*
G01Y1793061D02*
Y1788809D01*
G01X2480842Y1786900D02*
Y1788061D01*
G01Y1746900D02*
Y1748061D01*
G01Y1744970D02*
Y1743809D01*
G01Y1784970D02*
Y1783809D01*
G01X2479183Y1733061D02*
Y1728809D01*
G01Y1743061D02*
Y1738809D01*
G01Y1753061D02*
Y1748809D01*
G01Y1763061D02*
Y1758809D01*
G01Y1773061D02*
Y1768809D01*
G01Y1783061D02*
Y1778809D01*
G01Y1793061D02*
Y1788809D01*
G01X2478002Y1733061D02*
Y1728809D01*
G01Y1743061D02*
Y1738809D01*
G01Y1753061D02*
Y1748809D01*
G01Y1763061D02*
Y1758809D01*
G01Y1773061D02*
Y1768809D01*
G01Y1783061D02*
Y1778809D01*
G01Y1793061D02*
Y1788809D01*
G01X2476821Y1733061D02*
Y1728809D01*
G01Y1743061D02*
Y1738809D01*
G01Y1753061D02*
Y1748809D01*
G01Y1763061D02*
Y1758809D01*
G01Y1773061D02*
Y1768809D01*
G01Y1783061D02*
Y1778809D01*
G01Y1793061D02*
Y1788809D01*
G01X2472884Y1733061D02*
Y1728809D01*
G01Y1743061D02*
Y1738809D01*
G01Y1753061D02*
Y1748809D01*
G01Y1763061D02*
Y1758809D01*
G01Y1773061D02*
Y1768809D01*
G01Y1783061D02*
Y1778809D01*
G01Y1793061D02*
Y1788809D01*
G01X2472281Y1733061D02*
Y1728809D01*
G01Y1743061D02*
Y1738809D01*
G01Y1753061D02*
Y1748809D01*
G01Y1763061D02*
Y1758809D01*
G01Y1773061D02*
Y1768809D01*
G01Y1783061D02*
Y1778809D01*
G01Y1793061D02*
Y1788809D01*
G01X2471678Y1733061D02*
Y1728809D01*
G01Y1743061D02*
Y1738809D01*
G01Y1753061D02*
Y1748809D01*
G01Y1763061D02*
Y1758809D01*
G01Y1773061D02*
Y1768809D01*
G01Y1783061D02*
Y1778809D01*
G01Y1793061D02*
Y1788809D01*
G01X2462556Y1733061D02*
Y1728809D01*
G01Y1743061D02*
Y1738809D01*
G01Y1753061D02*
Y1748809D01*
G01Y1763061D02*
Y1758809D01*
G01Y1773061D02*
Y1768809D01*
G01Y1783061D02*
Y1778809D01*
G01Y1793061D02*
Y1788809D01*
G01X2461953Y1733061D02*
Y1728809D01*
G01Y1743061D02*
Y1738809D01*
G01Y1753061D02*
Y1748809D01*
G01Y1763061D02*
Y1758809D01*
G01Y1773061D02*
Y1768809D01*
G01Y1783061D02*
Y1778809D01*
G01Y1793061D02*
Y1788809D01*
G01X2497835Y1735167D02*
X2497685D01*
G01X2540449Y1735010D02*
X2498323D01*
G01X2501079Y1734774D02*
X2480449D01*
G01X2534012Y1734577D02*
X2498272D01*
G01X2480449Y1732982D02*
X2492079D01*
G01X2501079D02*
X2497929D01*
G01X2496945Y1731014D02*
X2480449D01*
G01X2501079Y1728061D02*
X2480449D01*
G01X2534012Y1727293D02*
X2498272D01*
G01X2501079Y1727096D02*
X2480449D01*
G01X2540449Y1726860D02*
X2498323D01*
G01X2497835Y1726703D02*
X2497685D01*
G01X2497835Y1725167D02*
X2497685D01*
G01X2540449Y1725010D02*
X2498323D01*
G01X2501079Y1724774D02*
X2480449D01*
G01X2534012Y1724577D02*
X2498272D01*
G01X2498188Y1767287D02*
X2498272Y1767293D01*
G01X2498188Y1757287D02*
X2498272Y1757293D01*
G01X2498188Y1737287D02*
X2498272Y1737293D01*
G01X2498188Y1727287D02*
X2498272Y1727293D01*
G01X2497142Y1787293D02*
X2493205Y1786900D01*
G01X2498308Y1777282D02*
X2498425Y1777293D01*
G01X2498308Y1767282D02*
X2498425Y1767293D01*
G01X2498308Y1757282D02*
X2498425Y1757293D01*
G01X2497142Y1747293D02*
X2493205Y1746900D01*
G01X2498308Y1727282D02*
X2498425Y1727293D01*
G01X2497685Y1766703D02*
X2497702Y1766846D01*
X2497753Y1766977D01*
X2497835Y1767096D01*
G01X2497685Y1766703D02*
X2497701Y1766847D01*
X2497752Y1766978D01*
X2497835Y1767096D01*
G01X2498190Y1777287D02*
X2498108Y1777270D01*
G01X2498190Y1767287D02*
X2498108Y1767270D01*
G01X2498190Y1757287D02*
X2498108Y1757270D01*
G01X2498190Y1737287D02*
X2498108Y1737270D01*
G01X2498190Y1727287D02*
X2498108Y1727270D01*
G01X2497881Y1726930D02*
X2497846Y1726817D01*
G01X2497881Y1736930D02*
X2497846Y1736817D01*
G01X2497881Y1756930D02*
X2497846Y1756817D01*
G01X2497881Y1766930D02*
X2497846Y1766817D01*
G01X2497881Y1776930D02*
X2497846Y1776817D01*
G01X2497935Y1727031D02*
X2497880Y1726928D01*
G01X2497935Y1737031D02*
X2497880Y1736928D01*
G01X2497835Y1727096D02*
X2497752Y1726978D01*
X2497701Y1726847D01*
X2497685Y1726703D01*
G01X2497935Y1757031D02*
X2497880Y1756928D01*
G01X2497935Y1767031D02*
X2497880Y1766928D01*
G01X2497935Y1777031D02*
X2497880Y1776928D01*
G01X2497934Y1727029D02*
X2498008Y1727120D01*
G01X2497934Y1737029D02*
X2498008Y1737120D01*
G01X2497934Y1757029D02*
X2498008Y1757120D01*
G01X2497934Y1767029D02*
X2498008Y1767120D01*
G01X2497835Y1737096D02*
X2497752Y1736978D01*
X2497701Y1736847D01*
X2497685Y1736703D01*
G01X2497835Y1757096D02*
X2497752Y1756978D01*
X2497701Y1756847D01*
X2497685Y1756703D01*
G01X2497835Y1777096D02*
X2497752Y1776978D01*
X2497701Y1776847D01*
X2497685Y1776703D01*
G01X2497893Y1727155D02*
X2497833Y1727096D01*
G01X2497893Y1737155D02*
X2497833Y1737096D01*
G01X2497893Y1757155D02*
X2497833Y1757096D01*
G01X2480842Y1746900D02*
X2480449Y1746506D01*
G01X2497934Y1777029D02*
X2498008Y1777120D01*
G01X2497960Y1727203D02*
X2497892Y1727154D01*
G01X2498098Y1727195D02*
X2498008Y1727120D01*
G01X2498098Y1737195D02*
X2498008Y1737120D01*
G01X2498098Y1757195D02*
X2498008Y1757120D01*
G01X2498098Y1767195D02*
X2498008Y1767120D01*
G01X2498098Y1777195D02*
X2498008Y1777120D01*
G01X2497893Y1767155D02*
X2497833Y1767096D01*
G01X2497893Y1777155D02*
X2497833Y1777096D01*
G01X2480842Y1786900D02*
X2480449Y1786506D01*
G01X2497960Y1737203D02*
X2497892Y1737154D01*
G01X2497960Y1757203D02*
X2497892Y1757154D01*
G01X2497960Y1767203D02*
X2497892Y1767154D01*
G01X2497960Y1777203D02*
X2497892Y1777154D01*
G01X2498200Y1727249D02*
X2498097Y1727193D01*
G01X2498032Y1727242D02*
X2497958Y1727202D01*
G01X2498032Y1737242D02*
X2497958Y1737202D01*
G01X2498200Y1757249D02*
X2498097Y1757193D01*
G01X2498032Y1757242D02*
X2497958Y1757202D01*
G01X2498200Y1767249D02*
X2498097Y1767193D01*
G01X2498032Y1767242D02*
X2497958Y1767202D01*
G01X2498200Y1777249D02*
X2498097Y1777193D01*
G01X2498032Y1777242D02*
X2497958Y1777202D01*
G01X2498310Y1727282D02*
X2498198Y1727248D01*
G01Y1737248D02*
X2498308Y1737282D01*
X2498425Y1737293D01*
G01X2498109Y1727270D02*
X2498030Y1727241D01*
G01X2498109Y1737270D02*
X2498030Y1737241D01*
G01X2498109Y1757270D02*
X2498030Y1757241D01*
G01X2498109Y1767270D02*
X2498030Y1767241D01*
G01X2498310Y1737282D02*
X2498200Y1737249D01*
X2498097Y1737193D01*
G01X2498310Y1757282D02*
X2498198Y1757248D01*
G01X2498310Y1767282D02*
X2498198Y1767248D01*
G01X2498310Y1777282D02*
X2498198Y1777248D01*
G01X2498109Y1777270D02*
X2498030Y1777241D01*
G01X2455197Y1859249D02*
X2455305Y1859097D01*
G01X2454016Y1859249D02*
X2454124Y1859097D01*
G01X2455197Y1849249D02*
X2455305Y1849097D01*
G01X2454016Y1849249D02*
X2454124Y1849097D01*
G01X2455197Y1839249D02*
X2455305Y1839097D01*
G01X2454016Y1839249D02*
X2454124Y1839097D01*
G01X2455197Y1829249D02*
X2455305Y1829097D01*
G01X2454016Y1829249D02*
X2454124Y1829097D01*
G01X2455197Y1819249D02*
X2455305Y1819097D01*
G01X2454016Y1819249D02*
X2454124Y1819097D01*
G01X2455197Y1809249D02*
X2455305Y1809097D01*
G01X2454016Y1809249D02*
X2454124Y1809097D01*
G01X2455197Y1799249D02*
X2455305Y1799097D01*
G01X2454016Y1799249D02*
X2454124Y1799097D01*
G01X2455436Y1858973D02*
X2455305Y1859097D01*
G01X2454255Y1858973D02*
X2454124Y1859097D01*
G01X2455436Y1848973D02*
X2455305Y1849097D01*
G01X2454255Y1848973D02*
X2454124Y1849097D01*
G01X2455436Y1838973D02*
X2455305Y1839097D01*
G01X2454255Y1838973D02*
X2454124Y1839097D01*
G01X2455436Y1828973D02*
X2455305Y1829097D01*
G01X2454255Y1828973D02*
X2454124Y1829097D01*
G01X2455436Y1818973D02*
X2455305Y1819097D01*
G01X2454255Y1818973D02*
X2454124Y1819097D01*
G01X2455436Y1808973D02*
X2455305Y1809097D01*
G01X2454255Y1808973D02*
X2454124Y1809097D01*
G01X2455436Y1798973D02*
X2455305Y1799097D01*
G01X2454255Y1798973D02*
X2454124Y1799097D01*
G01X2455433Y1858975D02*
X2455583Y1858883D01*
G01X2454252Y1858975D02*
X2454401Y1858883D01*
G01X2455433Y1848975D02*
X2455583Y1848883D01*
G01X2454252Y1848975D02*
X2454401Y1848883D01*
G01X2455433Y1838975D02*
X2455583Y1838883D01*
G01X2454252Y1838975D02*
X2454401Y1838883D01*
G01X2455433Y1828975D02*
X2455583Y1828883D01*
G01X2454252Y1828975D02*
X2454401Y1828883D01*
G01X2455433Y1818975D02*
X2455583Y1818883D01*
G01X2454252Y1818975D02*
X2454401Y1818883D01*
G01X2455433Y1808975D02*
X2455583Y1808883D01*
G01X2454252Y1808975D02*
X2454401Y1808883D01*
G01X2455433Y1798975D02*
X2455583Y1798883D01*
G01X2454252Y1798975D02*
X2454401Y1798883D01*
G01X2455580Y1858885D02*
X2455742Y1858828D01*
G01X2454399Y1858885D02*
X2454561Y1858828D01*
G01X2455580Y1848885D02*
X2455742Y1848828D01*
G01X2454399Y1848885D02*
X2454561Y1848828D01*
G01X2455580Y1838885D02*
X2455742Y1838828D01*
G01X2454399Y1838885D02*
X2454561Y1838828D01*
G01X2455119Y1859418D02*
X2455199Y1859246D01*
G01X2453938Y1859418D02*
X2454018Y1859246D01*
G01X2455119Y1849418D02*
X2455199Y1849246D01*
G01X2453938Y1849418D02*
X2454018Y1849246D01*
G01X2455119Y1839418D02*
X2455199Y1839246D01*
G01X2453938Y1839418D02*
X2454018Y1839246D01*
G01X2455119Y1829418D02*
X2455199Y1829246D01*
G01X2453938Y1829418D02*
X2454018Y1829246D01*
G01X2455119Y1819418D02*
X2455199Y1819246D01*
G01X2453938Y1819418D02*
X2454018Y1819246D01*
G01X2455119Y1809418D02*
X2455199Y1809246D01*
G01X2453938Y1809418D02*
X2454018Y1809246D01*
G01X2455119Y1799418D02*
X2455199Y1799246D01*
G01X2453938Y1799418D02*
X2454018Y1799246D01*
G01X2455580Y1828885D02*
X2455742Y1828828D01*
G01X2454399Y1828885D02*
X2454561Y1828828D01*
G01X2455580Y1818885D02*
X2455742Y1818828D01*
G01X2454399Y1818885D02*
X2454561Y1818828D01*
G01X2455580Y1808885D02*
X2455742Y1808828D01*
G01X2454399Y1808885D02*
X2454561Y1808828D01*
G01X2455580Y1798885D02*
X2455742Y1798828D01*
G01X2454399Y1798885D02*
X2454561Y1798828D01*
G01X2455739Y1858828D02*
X2455907Y1858809D01*
G01X2454558Y1858828D02*
X2454726Y1858809D01*
G01X2455739Y1848828D02*
X2455907Y1848809D01*
G01X2454558Y1848828D02*
X2454726Y1848809D01*
G01X2455739Y1838828D02*
X2455907Y1838809D01*
G01X2454558Y1838828D02*
X2454726Y1838809D01*
G01X2455071Y1859602D02*
X2455120Y1859415D01*
G01X2453890Y1859602D02*
X2453939Y1859415D01*
G01X2455071Y1849602D02*
X2455120Y1849415D01*
G01X2453890Y1849602D02*
X2453939Y1849415D01*
G01X2455071Y1839602D02*
X2455120Y1839415D01*
G01X2453890Y1839602D02*
X2453939Y1839415D01*
G01X2455071Y1829602D02*
X2455120Y1829415D01*
G01X2453890Y1829602D02*
X2453939Y1829415D01*
G01X2455071Y1819602D02*
X2455120Y1819415D01*
G01X2453890Y1819602D02*
X2453939Y1819415D01*
G01X2455071Y1809602D02*
X2455120Y1809415D01*
G01X2453890Y1809602D02*
X2453939Y1809415D01*
G01X2455071Y1799602D02*
X2455120Y1799415D01*
G01X2453890Y1799602D02*
X2453939Y1799415D01*
G01X2455739Y1828828D02*
X2455907Y1828809D01*
G01X2454558Y1828828D02*
X2454726Y1828809D01*
G01X2455739Y1818828D02*
X2455907Y1818809D01*
G01X2454558Y1818828D02*
X2454726Y1818809D01*
G01X2455739Y1808828D02*
X2455907Y1808809D01*
G01X2454558Y1808828D02*
X2454726Y1808809D01*
G01X2455739Y1798828D02*
X2455907Y1798809D01*
G01X2454558Y1798828D02*
X2454726Y1798809D01*
G01X2483598Y1863061D02*
X2454726D01*
G01X2455055Y1862077D02*
X2453874D01*
G01X2455055Y1859793D02*
X2453874D01*
G01X2483598Y1858809D02*
X2454726D01*
G01X2483598Y1853061D02*
X2454726D01*
G01X2455055Y1852077D02*
X2453874D01*
G01X2455055Y1849793D02*
X2453874D01*
G01X2483598Y1848809D02*
X2454726D01*
G01X2483598Y1843061D02*
X2454726D01*
G01X2455055Y1842077D02*
X2453874D01*
G01X2455055Y1839793D02*
X2453874D01*
G01X2483598Y1838809D02*
X2454726D01*
G01X2483598Y1833061D02*
X2454726D01*
G01X2455055Y1832077D02*
X2453874D01*
G01X2455055Y1829793D02*
X2453874D01*
G01X2483598Y1828809D02*
X2454726D01*
G01X2483598Y1823061D02*
X2454726D01*
G01X2455055Y1822077D02*
X2453874D01*
G01X2455055Y1819793D02*
X2453874D01*
G01X2483598Y1818809D02*
X2454726D01*
G01X2483598Y1813061D02*
X2454726D01*
G01X2455055Y1812077D02*
X2453874D01*
G01X2455055Y1809793D02*
X2453874D01*
G01X2483598Y1808809D02*
X2454726D01*
G01X2483598Y1803061D02*
X2454726D01*
G01X2455055Y1802077D02*
X2453874D01*
G01X2455055Y1799793D02*
X2453874D01*
G01X2483598Y1798809D02*
X2454726D01*
G01X2454558Y1863042D02*
X2454726Y1863061D01*
G01X2455739Y1863042D02*
X2455907Y1863061D01*
G01X2454558Y1853042D02*
X2454726Y1853061D01*
G01X2455739Y1853042D02*
X2455907Y1853061D01*
G01X2454558Y1843042D02*
X2454726Y1843061D01*
G01X2455739Y1843042D02*
X2455907Y1843061D01*
G01X2454558Y1833042D02*
X2454726Y1833061D01*
G01X2454558Y1823042D02*
X2454726Y1823061D01*
G01X2455739Y1823042D02*
X2455907Y1823061D01*
G01X2454558Y1813042D02*
X2454726Y1813061D01*
G01X2455739Y1813042D02*
X2455907Y1813061D01*
G01X2454558Y1803042D02*
X2454726Y1803061D01*
G01X2455739Y1803042D02*
X2455907Y1803061D01*
G01X2460764D02*
Y1798809D01*
G01Y1813061D02*
Y1808809D01*
G01Y1823061D02*
Y1818809D01*
G01Y1833061D02*
Y1828809D01*
G01Y1843061D02*
Y1838809D01*
G01Y1853061D02*
Y1848809D01*
G01Y1863061D02*
Y1858809D01*
G01X2459583Y1803061D02*
Y1798809D01*
G01Y1813061D02*
Y1808809D01*
G01Y1823061D02*
Y1818809D01*
G01Y1833061D02*
Y1828809D01*
G01Y1843061D02*
Y1838809D01*
G01Y1853061D02*
Y1848809D01*
G01Y1863061D02*
Y1858809D01*
G01X2455055Y1802077D02*
Y1799793D01*
G01Y1812077D02*
Y1809793D01*
G01Y1822077D02*
Y1819793D01*
G01Y1832077D02*
Y1829793D01*
G01Y1842077D02*
Y1839793D01*
G01Y1852077D02*
Y1849793D01*
G01Y1862077D02*
Y1859793D01*
G01X2453874Y1802077D02*
Y1799793D01*
G01Y1812077D02*
Y1809793D01*
G01Y1822077D02*
Y1819793D01*
G01Y1832077D02*
Y1829793D01*
G01Y1842077D02*
Y1839793D01*
G01Y1852077D02*
Y1849793D01*
G01Y1862077D02*
Y1859793D01*
G01X2455072Y1859599D02*
X2455055Y1859793D01*
G01X2455072Y1849599D02*
X2455055Y1849793D01*
G01X2453891Y1859599D02*
X2453874Y1859793D01*
G01X2455072Y1839599D02*
X2455055Y1839793D01*
G01X2453891Y1849599D02*
X2453874Y1849793D01*
G01X2455072Y1829599D02*
X2455055Y1829793D01*
G01X2453891Y1839599D02*
X2453874Y1839793D01*
G01X2455072Y1819599D02*
X2455055Y1819793D01*
G01X2453891Y1829599D02*
X2453874Y1829793D01*
G01X2455072Y1809599D02*
X2455055Y1809793D01*
G01X2453891Y1819599D02*
X2453874Y1819793D01*
G01X2455072Y1799599D02*
X2455055Y1799793D01*
G01X2453891Y1809599D02*
X2453874Y1809793D01*
G01X2453891Y1799599D02*
X2453874Y1799793D01*
G01X2455072Y1802271D02*
X2455055Y1802077D01*
G01X2455072Y1812271D02*
X2455055Y1812077D01*
G01X2453891Y1802271D02*
X2453874Y1802077D01*
G01X2455072Y1822271D02*
X2455055Y1822077D01*
G01X2453891Y1812271D02*
X2453874Y1812077D01*
G01X2455072Y1832271D02*
X2455055Y1832077D01*
G01X2453891Y1822271D02*
X2453874Y1822077D01*
G01X2455072Y1842271D02*
X2455055Y1842077D01*
G01X2453891Y1832271D02*
X2453874Y1832077D01*
G01X2455072Y1852271D02*
X2455055Y1852077D01*
G01X2453891Y1842271D02*
X2453874Y1842077D01*
G01X2453891Y1852271D02*
X2453874Y1852077D01*
G01X2455120Y1802455D02*
X2455071Y1802268D01*
G01X2453939Y1802455D02*
X2453890Y1802268D01*
G01X2455120Y1812455D02*
X2455071Y1812268D01*
G01X2453939Y1812455D02*
X2453890Y1812268D01*
G01X2455120Y1822455D02*
X2455071Y1822268D01*
G01X2453939Y1822455D02*
X2453890Y1822268D01*
G01X2455120Y1832455D02*
X2455071Y1832268D01*
G01X2453939Y1832455D02*
X2453890Y1832268D01*
G01X2455120Y1842455D02*
X2455071Y1842268D01*
G01X2453939Y1842455D02*
X2453890Y1842268D01*
G01X2455120Y1852455D02*
X2455071Y1852268D01*
G01X2453939Y1852455D02*
X2453890Y1852268D01*
G01X2455071Y1862268D02*
X2455119Y1862452D01*
G01X2453890Y1862268D02*
X2453938Y1862452D01*
G01X2455120Y1862455D02*
X2455072Y1862271D01*
X2455055Y1862077D01*
G01X2453939Y1862455D02*
X2453891Y1862271D01*
X2453874Y1862077D01*
G01X2455199Y1802624D02*
X2455119Y1802452D01*
G01X2454018Y1802624D02*
X2453938Y1802452D01*
G01X2455199Y1812624D02*
X2455119Y1812452D01*
G01X2454018Y1812624D02*
X2453938Y1812452D01*
G01X2455199Y1822624D02*
X2455119Y1822452D01*
G01X2454018Y1822624D02*
X2453938Y1822452D01*
G01X2455199Y1832624D02*
X2455119Y1832452D01*
G01X2454018Y1832624D02*
X2453938Y1832452D01*
G01X2455199Y1842624D02*
X2455119Y1842452D01*
G01X2454018Y1842624D02*
X2453938Y1842452D01*
G01X2455199Y1852624D02*
X2455119Y1852452D01*
G01X2454018Y1852624D02*
X2453938Y1852452D01*
G01X2455199Y1862624D02*
X2455119Y1862452D01*
G01X2454018Y1862624D02*
X2453938Y1862452D01*
G01X2455197Y1802621D02*
X2455305Y1802773D01*
G01X2454016Y1802621D02*
X2454124Y1802773D01*
G01X2455197Y1812621D02*
X2455305Y1812773D01*
G01X2454016Y1812621D02*
X2454124Y1812773D01*
G01X2455197Y1822621D02*
X2455305Y1822773D01*
G01X2454016Y1822621D02*
X2454124Y1822773D01*
G01X2455197Y1832621D02*
X2455305Y1832773D01*
G01X2454016Y1832621D02*
X2454124Y1832773D01*
G01X2455197Y1842621D02*
X2455305Y1842773D01*
G01X2454016Y1842621D02*
X2454124Y1842773D01*
G01X2455197Y1852621D02*
X2455305Y1852773D01*
G01X2454016Y1852621D02*
X2454124Y1852773D01*
G01X2455197Y1862621D02*
X2455305Y1862773D01*
G01X2454016Y1862621D02*
X2454124Y1862773D01*
G01X2455436Y1802896D02*
X2455305Y1802773D01*
G01X2454255Y1802896D02*
X2454124Y1802773D01*
G01X2455436Y1812896D02*
X2455305Y1812773D01*
G01X2454255Y1812896D02*
X2454124Y1812773D01*
G01X2455436Y1832896D02*
X2455305Y1832773D01*
G01X2454255Y1832896D02*
X2454124Y1832773D01*
G01X2455436Y1842896D02*
X2455305Y1842773D01*
G01X2454255Y1842896D02*
X2454124Y1842773D01*
G01X2455436Y1852896D02*
X2455305Y1852773D01*
G01X2454255Y1852896D02*
X2454124Y1852773D01*
G01X2455436Y1862896D02*
X2455305Y1862773D01*
G01X2454255Y1862896D02*
X2454124Y1862773D01*
G01X2455583Y1802987D02*
X2455433Y1802895D01*
G01X2454401Y1802987D02*
X2454252Y1802895D01*
G01X2455583Y1812987D02*
X2455433Y1812895D01*
G01X2454401Y1812987D02*
X2454252Y1812895D01*
G01X2455433Y1822895D02*
X2455580Y1822985D01*
G01X2454252Y1822895D02*
X2454399Y1822985D01*
G01X2455583Y1822987D02*
X2455436Y1822896D01*
X2455305Y1822773D01*
G01X2454401Y1822987D02*
X2454255Y1822896D01*
X2454124Y1822773D01*
G01X2454401Y1832987D02*
X2454252Y1832895D01*
G01X2455583Y1842987D02*
X2455433Y1842895D01*
G01X2454401Y1842987D02*
X2454252Y1842895D01*
G01X2455583Y1852987D02*
X2455433Y1852895D01*
G01X2454401Y1852987D02*
X2454252Y1852895D01*
G01X2455583Y1862987D02*
X2455433Y1862895D01*
G01X2454401Y1862987D02*
X2454252Y1862895D01*
G01X2455742Y1803042D02*
X2455580Y1802985D01*
G01X2454561Y1803042D02*
X2454399Y1802985D01*
G01X2455742Y1813042D02*
X2455580Y1812985D01*
G01X2454561Y1813042D02*
X2454399Y1812985D01*
G01X2455742Y1823042D02*
X2455580Y1822985D01*
G01X2454561Y1823042D02*
X2454399Y1822985D01*
G01X2455580Y1832985D02*
X2455739Y1833042D01*
X2455907Y1833061D01*
G01X2455742Y1833042D02*
X2455583Y1832987D01*
X2455433Y1832895D01*
G01X2454561Y1833042D02*
X2454399Y1832985D01*
G01X2455742Y1843042D02*
X2455580Y1842985D01*
G01X2454561Y1843042D02*
X2454399Y1842985D01*
G01X2455742Y1853042D02*
X2455580Y1852985D01*
G01X2454561Y1853042D02*
X2454399Y1852985D01*
G01X2455742Y1863042D02*
X2455580Y1862985D01*
G01X2454561Y1863042D02*
X2454399Y1862985D01*
G01X2498323Y1796860D02*
G03X2497929Y1796466I0J-394D01*
G01Y1795403D02*
G03X2498323Y1795010I394J1D01*
G01X2497880Y1794942D02*
X2497935Y1794839D01*
G01X2497934Y1794840D02*
X2498008Y1794750D01*
G01X2497893Y1794715D02*
X2497833Y1794774D01*
G01X2498098Y1794675D02*
X2498008Y1794750D01*
G01X2497892Y1794716D02*
X2497960Y1794666D01*
G01X2498097Y1794676D02*
X2498200Y1794621D01*
G01X2497958Y1794667D02*
X2498032Y1794628D01*
G01X2497846Y1795053D02*
X2497881Y1794940D01*
G01X2498030Y1794629D02*
X2498109Y1794600D01*
G01X2498198Y1794622D02*
X2498310Y1794588D01*
G01X2498108Y1794600D02*
X2498190Y1794582D01*
G01X2497685Y1795167D02*
X2497701Y1795023D01*
X2497752Y1794892D01*
X2497835Y1794774D01*
G01X2498308Y1794588D02*
X2498425Y1794577D01*
G01X2498188Y1794583D02*
X2498272Y1794577D01*
G01X2497847Y1795051D02*
X2497835Y1795167D01*
G01X2540449Y1796860D02*
X2498323D01*
G01X2497835Y1796703D02*
X2497685D01*
G01X2497835Y1795167D02*
X2497685D01*
G01X2540449Y1795010D02*
X2498323D01*
G01X2501079Y1794774D02*
X2480449D01*
G01X2534012Y1794577D02*
X2498272D01*
G01X2497847Y1796819D02*
X2497835Y1796703D01*
G01X2501866Y1795010D02*
Y1796860D01*
G01X2497835Y1796703D02*
Y1795167D01*
G01X2497685Y1796703D02*
Y1795167D01*
G01X2484386Y1797096D02*
Y1794774D01*
G01X2497881Y1796930D02*
X2497846Y1796817D01*
G01X2497752Y1796978D02*
X2497701Y1796847D01*
X2497685Y1796703D01*
G01X2497935Y1797031D02*
X2497880Y1796928D01*
G01X2497752Y1796978D02*
X2497835Y1797096D01*
G01X2497934Y1797029D02*
X2498008Y1797120D01*
G01X2497929Y1855403D02*
G03X2498323Y1855010I394J1D01*
G01Y1856860D02*
G03X2497929Y1856466I0J-394D01*
G01Y1835403D02*
G03X2498323Y1835010I394J1D01*
G01Y1836860D02*
G03X2497929Y1836466I0J-394D01*
G01X2498323Y1846860D02*
G03X2497929Y1846466I0J-394D01*
G01Y1845403D02*
G03X2498323Y1845010I394J1D01*
G01X2497929Y1859872D02*
G03X2496945Y1860856I-984J0D01*
G01Y1851014D02*
G03X2497929Y1851998I0J984D01*
G01X2496945Y1831014D02*
G03X2497929Y1831998I0J984D01*
G01Y1839872D02*
G03X2496945Y1840856I-984J0D01*
G01X2497929Y1805403D02*
G03X2498323Y1805010I394J1D01*
G01Y1806860D02*
G03X2497929Y1806466I0J-394D01*
G01Y1815403D02*
G03X2498323Y1815010I394J1D01*
G01Y1816860D02*
G03X2497929Y1816466I0J-394D01*
G01X2496945Y1811014D02*
G03X2497929Y1811998I0J984D01*
G01Y1819872D02*
G03X2496945Y1820856I-984J0D01*
G01X2497929Y1799872D02*
G03X2496945Y1800856I-984J0D01*
G01X2489307Y1840856D02*
G03X2488323Y1839872I0J-984D01*
G01Y1831998D02*
G03X2489307Y1831014I984J0D01*
G01Y1860856D02*
G03X2488323Y1859872I0J-984D01*
G01Y1851998D02*
G03X2489307Y1851014I984J0D01*
G01Y1800856D02*
G03X2488323Y1799872I0J-984D01*
G01X2489307Y1820856D02*
G03X2488323Y1819872I0J-984D01*
G01Y1811998D02*
G03X2489307Y1811014I984J0D01*
G01X2497934Y1854840D02*
X2498008Y1854750D01*
G01X2480449Y1865364D02*
X2480842Y1864970D01*
G01X2497893Y1854715D02*
X2497833Y1854774D01*
G01X2497893Y1844715D02*
X2497833Y1844774D01*
G01X2498098Y1854675D02*
X2498008Y1854750D01*
G01X2498098Y1844675D02*
X2498008Y1844750D01*
G01X2497892Y1854716D02*
X2497960Y1854666D01*
G01X2497892Y1844716D02*
X2497960Y1844666D01*
G01X2497880Y1854942D02*
X2497935Y1854839D01*
G01X2497880Y1844942D02*
X2497935Y1844839D01*
G01X2497880Y1834942D02*
X2497935Y1834839D01*
G01X2497880Y1814942D02*
X2497935Y1814839D01*
G01X2497880Y1804942D02*
X2497935Y1804839D01*
G01X2497835Y1854774D02*
X2497753Y1854893D01*
X2497702Y1855024D01*
X2497685Y1855167D01*
G01X2497835Y1844774D02*
X2497753Y1844893D01*
X2497702Y1845024D01*
X2497685Y1845167D01*
G01X2497835Y1854774D02*
X2497752Y1854892D01*
X2497701Y1855023D01*
X2497685Y1855167D01*
G01X2497835Y1844774D02*
X2497752Y1844892D01*
X2497701Y1845023D01*
X2497685Y1845167D01*
G01X2497934Y1844840D02*
X2498008Y1844750D01*
G01X2497934Y1834840D02*
X2498008Y1834750D01*
G01X2497934Y1814840D02*
X2498008Y1814750D01*
G01X2497934Y1804840D02*
X2498008Y1804750D01*
G01X2480449Y1825364D02*
X2480842Y1824970D01*
G01X2497893Y1834715D02*
X2497833Y1834774D01*
G01X2497893Y1814715D02*
X2497833Y1814774D01*
G01X2497893Y1804715D02*
X2497833Y1804774D01*
G01X2498098Y1834675D02*
X2498008Y1834750D01*
G01X2498098Y1814675D02*
X2498008Y1814750D01*
G01X2498098Y1804675D02*
X2498008Y1804750D01*
G01X2497892Y1834716D02*
X2497960Y1834666D01*
G01X2497892Y1814716D02*
X2497960Y1814666D01*
G01X2497892Y1804716D02*
X2497960Y1804666D01*
G01X2498097Y1854676D02*
X2498200Y1854621D01*
G01X2497958Y1854667D02*
X2498032Y1854628D01*
G01X2498097Y1844676D02*
X2498200Y1844621D01*
G01X2497958Y1844667D02*
X2498032Y1844628D01*
G01X2498097Y1834676D02*
X2498200Y1834621D01*
G01X2497958Y1834667D02*
X2498032Y1834628D01*
G01X2498097Y1814676D02*
X2498200Y1814621D01*
G01X2497958Y1814667D02*
X2498032Y1814628D01*
G01X2498097Y1804676D02*
X2498200Y1804621D01*
G01X2497958Y1804667D02*
X2498032Y1804628D01*
G01X2498030Y1854629D02*
X2498109Y1854600D01*
G01X2498030Y1844629D02*
X2498109Y1844600D01*
G01X2498030Y1834629D02*
X2498109Y1834600D01*
G01X2498198Y1854622D02*
X2498310Y1854588D01*
G01X2498198Y1844622D02*
X2498310Y1844588D01*
G01X2497846Y1855053D02*
X2497881Y1854940D01*
G01X2497846Y1845053D02*
X2497881Y1844940D01*
G01X2497846Y1835053D02*
X2497881Y1834940D01*
G01X2497846Y1815053D02*
X2497881Y1814940D01*
G01X2497846Y1805053D02*
X2497881Y1804940D01*
G01X2498030Y1814629D02*
X2498109Y1814600D01*
G01X2498030Y1804629D02*
X2498109Y1804600D01*
G01X2498198Y1834622D02*
X2498310Y1834588D01*
G01X2498198Y1814622D02*
X2498310Y1814588D01*
G01X2498198Y1804622D02*
X2498310Y1804588D01*
G01X2498108Y1854600D02*
X2498190Y1854582D01*
G01X2498108Y1844600D02*
X2498190Y1844582D01*
G01X2498108Y1834600D02*
X2498190Y1834582D01*
G01X2498108Y1814600D02*
X2498190Y1814582D01*
G01X2498108Y1804600D02*
X2498190Y1804582D01*
G01X2497142Y1864577D02*
X2493205Y1864970D01*
G01X2498308Y1854588D02*
X2498425Y1854577D01*
G01X2498308Y1844588D02*
X2498425Y1844577D01*
G01X2498188Y1854583D02*
X2498272Y1854577D01*
G01X2497685Y1835167D02*
X2497701Y1835023D01*
X2497752Y1834892D01*
X2497835Y1834774D01*
G01X2497685Y1815167D02*
X2497701Y1815023D01*
X2497752Y1814892D01*
X2497835Y1814774D01*
G01X2497685Y1805167D02*
X2497701Y1805023D01*
X2497752Y1804892D01*
X2497835Y1804774D01*
G01X2498308Y1834588D02*
X2498425Y1834577D01*
G01X2497142Y1824577D02*
X2493205Y1824970D01*
G01X2498308Y1814588D02*
X2498425Y1814577D01*
G01X2498308Y1804588D02*
X2498425Y1804577D01*
G01X2498188Y1844583D02*
X2498272Y1844577D01*
G01X2498188Y1834583D02*
X2498272Y1834577D01*
G01X2498188Y1814583D02*
X2498272Y1814577D01*
G01X2498188Y1804583D02*
X2498272Y1804577D01*
G01X2540449Y1865010D02*
X2501079D01*
G01X2480842Y1864970D02*
X2501079D01*
G01X2480449Y1864577D02*
X2534012D01*
G01X2501079Y1863809D02*
X2480449D01*
G01X2496945Y1860856D02*
X2480449D01*
G01Y1858888D02*
X2492079D01*
G01X2501079D02*
X2497929D01*
G01X2534012Y1857293D02*
X2498272D01*
G01X2501079Y1857096D02*
X2480449D01*
G01X2540449Y1856860D02*
X2498323D01*
G01X2497835Y1856703D02*
X2497685D01*
G01X2497835Y1855167D02*
X2497685D01*
G01X2540449Y1855010D02*
X2498323D01*
G01X2501079Y1854774D02*
X2480449D01*
G01X2534012Y1854577D02*
X2498272D01*
G01X2480449Y1852982D02*
X2492079D01*
G01X2501079D02*
X2497929D01*
G01X2496945Y1851014D02*
X2480449D01*
G01X2501079Y1848061D02*
X2480449D01*
G01X2534012Y1847293D02*
X2498272D01*
G01X2501079Y1847096D02*
X2480449D01*
G01X2540449Y1846860D02*
X2498323D01*
G01X2497835Y1846703D02*
X2497685D01*
G01X2497835Y1845167D02*
X2497685D01*
G01X2540449Y1845010D02*
X2498323D01*
G01X2501079Y1844774D02*
X2480449D01*
G01X2534012Y1844577D02*
X2498272D01*
G01X2501079Y1843809D02*
X2480449D01*
G01X2496945Y1840856D02*
X2480449D01*
G01Y1838888D02*
X2492079D01*
G01X2501079D02*
X2497929D01*
G01X2534012Y1837293D02*
X2498272D01*
G01X2480449Y1837096D02*
X2501079D01*
G01X2540449Y1836860D02*
X2498323D01*
G01X2497835Y1836703D02*
X2497685D01*
G01X2497835Y1835167D02*
X2497685D01*
G01X2540449Y1835010D02*
X2498323D01*
G01X2501079Y1834774D02*
X2480449D01*
G01X2534012Y1834577D02*
X2498272D01*
G01X2480449Y1832982D02*
X2492079D01*
G01X2501079D02*
X2497929D01*
G01X2496945Y1831014D02*
X2480449D01*
G01X2501079Y1828061D02*
X2480449D01*
G01X2534012Y1827293D02*
X2480449D01*
G01X2480842Y1826900D02*
X2501079D01*
G01X2540449Y1826860D02*
X2501079D01*
G01X2540449Y1825010D02*
X2501079D01*
G01Y1824970D02*
X2480842D01*
G01X2534012Y1824577D02*
X2480449D01*
G01X2501079Y1823809D02*
X2480449D01*
G01X2496945Y1820856D02*
X2480449D01*
G01Y1818888D02*
X2492079D01*
G01X2501079D02*
X2497929D01*
G01X2534012Y1817293D02*
X2498272D01*
G01X2501079Y1817096D02*
X2480449D01*
G01X2540449Y1816860D02*
X2498323D01*
G01X2497835Y1816703D02*
X2497685D01*
G01X2497835Y1815167D02*
X2497685D01*
G01X2540449Y1815010D02*
X2498323D01*
G01X2501079Y1814774D02*
X2480449D01*
G01X2534012Y1814577D02*
X2498272D01*
G01X2480449Y1812982D02*
X2492079D01*
G01X2501079D02*
X2497929D01*
G01X2498188Y1857287D02*
X2498272Y1857293D01*
G01X2497847Y1855051D02*
X2497835Y1855167D01*
G01X2497847Y1845051D02*
X2497835Y1845167D01*
G01X2497847Y1835051D02*
X2497835Y1835167D01*
G01X2497847Y1815051D02*
X2497835Y1815167D01*
G01X2497847Y1805051D02*
X2497835Y1805167D01*
G01X2496945Y1811014D02*
X2480449D01*
G01X2501079Y1808061D02*
X2480449D01*
G01X2534012Y1807293D02*
X2498272D01*
G01X2501079Y1807096D02*
X2480449D01*
G01X2540449Y1806860D02*
X2498323D01*
G01X2497835Y1806703D02*
X2497685D01*
G01X2497835Y1805167D02*
X2497685D01*
G01X2540449Y1805010D02*
X2498323D01*
G01X2501079Y1804774D02*
X2480449D01*
G01X2534012Y1804577D02*
X2498272D01*
G01X2501079Y1803809D02*
X2480449D01*
G01X2496945Y1800856D02*
X2480449D01*
G01Y1798888D02*
X2492079D01*
G01X2501079D02*
X2497929D01*
G01X2534012Y1797293D02*
X2498272D01*
G01X2501079Y1797096D02*
X2480449D01*
G01X2498188Y1847287D02*
X2498272Y1847293D01*
G01X2498188Y1837287D02*
X2498272Y1837293D01*
G01X2498188Y1817287D02*
X2498272Y1817293D01*
G01X2498188Y1807287D02*
X2498272Y1807293D01*
G01X2498188Y1797287D02*
X2498272Y1797293D01*
G01X2498308Y1857282D02*
X2498425Y1857293D01*
G01X2498308Y1847282D02*
X2498425Y1847293D01*
G01X2498308Y1837282D02*
X2498425Y1837293D01*
G01X2497142Y1827293D02*
X2493205Y1826900D01*
G01X2498308Y1807282D02*
X2498425Y1807293D01*
G01X2498308Y1797282D02*
X2498425Y1797293D01*
G01X2497847Y1806819D02*
X2497835Y1806703D01*
G01X2497847Y1816819D02*
X2497835Y1816703D01*
G01X2501866Y1855010D02*
Y1856860D01*
G01Y1845010D02*
Y1846860D01*
G01Y1835010D02*
Y1836860D01*
G01Y1815010D02*
Y1816860D01*
G01Y1806860D02*
Y1805010D01*
G01X2497929Y1806466D02*
Y1805403D01*
G01Y1819872D02*
Y1811998D01*
G01Y1839872D02*
Y1831998D01*
G01Y1846466D02*
Y1845403D01*
G01Y1859872D02*
Y1851998D01*
G01X2497835Y1806703D02*
Y1805167D01*
G01Y1816703D02*
Y1815167D01*
G01Y1836703D02*
Y1835167D01*
G01Y1846703D02*
Y1845167D01*
G01Y1856703D02*
Y1855167D01*
G01X2497685Y1806703D02*
Y1805167D01*
G01Y1816703D02*
Y1815167D01*
G01Y1836703D02*
Y1835167D01*
G01Y1846703D02*
Y1845167D01*
G01Y1856703D02*
Y1855167D01*
G01X2497421Y1864577D02*
Y1827293D01*
G01X2497269Y1804774D02*
Y1797096D01*
G01Y1814774D02*
Y1807096D01*
G01Y1824577D02*
Y1817096D01*
G01Y1834774D02*
Y1827293D01*
G01Y1844774D02*
Y1837096D01*
G01Y1854774D02*
Y1847096D01*
G01Y1864577D02*
Y1857096D01*
G01X2497142Y1864577D02*
Y1827293D01*
G01X2492079Y1818888D02*
Y1812982D01*
G01Y1838888D02*
Y1832982D01*
G01Y1858888D02*
Y1852982D01*
G01X2491275Y1818888D02*
Y1812982D01*
G01Y1838888D02*
Y1832982D01*
G01Y1858888D02*
Y1852982D01*
G01X2489520Y1832982D02*
Y1838888D01*
G01Y1818888D02*
Y1812982D01*
G01Y1858888D02*
Y1852982D01*
G01X2488716Y1818888D02*
Y1812982D01*
G01Y1838888D02*
Y1832982D01*
G01Y1858888D02*
Y1852982D01*
G01X2488323Y1819872D02*
Y1811998D01*
G01Y1839872D02*
Y1831998D01*
G01Y1859872D02*
Y1851998D01*
G01X2486354Y1818888D02*
Y1812982D01*
G01Y1838888D02*
Y1832982D01*
G01Y1858888D02*
Y1852982D01*
G01X2484386Y1807096D02*
Y1804774D01*
G01Y1817096D02*
Y1814774D01*
G01Y1837096D02*
Y1834774D01*
G01Y1847096D02*
Y1844774D01*
G01Y1857096D02*
Y1854774D01*
G01X2483598Y1808809D02*
Y1803061D01*
G01Y1818809D02*
Y1813061D01*
G01Y1824970D02*
Y1823061D01*
G01Y1828809D02*
Y1826900D01*
G01Y1838809D02*
Y1833061D01*
G01Y1848809D02*
Y1843061D01*
G01Y1858809D02*
Y1853061D01*
G01Y1864970D02*
Y1863061D01*
G01X2482811Y1803061D02*
Y1798809D01*
G01Y1813061D02*
Y1808809D01*
G01Y1823061D02*
Y1818809D01*
G01Y1833061D02*
Y1828809D01*
G01Y1843061D02*
Y1838809D01*
G01Y1853061D02*
Y1848809D01*
G01Y1863061D02*
Y1858809D01*
G01X2481630Y1803061D02*
Y1798809D01*
G01Y1813061D02*
Y1808809D01*
G01Y1823061D02*
Y1818809D01*
G01Y1833061D02*
Y1828809D01*
G01Y1843061D02*
Y1838809D01*
G01Y1853061D02*
Y1848809D01*
G01Y1863061D02*
Y1858809D01*
G01X2480842Y1824970D02*
Y1823809D01*
G01Y1828061D02*
Y1826900D01*
G01Y1864970D02*
Y1863809D01*
G01X2479183Y1803061D02*
Y1798809D01*
G01Y1813061D02*
Y1808809D01*
G01Y1823061D02*
Y1818809D01*
G01Y1833061D02*
Y1828809D01*
G01Y1843061D02*
Y1838809D01*
G01Y1853061D02*
Y1848809D01*
G01Y1863061D02*
Y1858809D01*
G01X2478002Y1803061D02*
Y1798809D01*
G01Y1813061D02*
Y1808809D01*
G01Y1823061D02*
Y1818809D01*
G01Y1833061D02*
Y1828809D01*
G01Y1843061D02*
Y1838809D01*
G01Y1853061D02*
Y1848809D01*
G01Y1863061D02*
Y1858809D01*
G01X2476821Y1803061D02*
Y1798809D01*
G01Y1813061D02*
Y1808809D01*
G01Y1823061D02*
Y1818809D01*
G01Y1833061D02*
Y1828809D01*
G01Y1843061D02*
Y1838809D01*
G01Y1853061D02*
Y1848809D01*
G01Y1863061D02*
Y1858809D01*
G01X2472884Y1803061D02*
Y1798809D01*
G01Y1813061D02*
Y1808809D01*
G01Y1823061D02*
Y1818809D01*
G01Y1833061D02*
Y1828809D01*
G01Y1843061D02*
Y1838809D01*
G01Y1853061D02*
Y1848809D01*
G01Y1863061D02*
Y1858809D01*
G01X2472281Y1803061D02*
Y1798809D01*
G01Y1813061D02*
Y1808809D01*
G01Y1823061D02*
Y1818809D01*
G01Y1833061D02*
Y1828809D01*
G01Y1843061D02*
Y1838809D01*
G01Y1853061D02*
Y1848809D01*
G01Y1863061D02*
Y1858809D01*
G01X2471678Y1803061D02*
Y1798809D01*
G01Y1813061D02*
Y1808809D01*
G01Y1823061D02*
Y1818809D01*
G01Y1833061D02*
Y1828809D01*
G01Y1843061D02*
Y1838809D01*
G01Y1853061D02*
Y1848809D01*
G01Y1863061D02*
Y1858809D01*
G01X2462556Y1803061D02*
Y1798809D01*
G01Y1813061D02*
Y1808809D01*
G01Y1823061D02*
Y1818809D01*
G01Y1833061D02*
Y1828809D01*
G01Y1843061D02*
Y1838809D01*
G01Y1853061D02*
Y1848809D01*
G01Y1863061D02*
Y1858809D01*
G01X2461953Y1803061D02*
Y1798809D01*
G01Y1813061D02*
Y1808809D01*
G01Y1823061D02*
Y1818809D01*
G01Y1833061D02*
Y1828809D01*
G01Y1843061D02*
Y1838809D01*
G01Y1853061D02*
Y1848809D01*
G01Y1863061D02*
Y1858809D01*
G01X2498190Y1857287D02*
X2498108Y1857270D01*
G01X2498190Y1847287D02*
X2498108Y1847270D01*
G01X2498190Y1837287D02*
X2498108Y1837270D01*
G01X2498190Y1817287D02*
X2498108Y1817270D01*
G01X2498190Y1807287D02*
X2498108Y1807270D01*
G01X2498190Y1797287D02*
X2498108Y1797270D01*
G01X2497685Y1806703D02*
X2497702Y1806846D01*
X2497753Y1806977D01*
X2497835Y1807096D01*
G01X2497685Y1806703D02*
X2497701Y1806847D01*
X2497752Y1806978D01*
X2497835Y1807096D01*
G01X2497847Y1836819D02*
X2497835Y1836703D01*
G01X2497847Y1846819D02*
X2497835Y1846703D01*
G01X2497847Y1856819D02*
X2497835Y1856703D01*
G01X2497881Y1806930D02*
X2497846Y1806817D01*
G01X2497881Y1816930D02*
X2497846Y1816817D01*
G01X2497881Y1836930D02*
X2497846Y1836817D01*
G01X2497881Y1846930D02*
X2497846Y1846817D01*
G01X2497881Y1856930D02*
X2497846Y1856817D01*
G01X2497935Y1807031D02*
X2497880Y1806928D01*
G01X2497935Y1817031D02*
X2497880Y1816928D01*
G01X2497935Y1837031D02*
X2497880Y1836928D01*
G01X2497935Y1847031D02*
X2497880Y1846928D01*
G01X2497935Y1857031D02*
X2497880Y1856928D01*
G01X2497835Y1817096D02*
X2497752Y1816978D01*
X2497701Y1816847D01*
X2497685Y1816703D01*
G01X2497835Y1837096D02*
X2497752Y1836978D01*
X2497701Y1836847D01*
X2497685Y1836703D01*
G01X2497835Y1847096D02*
X2497752Y1846978D01*
X2497701Y1846847D01*
X2497685Y1846703D01*
G01X2497835Y1857096D02*
X2497752Y1856978D01*
X2497701Y1856847D01*
X2497685Y1856703D01*
G01X2497835Y1817096D02*
X2497753Y1816977D01*
X2497702Y1816846D01*
X2497685Y1816703D01*
G01X2497835Y1837096D02*
X2497753Y1836977D01*
X2497702Y1836846D01*
X2497685Y1836703D01*
G01X2497835Y1847096D02*
X2497753Y1846977D01*
X2497702Y1846846D01*
X2497685Y1846703D01*
G01X2497934Y1807029D02*
X2498008Y1807120D01*
G01X2497934Y1817029D02*
X2498008Y1817120D01*
G01X2497934Y1837029D02*
X2498008Y1837120D01*
G01X2497934Y1847029D02*
X2498008Y1847120D01*
G01X2497934Y1857029D02*
X2498008Y1857120D01*
G01X2497893Y1797155D02*
X2497833Y1797096D01*
G01X2497893Y1807155D02*
X2497833Y1807096D01*
G01X2497893Y1817155D02*
X2497833Y1817096D01*
G01X2497893Y1837155D02*
X2497833Y1837096D01*
G01X2497893Y1847155D02*
X2497833Y1847096D01*
G01X2497893Y1857155D02*
X2497833Y1857096D01*
G01X2480842Y1826900D02*
X2480449Y1826506D01*
G01Y1866506D02*
X2480842Y1866900D01*
G01X2497960Y1807203D02*
X2497892Y1807154D01*
G01X2497960Y1817203D02*
X2497892Y1817154D01*
G01X2498098Y1807195D02*
X2498008Y1807120D01*
G01X2498098Y1817195D02*
X2498008Y1817120D01*
G01X2498098Y1837195D02*
X2498008Y1837120D01*
G01X2498098Y1847195D02*
X2498008Y1847120D01*
G01X2498098Y1857195D02*
X2498008Y1857120D01*
G01X2497958Y1797202D02*
X2498030Y1797241D01*
G01X2498097Y1797193D02*
X2498198Y1797248D01*
G01X2497960Y1837203D02*
X2497892Y1837154D01*
G01X2497960Y1847203D02*
X2497892Y1847154D01*
G01X2497960Y1857203D02*
X2497892Y1857154D01*
G01X2498200Y1797249D02*
X2498098Y1797195D01*
X2498008Y1797120D01*
G01X2498032Y1797242D02*
X2497960Y1797203D01*
X2497892Y1797154D01*
G01X2498200Y1807249D02*
X2498097Y1807193D01*
G01X2498032Y1807242D02*
X2497958Y1807202D01*
G01X2498032Y1817242D02*
X2497958Y1817202D01*
G01X2498200Y1837249D02*
X2498097Y1837193D01*
G01X2498032Y1837242D02*
X2497958Y1837202D01*
G01X2498200Y1847249D02*
X2498097Y1847193D01*
G01X2498032Y1847242D02*
X2497958Y1847202D01*
G01X2498200Y1857249D02*
X2498097Y1857193D01*
G01X2498310Y1797282D02*
X2498198Y1797248D01*
G01X2498310Y1807282D02*
X2498198Y1807248D01*
G01Y1817248D02*
X2498308Y1817282D01*
X2498425Y1817293D01*
G01X2498109Y1797270D02*
X2498030Y1797241D01*
G01X2498109Y1807270D02*
X2498030Y1807241D01*
G01X2498109Y1817270D02*
X2498030Y1817241D01*
G01X2498109Y1837270D02*
X2498030Y1837241D01*
G01X2498109Y1847270D02*
X2498030Y1847241D01*
G01Y1857241D02*
X2498108Y1857270D01*
G01X2498310Y1817282D02*
X2498200Y1817249D01*
X2498097Y1817193D01*
G01X2498310Y1837282D02*
X2498198Y1837248D01*
G01X2498310Y1847282D02*
X2498198Y1847248D01*
G01X2498310Y1857282D02*
X2498198Y1857248D01*
G01X2498109Y1857270D02*
X2498032Y1857242D01*
X2497958Y1857202D01*
G01X2455197Y1869249D02*
X2455305Y1869097D01*
G01X2454016Y1869249D02*
X2454124Y1869097D01*
G01X2455436Y1868973D02*
X2455305Y1869097D01*
G01X2454255Y1868973D02*
X2454124Y1869097D01*
G01X2455433Y1868975D02*
X2455583Y1868883D01*
G01X2454252Y1868975D02*
X2454401Y1868883D01*
G01X2455580Y1868885D02*
X2455742Y1868828D01*
G01X2454399Y1868885D02*
X2454561Y1868828D01*
G01X2455120Y1869415D02*
X2455072Y1869599D01*
X2455055Y1869793D01*
G01X2453938Y1869418D02*
X2454018Y1869246D01*
G01X2455739Y1868828D02*
X2455907Y1868809D01*
G01X2454558Y1868828D02*
X2454726Y1868809D01*
G01X2455071Y1869602D02*
X2455119Y1869418D01*
X2455199Y1869246D01*
G01X2453890Y1869602D02*
X2453939Y1869415D01*
G01X2455055Y1869793D02*
X2453874D01*
G01X2483598Y1868809D02*
X2454726D01*
G01X2460764Y1873061D02*
Y1868809D01*
G01X2459583Y1873061D02*
Y1868809D01*
G01X2455055Y1872077D02*
Y1869793D01*
G01X2453874Y1872077D02*
Y1869793D01*
G01X2453891Y1869599D02*
X2453874Y1869793D01*
G01X2450901Y1889695D02*
G03Y1885482I0J-2107D01*
G01X2452890Y1886762D02*
X2453874Y1885777D01*
G01X2454255Y1878973D02*
X2454124Y1879097D01*
G01X2455433Y1878975D02*
X2455580Y1878885D01*
X2455742Y1878828D01*
G01X2455197Y1879249D02*
X2455305Y1879097D01*
G01X2454016Y1879249D02*
X2454124Y1879097D01*
G01X2454252Y1878975D02*
X2454401Y1878883D01*
G01X2455583D02*
X2455436Y1878973D01*
X2455305Y1879097D01*
G01X2454399Y1878885D02*
X2454561Y1878828D01*
G01X2455071Y1879602D02*
X2455120Y1879415D01*
G01X2453890Y1879602D02*
X2453939Y1879415D01*
G01X2455119Y1879418D02*
X2455199Y1879246D01*
G01X2453938Y1879418D02*
X2454018Y1879246D01*
G01X2455739Y1878828D02*
X2455907Y1878809D01*
G01X2454558Y1878828D02*
X2454726Y1878809D01*
G01X2465303Y1938927D02*
X2454110D01*
G01X2465303Y1935502D02*
X2454110D01*
G01X2465303Y1933927D02*
X2454110D01*
G01X2465303Y1930502D02*
X2454110D01*
G01X2465303Y1928927D02*
X2454110D01*
G01X2465303Y1925502D02*
X2454110D01*
G01X2465303Y1923927D02*
X2454110D01*
G01X2465303Y1920502D02*
X2454110D01*
G01X2465303Y1918927D02*
X2454110D01*
G01X2465303Y1915502D02*
X2454110D01*
G01X2465303Y1913927D02*
X2454110D01*
G01X2465303Y1910502D02*
X2454110D01*
G01X2465303Y1908927D02*
X2454110D01*
G01X2465303Y1905502D02*
X2454110D01*
G01X2465303Y1903927D02*
X2454110D01*
G01X2465303Y1900502D02*
X2454110D01*
G01X2465303Y1898927D02*
X2454110D01*
G01X2465303Y1895502D02*
X2454110D01*
G01X2465303Y1893927D02*
X2454110D01*
G01X2490685Y1891368D02*
X2452890D01*
G01X2450901Y1889695D02*
X2478480D01*
G01X2480449Y1889400D02*
X2453874D01*
G01X2490685Y1889006D02*
X2452890D01*
G01X2480449Y1885777D02*
X2453874D01*
G01X2478480Y1885482D02*
X2450901D01*
G01X2501079Y1884970D02*
X2452890D01*
G01X2534012Y1884577D02*
X2456399D01*
G01X2501079Y1883809D02*
X2452890D01*
G01X2483598Y1883061D02*
X2454726D01*
G01X2455055Y1882077D02*
X2453874D01*
G01X2455055Y1879793D02*
X2453874D01*
G01X2483598Y1878809D02*
X2454726D01*
G01X2483598Y1873061D02*
X2454726D01*
G01X2455055Y1872077D02*
X2453874D01*
G01X2454558Y1883042D02*
X2454726Y1883061D01*
G01X2455739Y1883042D02*
X2455907Y1883061D01*
G01X2454558Y1873042D02*
X2454726Y1873061D01*
G01X2455739Y1873042D02*
X2455907Y1873061D01*
G01X2460764Y1883061D02*
Y1878809D01*
G01X2460173Y1895502D02*
Y1893927D01*
G01Y1900502D02*
Y1898927D01*
G01Y1905502D02*
Y1903927D01*
G01Y1910502D02*
Y1908927D01*
G01Y1915502D02*
Y1913927D01*
G01Y1920502D02*
Y1918927D01*
G01Y1925502D02*
Y1923927D01*
G01Y1930502D02*
Y1928927D01*
G01Y1935502D02*
Y1933927D01*
G01Y1940502D02*
Y1938927D01*
G01X2459583Y1883061D02*
Y1878809D01*
G01Y1895502D02*
Y1893927D01*
G01Y1900502D02*
Y1898927D01*
G01Y1905502D02*
Y1903927D01*
G01Y1910502D02*
Y1908927D01*
G01Y1915502D02*
Y1913927D01*
G01Y1920502D02*
Y1918927D01*
G01Y1925502D02*
Y1923927D01*
G01Y1930502D02*
Y1928927D01*
G01Y1935502D02*
Y1933927D01*
G01Y1940502D02*
Y1938927D01*
G01X2456827Y1885777D02*
Y1884577D01*
G01Y1891368D02*
Y1889400D01*
G01X2456399Y1884970D02*
Y1884577D01*
G01X2455055Y1882077D02*
Y1879793D01*
G01X2454701Y1895502D02*
Y1893927D01*
G01Y1900502D02*
Y1898927D01*
G01Y1905502D02*
Y1903927D01*
G01Y1910502D02*
Y1908927D01*
G01Y1915502D02*
Y1913927D01*
G01Y1920502D02*
Y1918927D01*
G01Y1925502D02*
Y1923927D01*
G01Y1930502D02*
Y1928927D01*
G01Y1935502D02*
Y1933927D01*
G01Y1940502D02*
Y1938927D01*
G01X2454110Y1895502D02*
Y1893927D01*
G01Y1900502D02*
Y1898927D01*
G01Y1905502D02*
Y1903927D01*
G01Y1910502D02*
Y1908927D01*
G01Y1915502D02*
Y1913927D01*
G01Y1920502D02*
Y1918927D01*
G01Y1925502D02*
Y1923927D01*
G01Y1930502D02*
Y1928927D01*
G01Y1935502D02*
Y1933927D01*
G01Y1940502D02*
Y1938927D01*
G01X2453874Y1882077D02*
Y1879793D01*
G01Y1889006D02*
Y1883809D01*
G01X2452890Y1891368D02*
Y1883809D01*
G01X2455072Y1879599D02*
X2455055Y1879793D01*
G01X2453891Y1879599D02*
X2453874Y1879793D01*
G01X2455072Y1872271D02*
X2455055Y1872077D01*
G01X2455072Y1882271D02*
X2455055Y1882077D01*
G01X2453891Y1872271D02*
X2453874Y1872077D01*
G01X2453891Y1882271D02*
X2453874Y1882077D01*
G01X2455120Y1872455D02*
X2455071Y1872268D01*
G01X2453939Y1872455D02*
X2453890Y1872268D01*
G01X2455120Y1882455D02*
X2455071Y1882268D01*
G01X2453939Y1882455D02*
X2453890Y1882268D01*
G01X2455199Y1872624D02*
X2455119Y1872452D01*
G01X2454018Y1872624D02*
X2453938Y1872452D01*
G01X2455199Y1882624D02*
X2455119Y1882452D01*
G01X2454018Y1882624D02*
X2453938Y1882452D01*
G01X2455197Y1872621D02*
X2455305Y1872773D01*
G01X2454016Y1872621D02*
X2454124Y1872773D01*
G01X2455197Y1882621D02*
X2455305Y1882773D01*
G01X2454016Y1882621D02*
X2454124Y1882773D01*
G01X2455436Y1872896D02*
X2455305Y1872773D01*
G01X2454255Y1872896D02*
X2454124Y1872773D01*
G01X2455436Y1882896D02*
X2455305Y1882773D01*
G01X2454255Y1882896D02*
X2454124Y1882773D01*
G01X2452890Y1888415D02*
X2453874Y1889400D01*
G01X2455583Y1872987D02*
X2455433Y1872895D01*
G01X2454401Y1872987D02*
X2454252Y1872895D01*
G01X2455583Y1882987D02*
X2455433Y1882895D01*
G01X2454401Y1882987D02*
X2454252Y1882895D01*
G01X2455742Y1873042D02*
X2455580Y1872985D01*
G01X2454561Y1873042D02*
X2454399Y1872985D01*
G01X2455742Y1883042D02*
X2455580Y1882985D01*
G01X2454561Y1883042D02*
X2454399Y1882985D01*
G01X2501079Y1868061D02*
X2480449D01*
G01X2534012Y1867293D02*
X2480449D01*
G01X2501079Y1866900D02*
X2480842D01*
G01X2540449Y1866860D02*
X2501079D01*
G01X2497142Y1867293D02*
X2493205Y1866900D01*
G01X2497421Y1884577D02*
Y1867293D01*
G01X2497269Y1874774D02*
Y1867293D01*
G01X2497142Y1884577D02*
Y1867293D01*
G01X2483598Y1868809D02*
Y1866900D01*
G01X2482811Y1873061D02*
Y1868809D01*
G01X2481630Y1873061D02*
Y1868809D01*
G01X2480842Y1866900D02*
Y1868061D01*
G01X2479183Y1873061D02*
Y1868809D01*
G01X2478002Y1873061D02*
Y1868809D01*
G01X2476821Y1873061D02*
Y1868809D01*
G01X2472884Y1873061D02*
Y1868809D01*
G01X2472281Y1873061D02*
Y1868809D01*
G01X2471678Y1873061D02*
Y1868809D01*
G01X2462556Y1873061D02*
Y1868809D01*
G01X2461953Y1873061D02*
Y1868809D01*
G01X2502654Y1938986D02*
G03X2502359Y1938907I0J-590D01*
G01Y1935522D02*
G03X2502654Y1935443I295J511D01*
G01Y1933986D02*
G03X2502359Y1933907I0J-590D01*
G01Y1930522D02*
G03X2502654Y1930443I295J511D01*
G01Y1928986D02*
G03X2502359Y1928907I0J-590D01*
G01X2501008Y1938218D02*
G03X2501303Y1938298I-2J590D01*
G01Y1936131D02*
G03X2501008Y1936211I-297J-511D01*
G01Y1933218D02*
G03X2501303Y1933298I-2J590D01*
G01Y1931131D02*
G03X2501008Y1931211I-297J-511D01*
G01Y1928218D02*
G03X2501303Y1928298I-2J590D01*
G01X2496984Y1938337D02*
G03X2496394Y1938927I-590J0D01*
G01Y1935502D02*
G03X2496984Y1936092I0J590D01*
G01Y1933337D02*
G03X2496394Y1933927I-590J0D01*
G01Y1930502D02*
G03X2496984Y1931092I0J590D01*
G01Y1928337D02*
G03X2496394Y1928927I-590J0D01*
G01X2502359Y1925522D02*
G03X2502654Y1925443I295J511D01*
G01Y1923986D02*
G03X2502359Y1923907I0J-590D01*
G01Y1920522D02*
G03X2502654Y1920443I295J511D01*
G01Y1918986D02*
G03X2502359Y1918907I0J-590D01*
G01Y1915522D02*
G03X2502654Y1915443I295J511D01*
G01Y1913986D02*
G03X2502359Y1913907I0J-590D01*
G01Y1910522D02*
G03X2502654Y1910443I295J511D01*
G01Y1908986D02*
G03X2502359Y1908907I0J-590D01*
G01Y1905522D02*
G03X2502654Y1905443I295J511D01*
G01Y1903986D02*
G03X2502359Y1903907I0J-590D01*
G01Y1900522D02*
G03X2502654Y1900443I295J511D01*
G01X2501303Y1926131D02*
G03X2501008Y1926211I-297J-511D01*
G01Y1923218D02*
G03X2501303Y1923298I-2J590D01*
G01Y1921131D02*
G03X2501008Y1921211I-297J-511D01*
G01Y1918218D02*
G03X2501303Y1918298I-2J590D01*
G01Y1916131D02*
G03X2501008Y1916211I-297J-511D01*
G01Y1913218D02*
G03X2501303Y1913298I-2J590D01*
G01Y1911131D02*
G03X2501008Y1911211I-297J-511D01*
G01Y1908218D02*
G03X2501303Y1908298I-2J590D01*
G01Y1906131D02*
G03X2501008Y1906211I-297J-511D01*
G01Y1903218D02*
G03X2501303Y1903298I-2J590D01*
G01Y1901131D02*
G03X2501008Y1901211I-297J-511D01*
G01X2502654Y1898986D02*
G03X2502359Y1898907I0J-590D01*
G01X2501008Y1898218D02*
G03X2501303Y1898298I-2J590D01*
G01Y1896131D02*
G03X2501008Y1896211I-297J-511D01*
G01X2502359Y1895522D02*
G03X2502654Y1895443I295J511D01*
G01Y1893986D02*
G03X2502359Y1893907I0J-590D01*
G01X2501008Y1893218D02*
G03X2501303Y1893298I-2J590D01*
G01X2496394Y1925502D02*
G03X2496984Y1926092I0J590D01*
G01Y1923337D02*
G03X2496394Y1923927I-590J0D01*
G01Y1920502D02*
G03X2496984Y1921092I0J590D01*
G01Y1918337D02*
G03X2496394Y1918927I-590J0D01*
G01Y1915502D02*
G03X2496984Y1916092I0J590D01*
G01Y1913337D02*
G03X2496394Y1913927I-590J0D01*
G01Y1910502D02*
G03X2496984Y1911092I0J590D01*
G01Y1908337D02*
G03X2496394Y1908927I-590J0D01*
G01Y1905502D02*
G03X2496984Y1906092I0J590D01*
G01Y1903337D02*
G03X2496394Y1903927I-590J0D01*
G01Y1900502D02*
G03X2496984Y1901092I0J590D01*
G01X2497929Y1875403D02*
G03X2498323Y1875010I394J1D01*
G01Y1876860D02*
G03X2497929Y1876466I0J-394D01*
G01X2496984Y1898337D02*
G03X2496394Y1898927I-590J0D01*
G01Y1895502D02*
G03X2496984Y1896092I0J590D01*
G01Y1893337D02*
G03X2496394Y1893927I-590J0D01*
G01X2497929Y1879872D02*
G03X2496945Y1880856I-984J0D01*
G01X2495961Y1938927D02*
G03X2495666Y1938848I0J-591D01*
G01Y1935581D02*
G03X2495961Y1935502I295J512D01*
G01Y1933927D02*
G03X2495666Y1933848I0J-591D01*
G01Y1930581D02*
G03X2495961Y1930502I295J512D01*
G01Y1928927D02*
G03X2495666Y1928848I0J-591D01*
G01Y1925581D02*
G03X2495961Y1925502I295J512D01*
G01Y1923927D02*
G03X2495666Y1923848I0J-591D01*
G01Y1920581D02*
G03X2495961Y1920502I295J512D01*
G01Y1918927D02*
G03X2495666Y1918848I0J-591D01*
G01Y1915581D02*
G03X2495961Y1915502I295J512D01*
G01Y1913927D02*
G03X2495666Y1913848I0J-591D01*
G01Y1910581D02*
G03X2495961Y1910502I295J512D01*
G01Y1908927D02*
G03X2495666Y1908848I0J-591D01*
G01Y1905581D02*
G03X2495961Y1905502I295J512D01*
G01Y1903927D02*
G03X2495666Y1903848I0J-591D01*
G01Y1900581D02*
G03X2495961Y1900502I295J512D01*
G01Y1898927D02*
G03X2495666Y1898848I0J-591D01*
G01Y1895581D02*
G03X2495961Y1895502I295J512D01*
G01Y1893927D02*
G03X2495666Y1893848I0J-591D01*
G01X2489307Y1880856D02*
G03X2488323Y1879872I0J-984D01*
G01X2496945Y1871014D02*
G03X2497929Y1871998I0J984D01*
G01X2488323D02*
G03X2489307Y1871014I984J0D01*
G01X2480449Y1879872D02*
G03X2476512Y1883809I-3937J0D01*
G01X2497835Y1874774D02*
X2497753Y1874893D01*
X2497702Y1875024D01*
X2497685Y1875167D01*
G01X2497835Y1874774D02*
X2497752Y1874892D01*
X2497701Y1875023D01*
X2497685Y1875167D01*
G01X2497934Y1874840D02*
X2498008Y1874750D01*
G01X2465303Y1938927D02*
X2465496Y1938730D01*
G01X2465060Y1938927D02*
X2465252Y1938730D01*
G01X2465303Y1933927D02*
X2465496Y1933730D01*
G01X2465060Y1933927D02*
X2465252Y1933730D01*
G01X2465303Y1928927D02*
X2465496Y1928730D01*
G01X2465060Y1928927D02*
X2465252Y1928730D01*
G01X2465303Y1923927D02*
X2465496Y1923730D01*
G01X2465060Y1923927D02*
X2465252Y1923730D01*
G01X2465303Y1918927D02*
X2465496Y1918730D01*
G01X2465060Y1918927D02*
X2465252Y1918730D01*
G01X2465303Y1913927D02*
X2465496Y1913730D01*
G01X2465060Y1913927D02*
X2465252Y1913730D01*
G01X2465303Y1908927D02*
X2465496Y1908730D01*
G01X2465060Y1908927D02*
X2465252Y1908730D01*
G01X2465303Y1903927D02*
X2465496Y1903730D01*
G01X2465060Y1903927D02*
X2465252Y1903730D01*
G01X2465303Y1898927D02*
X2465496Y1898730D01*
G01X2465060Y1898927D02*
X2465252Y1898730D01*
G01X2465303Y1893927D02*
X2465496Y1893730D01*
G01X2465060Y1893927D02*
X2465252Y1893730D01*
G01X2490744Y1937214D02*
X2491669Y1936289D01*
G01Y1935699D02*
X2490685Y1936683D01*
G01X2490744Y1932214D02*
X2491669Y1931289D01*
G01X2490685Y1931683D02*
X2491669Y1930699D01*
G01X2490744Y1927214D02*
X2491669Y1926289D01*
G01X2490685Y1926683D02*
X2491669Y1925699D01*
G01X2490744Y1922214D02*
X2491669Y1921289D01*
G01X2490685Y1921683D02*
X2491669Y1920699D01*
G01X2490744Y1917214D02*
X2491669Y1916289D01*
G01X2490685Y1916683D02*
X2491669Y1915699D01*
G01X2490744Y1912214D02*
X2491669Y1911289D01*
G01X2490685Y1911683D02*
X2491669Y1910699D01*
G01X2490744Y1907214D02*
X2491669Y1906289D01*
G01X2490685Y1906683D02*
X2491669Y1905699D01*
G01X2490744Y1902214D02*
X2491669Y1901289D01*
G01X2490685Y1901683D02*
X2491669Y1900699D01*
G01X2490744Y1897214D02*
X2491669Y1896289D01*
G01Y1895699D02*
X2490685Y1896683D01*
G01X2478480Y1885482D02*
X2480449Y1883514D01*
G01X2497893Y1874715D02*
X2497833Y1874774D01*
G01X2498098Y1874675D02*
X2498008Y1874750D01*
G01X2497892Y1874716D02*
X2497960Y1874666D01*
G01X2502359Y1935522D02*
X2501303Y1936131D01*
G01X2495666Y1935581D02*
X2494439Y1936289D01*
G01X2502359Y1930522D02*
X2501303Y1931131D01*
G01X2495666Y1930581D02*
X2494439Y1931289D01*
G01X2502359Y1925522D02*
X2501303Y1926131D01*
G01X2495666Y1925581D02*
X2494439Y1926289D01*
G01X2502359Y1920522D02*
X2501303Y1921131D01*
G01X2495666Y1920581D02*
X2494439Y1921289D01*
G01X2502359Y1915522D02*
X2501303Y1916131D01*
G01X2495666Y1915581D02*
X2494439Y1916289D01*
G01X2502359Y1910522D02*
X2501303Y1911131D01*
G01X2495666Y1910581D02*
X2494439Y1911289D01*
G01X2502359Y1905522D02*
X2501303Y1906131D01*
G01X2495666Y1905581D02*
X2494439Y1906289D01*
G01X2502359Y1900522D02*
X2501303Y1901131D01*
G01X2495666Y1900581D02*
X2494439Y1901289D01*
G01X2502359Y1895522D02*
X2501303Y1896131D01*
G01X2495666Y1895581D02*
X2494439Y1896289D01*
G01X2498097Y1874676D02*
X2498200Y1874621D01*
G01X2497958Y1874667D02*
X2498032Y1874628D01*
G01X2497880Y1874942D02*
X2497935Y1874839D01*
G01X2498030Y1874629D02*
X2498109Y1874600D01*
G01X2498198Y1874622D02*
X2498310Y1874588D01*
G01X2498108Y1874600D02*
X2498190Y1874582D01*
G01X2497846Y1875053D02*
X2497881Y1874940D01*
G01X2497142Y1884577D02*
X2493205Y1884970D01*
G01X2498308Y1874588D02*
X2498425Y1874577D01*
G01X2498188Y1874583D02*
X2498272Y1874577D01*
G01X2537152Y1938986D02*
X2502654D01*
G01X2496394Y1938927D02*
X2495961D01*
G01X2490685Y1938730D02*
X2465252D01*
G01X2540449D02*
X2491669D01*
G01X2501008Y1938218D02*
X2496984D01*
G01X2509189Y1938140D02*
X2491669D01*
G01X2491472Y1937943D02*
X2490685D01*
G01X2491472Y1936486D02*
X2490685D01*
G01X2509189Y1936289D02*
X2491669D01*
G01X2501008Y1936211D02*
X2496984D01*
G01X2490685Y1935699D02*
X2465252D01*
G01X2540449D02*
X2491669D01*
G01X2496394Y1935502D02*
X2495961D01*
G01X2537152Y1935443D02*
X2502654D01*
G01X2537152Y1933986D02*
X2502654D01*
G01X2496394Y1933927D02*
X2495961D01*
G01X2490685Y1933730D02*
X2465252D01*
G01X2540449D02*
X2491669D01*
G01X2501008Y1933218D02*
X2496984D01*
G01X2509189Y1933140D02*
X2491669D01*
G01X2491472Y1932943D02*
X2490685D01*
G01X2491472Y1931486D02*
X2490685D01*
G01X2509189Y1931289D02*
X2491669D01*
G01X2501008Y1931211D02*
X2496984D01*
G01X2490685Y1930699D02*
X2465252D01*
G01X2540449D02*
X2491669D01*
G01X2496394Y1930502D02*
X2495961D01*
G01X2537152Y1930443D02*
X2502654D01*
G01X2537152Y1928986D02*
X2502654D01*
G01X2496394Y1928927D02*
X2495961D01*
G01X2490685Y1928730D02*
X2465252D01*
G01X2540449D02*
X2491669D01*
G01X2501008Y1928218D02*
X2496984D01*
G01X2509189Y1928140D02*
X2491669D01*
G01X2491472Y1927943D02*
X2490685D01*
G01X2491472Y1926486D02*
X2490685D01*
G01X2509189Y1926289D02*
X2491669D01*
G01X2501008Y1926211D02*
X2496984D01*
G01X2490685Y1925699D02*
X2465252D01*
G01X2540449D02*
X2491669D01*
G01X2496394Y1925502D02*
X2495961D01*
G01X2537152Y1925443D02*
X2502654D01*
G01X2537152Y1923986D02*
X2502654D01*
G01X2496394Y1923927D02*
X2495961D01*
G01X2490685Y1923730D02*
X2465252D01*
G01X2540449D02*
X2491669D01*
G01X2501008Y1923218D02*
X2496984D01*
G01X2509189Y1923140D02*
X2491669D01*
G01X2491472Y1922943D02*
X2490685D01*
G01X2491472Y1921486D02*
X2490685D01*
G01X2509189Y1921289D02*
X2491669D01*
G01X2501008Y1921211D02*
X2496984D01*
G01X2490685Y1920699D02*
X2465252D01*
G01X2540449D02*
X2491669D01*
G01X2496394Y1920502D02*
X2495961D01*
G01X2537152Y1920443D02*
X2502654D01*
G01X2537152Y1918986D02*
X2502654D01*
G01X2496394Y1918927D02*
X2495961D01*
G01X2490685Y1918730D02*
X2465252D01*
G01X2540449D02*
X2491669D01*
G01X2501008Y1918218D02*
X2496984D01*
G01X2509189Y1918140D02*
X2491669D01*
G01X2491472Y1917943D02*
X2490685D01*
G01X2491472Y1916486D02*
X2490685D01*
G01X2509189Y1916289D02*
X2491669D01*
G01X2501008Y1916211D02*
X2496984D01*
G01X2490685Y1915699D02*
X2465252D01*
G01X2540449D02*
X2491669D01*
G01X2496394Y1915502D02*
X2495961D01*
G01X2537152Y1915443D02*
X2502654D01*
G01X2537152Y1913986D02*
X2502654D01*
G01X2496394Y1913927D02*
X2495961D01*
G01X2490685Y1913730D02*
X2465252D01*
G01X2540449D02*
X2491669D01*
G01X2501008Y1913218D02*
X2496984D01*
G01X2509189Y1913140D02*
X2491669D01*
G01X2491472Y1912943D02*
X2490685D01*
G01X2491472Y1911486D02*
X2490685D01*
G01X2509189Y1911289D02*
X2491669D01*
G01X2501008Y1911211D02*
X2496984D01*
G01X2490685Y1910699D02*
X2465252D01*
G01X2540449D02*
X2491669D01*
G01X2496394Y1910502D02*
X2495961D01*
G01X2537152Y1910443D02*
X2502654D01*
G01X2537152Y1908986D02*
X2502654D01*
G01X2496394Y1908927D02*
X2495961D01*
G01X2490685Y1908730D02*
X2465252D01*
G01X2540449D02*
X2491669D01*
G01X2501008Y1908218D02*
X2496984D01*
G01X2509189Y1908140D02*
X2491669D01*
G01X2491472Y1907943D02*
X2490685D01*
G01X2491472Y1906486D02*
X2490685D01*
G01X2509189Y1906289D02*
X2491669D01*
G01X2501008Y1906211D02*
X2496984D01*
G01X2490685Y1905699D02*
X2465252D01*
G01X2540449D02*
X2491669D01*
G01X2496394Y1905502D02*
X2495961D01*
G01X2537152Y1905443D02*
X2502654D01*
G01X2537152Y1903986D02*
X2502654D01*
G01X2496394Y1903927D02*
X2495961D01*
G01X2490685Y1903730D02*
X2465252D01*
G01X2540449D02*
X2491669D01*
G01X2501008Y1903218D02*
X2496984D01*
G01X2509189Y1903140D02*
X2491669D01*
G01X2491472Y1902943D02*
X2490685D01*
G01X2491472Y1901486D02*
X2490685D01*
G01X2509189Y1901289D02*
X2491669D01*
G01X2501008Y1901211D02*
X2496984D01*
G01X2490685Y1900699D02*
X2465252D01*
G01X2540449D02*
X2491669D01*
G01X2496394Y1900502D02*
X2495961D01*
G01X2537152Y1900443D02*
X2502654D01*
G01X2537152Y1898986D02*
X2502654D01*
G01X2496394Y1898927D02*
X2495961D01*
G01X2490685Y1898730D02*
X2465252D01*
G01X2540449D02*
X2491669D01*
G01X2501008Y1898218D02*
X2496984D01*
G01X2509189Y1898140D02*
X2491669D01*
G01X2491472Y1897943D02*
X2490685D01*
G01X2491472Y1896486D02*
X2490685D01*
G01X2509189Y1896289D02*
X2491669D01*
G01X2501008Y1896211D02*
X2496984D01*
G01X2490685Y1895699D02*
X2465252D01*
G01X2540449D02*
X2491669D01*
G01X2496394Y1895502D02*
X2495961D01*
G01X2537152Y1895443D02*
X2502654D01*
G01X2537152Y1893986D02*
X2502654D01*
G01X2496394Y1893927D02*
X2495961D01*
G01X2490685Y1893730D02*
X2465252D01*
G01X2540449D02*
X2491669D01*
G01X2501008Y1893218D02*
X2496984D01*
G01X2509189Y1893140D02*
X2491669D01*
G01X2491472Y1892943D02*
X2490685D01*
G01X2539464Y1885010D02*
X2501079D01*
G01X2496945Y1880856D02*
X2480324D01*
G01X2492079Y1878888D02*
X2480449D01*
G01X2501079D02*
X2497929D01*
G01X2534012Y1877293D02*
X2498272D01*
G01X2501079Y1877096D02*
X2480449D01*
G01X2540449Y1876860D02*
X2498323D01*
G01X2497835Y1876703D02*
X2497685D01*
G01X2497835Y1875167D02*
X2497685D01*
G01X2540449Y1875010D02*
X2498323D01*
G01X2501079Y1874774D02*
X2480449D01*
G01X2534012Y1874577D02*
X2498272D01*
G01X2492079Y1872982D02*
X2480449D01*
G01X2501079D02*
X2497929D01*
G01X2496945Y1871014D02*
X2480449D01*
G01X2498188Y1877287D02*
X2498272Y1877293D01*
G01X2498308Y1877282D02*
X2498425Y1877293D01*
G01X2497847Y1875051D02*
X2497835Y1875167D01*
G01X2498190Y1877287D02*
X2498108Y1877270D01*
G01X2511157Y1895699D02*
Y1893730D01*
G01Y1900699D02*
Y1898730D01*
G01Y1905699D02*
Y1903730D01*
G01Y1910699D02*
Y1908730D01*
G01Y1915699D02*
Y1913730D01*
G01Y1920699D02*
Y1918730D01*
G01Y1925699D02*
Y1923730D01*
G01Y1930699D02*
Y1928730D01*
G01Y1935699D02*
Y1933730D01*
G01Y1940699D02*
Y1938730D01*
G01X2509189Y1896289D02*
Y1893140D01*
G01Y1901289D02*
Y1898140D01*
G01Y1906289D02*
Y1903140D01*
G01Y1911289D02*
Y1908140D01*
G01Y1916289D02*
Y1913140D01*
G01Y1921289D02*
Y1918140D01*
G01Y1926289D02*
Y1923140D01*
G01Y1931289D02*
Y1928140D01*
G01Y1936289D02*
Y1933140D01*
G01Y1941289D02*
Y1938140D01*
G01X2505924Y1895443D02*
Y1893986D01*
G01Y1900443D02*
Y1898986D01*
G01Y1905443D02*
Y1903986D01*
G01Y1910443D02*
Y1908986D01*
G01Y1915443D02*
Y1913986D01*
G01Y1920443D02*
Y1918986D01*
G01Y1925443D02*
Y1923986D01*
G01Y1930443D02*
Y1928986D01*
G01Y1935443D02*
Y1933986D01*
G01Y1940443D02*
Y1938986D01*
G01X2505362Y1895443D02*
Y1893986D01*
G01Y1900443D02*
Y1898986D01*
G01Y1905443D02*
Y1903986D01*
G01Y1910443D02*
Y1908986D01*
G01Y1915443D02*
Y1913986D01*
G01Y1920443D02*
Y1918986D01*
G01Y1925443D02*
Y1923986D01*
G01Y1930443D02*
Y1928986D01*
G01Y1935443D02*
Y1933986D01*
G01Y1940443D02*
Y1938986D01*
G01X2504425Y1895443D02*
Y1893986D01*
G01Y1900443D02*
Y1898986D01*
G01Y1905443D02*
Y1903986D01*
G01Y1910443D02*
Y1908986D01*
G01Y1915443D02*
Y1913986D01*
G01Y1920443D02*
Y1918986D01*
G01Y1925443D02*
Y1923986D01*
G01Y1930443D02*
Y1928986D01*
G01Y1935443D02*
Y1933986D01*
G01Y1940443D02*
Y1938986D01*
G01X2501866Y1875010D02*
Y1876860D01*
G01X2497929Y1879872D02*
Y1871998D01*
G01X2497835Y1875167D02*
Y1876703D01*
G01X2497685D02*
Y1875167D01*
G01X2497269Y1884577D02*
Y1877096D01*
G01X2496984Y1893337D02*
Y1893218D01*
G01Y1896211D02*
Y1896092D01*
G01Y1898337D02*
Y1898218D01*
G01Y1903337D02*
Y1903218D01*
G01Y1901211D02*
Y1901092D01*
G01Y1906211D02*
Y1906092D01*
G01Y1908337D02*
Y1908218D01*
G01Y1911211D02*
Y1911092D01*
G01Y1913337D02*
Y1913218D01*
G01Y1916211D02*
Y1916092D01*
G01Y1921211D02*
Y1921092D01*
G01Y1918337D02*
Y1918218D01*
G01Y1926211D02*
Y1926092D01*
G01Y1923337D02*
Y1923218D01*
G01Y1931211D02*
Y1931092D01*
G01Y1928337D02*
Y1928218D01*
G01Y1936211D02*
Y1936092D01*
G01Y1933337D02*
Y1933218D01*
G01Y1938337D02*
Y1938218D01*
G01X2492079Y1878888D02*
Y1872982D01*
G01X2491669Y1896289D02*
Y1893140D01*
G01Y1901289D02*
Y1898140D01*
G01Y1906289D02*
Y1903140D01*
G01Y1911289D02*
Y1908140D01*
G01Y1916289D02*
Y1913140D01*
G01Y1921289D02*
Y1918140D01*
G01Y1926289D02*
Y1923140D01*
G01Y1931289D02*
Y1928140D01*
G01Y1936289D02*
Y1933140D01*
G01Y1941289D02*
Y1938140D01*
G01X2491275Y1878888D02*
Y1872982D01*
G01X2490685Y1955423D02*
Y1889006D01*
G01X2490291Y1895699D02*
Y1893730D01*
G01Y1900699D02*
Y1898730D01*
G01Y1905699D02*
Y1903730D01*
G01Y1910699D02*
Y1908730D01*
G01Y1915699D02*
Y1913730D01*
G01Y1920699D02*
Y1918730D01*
G01Y1925699D02*
Y1923730D01*
G01Y1930699D02*
Y1928730D01*
G01Y1935699D02*
Y1933730D01*
G01Y1940699D02*
Y1938730D01*
G01X2489885Y1895699D02*
Y1893730D01*
G01Y1900699D02*
Y1898730D01*
G01Y1905699D02*
Y1903730D01*
G01Y1910699D02*
Y1908730D01*
G01Y1915699D02*
Y1913730D01*
G01Y1920699D02*
Y1918730D01*
G01Y1925699D02*
Y1923730D01*
G01Y1930699D02*
Y1928730D01*
G01Y1935699D02*
Y1933730D01*
G01Y1940699D02*
Y1938730D01*
G01X2489642Y1895699D02*
Y1893730D01*
G01Y1900699D02*
Y1898730D01*
G01Y1905699D02*
Y1903730D01*
G01Y1910699D02*
Y1908730D01*
G01Y1915699D02*
Y1913730D01*
G01Y1920699D02*
Y1918730D01*
G01Y1925699D02*
Y1923730D01*
G01Y1930699D02*
Y1928730D01*
G01Y1935699D02*
Y1933730D01*
G01Y1940699D02*
Y1938730D01*
G01X2489520Y1878888D02*
Y1872982D01*
G01X2488716Y1878888D02*
Y1872982D01*
G01X2488323Y1879872D02*
Y1871998D01*
G01X2486354Y1878888D02*
Y1872982D01*
G01X2484386Y1877096D02*
Y1874774D01*
G01X2483598Y1878809D02*
Y1873061D01*
G01Y1884970D02*
Y1883061D01*
G01X2482811D02*
Y1878809D01*
G01X2481630Y1883061D02*
Y1878809D01*
G01X2480449Y1891663D02*
Y1949557D01*
G01Y1891368D02*
Y1889400D01*
G01X2479183Y1883061D02*
Y1878809D01*
G01X2478920Y1883061D02*
Y1882986D01*
G01X2478002Y1883061D02*
Y1878809D01*
G01X2476821Y1883061D02*
Y1878809D01*
G01X2472884Y1883061D02*
Y1878809D01*
G01X2472281Y1883061D02*
Y1878809D01*
G01X2471678Y1883061D02*
Y1878809D01*
G01X2462556Y1883061D02*
Y1878809D01*
G01X2462363Y1895502D02*
Y1893927D01*
G01Y1900502D02*
Y1898927D01*
G01Y1905502D02*
Y1903927D01*
G01Y1910502D02*
Y1908927D01*
G01Y1915502D02*
Y1913927D01*
G01Y1920502D02*
Y1918927D01*
G01Y1925502D02*
Y1923927D01*
G01Y1930502D02*
Y1928927D01*
G01Y1935502D02*
Y1933927D01*
G01Y1940502D02*
Y1938927D01*
G01X2462119Y1895502D02*
Y1893927D01*
G01Y1900502D02*
Y1898927D01*
G01Y1905502D02*
Y1903927D01*
G01Y1910502D02*
Y1908927D01*
G01Y1915502D02*
Y1913927D01*
G01Y1920502D02*
Y1918927D01*
G01Y1925502D02*
Y1923927D01*
G01Y1930502D02*
Y1928927D01*
G01Y1935502D02*
Y1933927D01*
G01Y1940502D02*
Y1938927D01*
G01X2461953Y1883061D02*
Y1878809D01*
G01X2497701Y1876847D02*
X2497685Y1876703D01*
G01X2497847Y1876819D02*
X2497835Y1876703D01*
G01X2497881Y1876930D02*
X2497846Y1876817D01*
G01X2497701Y1876847D02*
X2497752Y1876978D01*
X2497835Y1877096D01*
G01X2497935Y1877031D02*
X2497880Y1876928D01*
G01X2497934Y1877029D02*
X2498008Y1877120D01*
G01X2498098Y1877195D02*
X2498008Y1877120D01*
G01X2497893Y1877155D02*
X2497833Y1877096D01*
G01X2491669Y1893140D02*
X2490685Y1892155D01*
G01X2491669Y1893730D02*
X2490685Y1892746D01*
G01X2491669Y1898140D02*
X2490744Y1897214D01*
G01X2491669Y1898730D02*
X2490685Y1897746D01*
G01X2480449Y1891663D02*
X2478480Y1889695D01*
G01X2491669Y1903140D02*
X2490744Y1902214D01*
G01X2490685Y1902746D02*
X2491669Y1903730D01*
G01Y1908140D02*
X2490744Y1907214D01*
G01X2491669Y1908730D02*
X2490685Y1907746D01*
G01X2491669Y1913140D02*
X2490744Y1912214D01*
G01X2491669Y1913730D02*
X2490685Y1912746D01*
G01X2491669Y1918140D02*
X2490744Y1917214D01*
G01X2491669Y1918730D02*
X2490685Y1917746D01*
G01X2491669Y1923140D02*
X2490744Y1922214D01*
G01X2491669Y1923730D02*
X2490685Y1922746D01*
G01X2491669Y1928140D02*
X2490744Y1927214D01*
G01X2491669Y1928730D02*
X2490685Y1927746D01*
G01X2491669Y1933140D02*
X2490744Y1932214D01*
G01X2491669Y1933730D02*
X2490685Y1932746D01*
G01X2491669Y1938140D02*
X2490744Y1937214D01*
G01X2491669Y1938730D02*
X2490685Y1937746D01*
G01X2465496Y1895699D02*
X2465303Y1895502D01*
G01X2465252Y1895699D02*
X2465060Y1895502D01*
G01X2465496Y1900699D02*
X2465303Y1900502D01*
G01X2465252Y1900699D02*
X2465060Y1900502D01*
G01X2465496Y1905699D02*
X2465303Y1905502D01*
G01X2465252Y1905699D02*
X2465060Y1905502D01*
G01X2465496Y1910699D02*
X2465303Y1910502D01*
G01X2465252Y1910699D02*
X2465060Y1910502D01*
G01X2465496Y1915699D02*
X2465303Y1915502D01*
G01X2465252Y1915699D02*
X2465060Y1915502D01*
G01X2465496Y1920699D02*
X2465303Y1920502D01*
G01X2465252Y1920699D02*
X2465060Y1920502D01*
G01X2465496Y1925699D02*
X2465303Y1925502D01*
G01X2465252Y1925699D02*
X2465060Y1925502D01*
G01X2465496Y1930699D02*
X2465303Y1930502D01*
G01X2465252Y1930699D02*
X2465060Y1930502D01*
G01X2465496Y1935699D02*
X2465303Y1935502D01*
G01X2465252Y1935699D02*
X2465060Y1935502D01*
G01X2497960Y1877203D02*
X2497892Y1877154D01*
G01X2498200Y1877249D02*
X2498097Y1877193D01*
G01X2498032Y1877242D02*
X2497958Y1877202D01*
G01X2502359Y1893907D02*
X2501303Y1893298D01*
G01X2495666Y1893848D02*
X2494439Y1893140D01*
G01X2502359Y1898907D02*
X2501303Y1898298D01*
G01X2495666Y1898848D02*
X2494439Y1898140D01*
G01X2502359Y1903907D02*
X2501303Y1903298D01*
G01X2495666Y1903848D02*
X2494439Y1903140D01*
G01X2502359Y1908907D02*
X2501303Y1908298D01*
G01X2495666Y1908848D02*
X2494439Y1908140D01*
G01X2502359Y1913907D02*
X2501303Y1913298D01*
G01X2495666Y1913848D02*
X2494439Y1913140D01*
G01X2502359Y1918907D02*
X2501303Y1918298D01*
G01X2495666Y1918848D02*
X2494439Y1918140D01*
G01X2502359Y1923907D02*
X2501303Y1923298D01*
G01X2495666Y1923848D02*
X2494439Y1923140D01*
G01X2502359Y1928907D02*
X2501303Y1928298D01*
G01X2495666Y1928848D02*
X2494439Y1928140D01*
G01X2502359Y1933907D02*
X2501303Y1933298D01*
G01X2495666Y1933848D02*
X2494439Y1933140D01*
G01X2502359Y1938907D02*
X2501303Y1938298D01*
G01X2495666Y1938848D02*
X2494439Y1938140D01*
G01X2498310Y1877282D02*
X2498198Y1877248D01*
G01X2498109Y1877270D02*
X2498030Y1877241D01*
G01X2465303Y1940502D02*
X2454110D01*
G01X2465303Y1950502D02*
X2454110D01*
G01X2465303Y1948927D02*
X2454110D01*
G01X2465303Y1945502D02*
X2454110D01*
G01X2465303Y1943927D02*
X2454110D01*
G01X2460173Y1945502D02*
Y1943927D01*
G01Y1950502D02*
Y1948927D01*
G01X2459583Y1945502D02*
Y1943927D01*
G01Y1950502D02*
Y1948927D01*
G01X2454701Y1945502D02*
Y1943927D01*
G01Y1950502D02*
Y1948927D01*
G01X2454110Y1945502D02*
Y1943927D01*
G01Y1950502D02*
Y1948927D01*
G01X2502359Y1940522D02*
G03X2502654Y1940443I295J511D01*
G01X2501303Y1941131D02*
G03X2501008Y1941211I-297J-511D01*
G01X2496394Y1940502D02*
G03X2496984Y1941092I0J590D01*
G01X2495666Y1940581D02*
G03X2495961Y1940502I295J512D01*
G01X2490744Y1942214D02*
X2491669Y1941289D01*
G01X2490685Y1941683D02*
X2491669Y1940699D01*
G01X2502359Y1940522D02*
X2501303Y1941131D01*
G01X2495666Y1940581D02*
X2494439Y1941289D01*
G01X2491472Y1941486D02*
X2490685D01*
G01X2509189Y1941289D02*
X2491669D01*
G01X2501008Y1941211D02*
X2496984D01*
G01X2490685Y1940699D02*
X2465252D01*
G01X2540449D02*
X2491669D01*
G01X2496394Y1940502D02*
X2495961D01*
G01X2537152Y1940443D02*
X2502654D01*
G01X2496984Y1941211D02*
Y1941092D01*
G01X2491669Y1943140D02*
X2490744Y1942214D01*
G01X2491669Y1943730D02*
X2490685Y1942746D01*
G01X2465496Y1940699D02*
X2465303Y1940502D01*
G01X2465252Y1940699D02*
X2465060Y1940502D01*
G01X2502359Y1950522D02*
G03X2502654Y1950443I295J511D01*
G01Y1948986D02*
G03X2502359Y1948907I0J-590D01*
G01Y1945522D02*
G03X2502654Y1945443I295J511D01*
G01Y1943986D02*
G03X2502359Y1943907I0J-590D01*
G01X2501303Y1951131D02*
G03X2501008Y1951211I-297J-511D01*
G01Y1948218D02*
G03X2501303Y1948298I-2J590D01*
G01Y1946131D02*
G03X2501008Y1946211I-297J-511D01*
G01Y1943218D02*
G03X2501303Y1943298I-2J590D01*
G01X2496394Y1950502D02*
G03X2496984Y1951092I0J590D01*
G01Y1948337D02*
G03X2496394Y1948927I-590J0D01*
G01Y1945502D02*
G03X2496984Y1946092I0J590D01*
G01Y1943337D02*
G03X2496394Y1943927I-590J0D01*
G01X2495666Y1950581D02*
G03X2495961Y1950502I295J512D01*
G01Y1948927D02*
G03X2495666Y1948848I0J-591D01*
G01Y1945581D02*
G03X2495961Y1945502I295J512D01*
G01Y1943927D02*
G03X2495666Y1943848I0J-591D01*
G01X2495173Y1980620D02*
G03X2493205Y1982588I-1968J0D01*
G01X2465646Y1955029D02*
G03X2467614Y1953061I1968J0D01*
G01Y1982588D02*
G03X2465646Y1980620I0J-1968D01*
G01X2485921Y1955029D02*
G03X2480449Y1949557I0J-5472D01*
G01X2487732Y1967825D02*
G03I-7283J0D01*
G01D02*
G03I-7283J0D01*
G01X2488126D02*
G03I-7677J0D01*
G01X2502359Y1950522D02*
X2501303Y1951131D01*
G01X2495666Y1950581D02*
X2494439Y1951289D01*
G01X2502359Y1945522D02*
X2501303Y1946131D01*
G01X2465303Y1948927D02*
X2465496Y1948730D01*
G01X2465060Y1948927D02*
X2465252Y1948730D01*
G01X2465303Y1943927D02*
X2465496Y1943730D01*
G01X2465060Y1943927D02*
X2465252Y1943730D01*
G01X2490685Y1952274D02*
X2491669Y1951289D01*
G01X2490685Y1951683D02*
X2491669Y1950699D01*
G01X2490744Y1947214D02*
X2491669Y1946289D01*
G01X2490685Y1946683D02*
X2491669Y1945699D01*
G01X2495666Y1945581D02*
X2494439Y1946289D01*
G01X2493205Y1982588D02*
X2467614D01*
G01X2495173Y1966919D02*
X2540449D01*
G01Y1964951D02*
X2495173D01*
G01X2535724Y1959045D02*
X2501079D01*
G01X2465646Y1955423D02*
X2490685D01*
G01X2485921Y1955029D02*
X2490685D01*
G01X2495173Y1953061D02*
X2467614D01*
G01X2491472Y1951486D02*
X2490685D01*
G01X2509189Y1951289D02*
X2491669D01*
G01X2501008Y1951211D02*
X2496984D01*
G01X2490685Y1950699D02*
X2465252D01*
G01X2540449D02*
X2491669D01*
G01X2496394Y1950502D02*
X2495961D01*
G01X2537152Y1950443D02*
X2502654D01*
G01X2537152Y1948986D02*
X2502654D01*
G01X2496394Y1948927D02*
X2495961D01*
G01X2490685Y1948730D02*
X2465252D01*
G01X2540449D02*
X2491669D01*
G01X2501008Y1948218D02*
X2496984D01*
G01X2509189Y1948140D02*
X2491669D01*
G01X2491472Y1947943D02*
X2490685D01*
G01X2491472Y1946486D02*
X2490685D01*
G01X2509189Y1946289D02*
X2491669D01*
G01X2501008Y1946211D02*
X2496984D01*
G01X2490685Y1945699D02*
X2465252D01*
G01X2540449D02*
X2491669D01*
G01X2496394Y1945502D02*
X2495961D01*
G01X2537152Y1945443D02*
X2502654D01*
G01X2537152Y1943986D02*
X2502654D01*
G01X2496394Y1943927D02*
X2495961D01*
G01X2490685Y1943730D02*
X2465252D01*
G01X2540449D02*
X2491669D01*
G01X2501008Y1943218D02*
X2496984D01*
G01X2509189Y1943140D02*
X2491669D01*
G01X2491472Y1942943D02*
X2490685D01*
G01X2511157Y1945699D02*
Y1943730D01*
G01Y1950699D02*
Y1948730D01*
G01X2509189Y1943140D02*
Y1946289D01*
G01Y1951289D02*
Y1948140D01*
G01X2505924Y1945443D02*
Y1943986D01*
G01Y1950443D02*
Y1948986D01*
G01X2505362Y1945443D02*
Y1943986D01*
G01Y1950443D02*
Y1948986D01*
G01X2504425Y1945443D02*
Y1943986D01*
G01Y1950443D02*
Y1948986D01*
G01X2496984Y1943337D02*
Y1943218D01*
G01Y1946211D02*
Y1946092D01*
G01Y1948337D02*
Y1948218D01*
G01Y1951211D02*
Y1951092D01*
G01X2495173Y1953061D02*
Y1980620D01*
G01X2494622Y2261801D02*
Y1958966D01*
G01X2491669Y1948140D02*
Y1951289D01*
G01Y1946289D02*
Y1943140D01*
G01X2490291Y1945699D02*
Y1943730D01*
G01Y1950699D02*
Y1948730D01*
G01X2489885Y1945699D02*
Y1943730D01*
G01Y1950699D02*
Y1948730D01*
G01X2489642Y1945699D02*
Y1943730D01*
G01Y1950699D02*
Y1948730D01*
G01X2469583Y1953061D02*
Y1982588D01*
G01X2465646Y1980620D02*
Y1955029D01*
G01X2462363Y1945502D02*
Y1943927D01*
G01Y1950502D02*
Y1948927D01*
G01X2462119Y1945502D02*
Y1943927D01*
G01Y1950502D02*
Y1948927D01*
G01X2491669Y1948140D02*
X2490744Y1947214D01*
G01X2491669Y1948730D02*
X2490685Y1947746D01*
G01X2494622Y1958966D02*
X2490685Y1955029D01*
G01X2465496Y1945699D02*
X2465303Y1945502D01*
G01X2465252Y1945699D02*
X2465060Y1945502D01*
G01X2465496Y1950699D02*
X2465303Y1950502D01*
G01X2465252Y1950699D02*
X2465060Y1950502D01*
G01X2502359Y1943907D02*
X2501303Y1943298D01*
G01X2495666Y1943848D02*
X2494439Y1943140D01*
G01X2502359Y1948907D02*
X2501303Y1948298D01*
G01X2495666Y1948848D02*
X2494439Y1948140D01*
G01X2486340Y1972108D02*
X2522980Y1998745D01*
G01X2448223Y2170256D02*
G03X2462281I7029J-6890D01*
G01X2461256Y2185840D02*
G03I-984J0D01*
G01X2461155Y2173012D02*
G03X2462281Y2170256I3937J0D01*
G01X2451216Y2185840D02*
G03I-984J0D01*
G01X2461155Y2177146D02*
G03X2449349I-5903J0D01*
G01X2461157D02*
G03X2449346I-5906J0D01*
G01X2463126D02*
G03X2447378I-7874J0D01*
G01X2469031D02*
G03X2441472I-13780J0D01*
G01X2446197D02*
G03I-985J0D01*
G01X2447542Y2182165D02*
G03I-984J0D01*
G01X2448223Y2170256D02*
G03X2449349Y2173012I-2811J2757D01*
G01X2461157Y2174783D02*
X2469031D01*
G01X2441472D02*
X2449346D01*
G01X2461157Y2177146D02*
Y2174783D01*
G01X2461155Y2173012D02*
Y2177146D01*
G01X2449349D02*
Y2173012D01*
G01X2449346Y2174783D02*
Y2177146D01*
G01X2447378D02*
Y2174783D01*
G01X2441472Y2177146D02*
Y2174783D01*
G01X2459189Y2163376D02*
X2575488D01*
G01X2455252Y2167313D02*
Y2300777D01*
G01X2472024Y2224124D02*
G03I-4292J0D01*
G01X2466275Y2177146D02*
G03I-984J0D01*
G01X2464930Y2182165D02*
G03I-984J0D01*
G01X2471000Y2163366D02*
Y2177146D01*
G01Y2163366D02*
Y2177146D01*
G01Y2163366D02*
Y2177146D01*
G01X2469031Y2174783D02*
Y2177146D01*
G01X2463126Y2174783D02*
Y2177146D01*
G01X2461984Y2167460D02*
X2519016Y2202058D01*
G01X2471377Y2226390D02*
X2529131Y2262292D01*
G01X2467732Y2228061D02*
Y2300777D01*
G01X2471669Y2224124D02*
X2529649D01*
G01X2494622Y2261801D02*
G03X2490685Y2265738I-3937J0D01*
G01X2458349Y2307057D02*
X2457627Y2307544D01*
X2456905Y2308519D01*
Y2309493D01*
X2457627Y2310467D01*
X2458349Y2310955D01*
X2459793D01*
X2460514Y2310467D01*
G01X2445869Y2307057D02*
X2445147Y2307544D01*
X2444425Y2308519D01*
Y2309493D01*
X2445147Y2310467D01*
X2445869Y2310955D01*
X2447312D01*
X2448034Y2310467D01*
G01D02*
X2449478Y2308519D01*
X2450921Y2307544D01*
X2453087Y2307057D01*
Y2310955D01*
G01X2460514Y2310467D02*
X2461958Y2308519D01*
X2463401Y2307544D01*
X2465567Y2307057D01*
Y2310955D01*
G01X2445147Y2323135D02*
X2444425Y2324109D01*
Y2325084D01*
X2445147Y2326058D01*
X2445869Y2326545D01*
X2446590D01*
X2447312Y2326058D01*
X2448034Y2325084D01*
X2448756Y2326058D01*
G01X2450921Y2327032D02*
X2452365Y2326058D01*
X2453087Y2325084D01*
Y2324109D01*
X2452365Y2323135D01*
X2451643Y2322648D01*
G01X2462680Y2338238D02*
X2461236Y2338725D01*
X2460514Y2340187D01*
X2461236Y2341649D01*
X2462680Y2342136D01*
X2464123Y2341649D01*
X2464845Y2341161D01*
X2465567Y2340187D01*
X2464845Y2339213D01*
X2464123Y2338725D01*
X2462680Y2338238D01*
X2459793D01*
X2458349Y2338725D01*
X2457627Y2339213D01*
X2456905Y2340187D01*
X2457627Y2341161D01*
X2458349Y2341649D01*
G01X2462680Y2322648D02*
X2461236Y2323135D01*
X2460514Y2324596D01*
X2461236Y2326058D01*
X2462680Y2326545D01*
X2464123Y2326058D01*
X2464845Y2325571D01*
X2465567Y2324596D01*
X2464845Y2323622D01*
X2464123Y2323135D01*
X2462680Y2322648D01*
X2459793D01*
X2458349Y2323135D01*
X2457627Y2323622D01*
X2456905Y2324596D01*
X2457627Y2325571D01*
X2458349Y2326058D01*
G01X2465567Y2347982D02*
X2461958Y2348469D01*
X2459793Y2348956D01*
X2456905Y2349931D01*
G01Y2318750D02*
Y2315827D01*
X2460514Y2315339D01*
X2459793Y2316314D01*
Y2317288D01*
X2460514Y2318263D01*
X2461236Y2318750D01*
X2462680Y2319237D01*
X2464123Y2318750D01*
X2464845Y2318263D01*
X2465567Y2317288D01*
Y2316314D01*
X2464845Y2315339D01*
X2464123Y2314852D01*
G01X2456905Y2349931D02*
Y2346033D01*
G01X2453087Y2332392D02*
Y2331904D01*
X2452365D01*
X2453087Y2332392D01*
G01X2448034Y2324109D02*
Y2325084D01*
G01X2444425Y2318750D02*
Y2315827D01*
X2448034Y2315339D01*
X2447312Y2316314D01*
Y2317288D01*
X2448034Y2318263D01*
X2448756Y2318750D01*
X2450199Y2319237D01*
X2451643Y2318750D01*
X2452365Y2318263D01*
X2453087Y2317288D01*
Y2316314D01*
X2452365Y2315339D01*
X2451643Y2314852D01*
G01X2444425Y2342136D02*
Y2339213D01*
X2448034Y2338725D01*
X2447312Y2339700D01*
Y2340674D01*
X2448034Y2341649D01*
X2448756Y2342136D01*
X2450199Y2342623D01*
X2451643Y2342136D01*
X2452365Y2341649D01*
X2453087Y2340674D01*
Y2339700D01*
X2452365Y2338725D01*
X2451643Y2338238D01*
G01X2453087Y2347982D02*
X2452365Y2347008D01*
X2451643Y2346521D01*
X2450199Y2346033D01*
X2447312D01*
X2445869Y2346521D01*
X2445147Y2347008D01*
X2444425Y2347982D01*
X2445147Y2348956D01*
X2445869Y2349444D01*
X2447312Y2349931D01*
X2450199D01*
X2451643Y2349444D01*
X2452365Y2348956D01*
X2453087Y2347982D01*
G01X2448756Y2326058D02*
X2450199Y2327032D01*
X2450921D01*
G01X2465567Y2332392D02*
Y2331904D01*
X2464845D01*
X2465567Y2332392D01*
G01X2487318Y2418463D02*
X4130359D01*
G01X2535002Y-34372D02*
X2534280Y-35346D01*
X2533558Y-35833D01*
X2532114Y-36320D01*
X2529227D01*
X2527783Y-35833D01*
X2527062Y-35346D01*
X2526340Y-34372D01*
X2527062Y-33398D01*
X2527783Y-32910D01*
X2529227Y-32423D01*
X2532114D01*
X2533558Y-32910D01*
X2534280Y-33398D01*
X2535002Y-34372D01*
G01Y-26577D02*
Y-27064D01*
X2534280D01*
X2535002Y-26577D01*
G01X2537167Y-38269D02*
Y22156D01*
G01Y20187D02*
Y-38269D01*
G01X2626644Y17403D02*
X2583476Y-25765D01*
G01X2566983Y2962D02*
X2564060D01*
X2563573Y-647D01*
X2564547Y74D01*
X2565521D01*
X2566496Y-647D01*
X2566983Y-1369D01*
X2567470Y-2813D01*
X2566983Y-4256D01*
X2566496Y-4978D01*
X2565521Y-5700D01*
X2564547D01*
X2563573Y-4978D01*
X2563085Y-4256D01*
G01X2572830Y-5700D02*
X2572342D01*
Y-4978D01*
X2572830Y-5700D01*
G01X2535002Y-10986D02*
X2534280Y-11961D01*
X2533558Y-12448D01*
X2532114Y-12935D01*
X2529227D01*
X2527783Y-12448D01*
X2527062Y-11961D01*
X2526340Y-10986D01*
X2527062Y-10012D01*
X2527783Y-9524D01*
X2529227Y-9037D01*
X2532114D01*
X2533558Y-9524D01*
X2534280Y-10012D01*
X2535002Y-10986D01*
G01X2584522Y4406D02*
Y2962D01*
X2585244Y2240D01*
X2586687D01*
X2587409Y2962D01*
Y4406D01*
X2586687Y5127D01*
X2585244D01*
X2584522Y4406D01*
G01X2580625Y-5700D02*
X2579650Y-4978D01*
X2579163Y-4256D01*
X2578676Y-2813D01*
Y74D01*
X2579163Y1518D01*
X2579650Y2240D01*
X2580625Y2962D01*
X2581599Y2240D01*
X2582086Y1518D01*
X2582574Y74D01*
Y-2813D01*
X2582086Y-4256D01*
X2581599Y-4978D01*
X2580625Y-5700D01*
G01X2558700D02*
Y2962D01*
X2555290Y-3534D01*
X2559675D01*
G01X2526340Y-16832D02*
Y-19756D01*
X2529949Y-20243D01*
X2529227Y-19269D01*
Y-18294D01*
X2529949Y-17320D01*
X2530670Y-16832D01*
X2532114Y-16345D01*
X2533558Y-16832D01*
X2534280Y-17320D01*
X2535002Y-18294D01*
Y-19269D01*
X2534280Y-20243D01*
X2533558Y-20730D01*
G01X2537167Y43809D02*
Y22156D01*
G01Y24124D02*
Y43809D01*
G01X2625491Y20187D02*
X2533230D01*
G01X2629428Y24124D02*
X2533230D01*
G01X2569635Y43524D02*
G03X2566748Y24124I63730J-19399D01*
G01X2629428D02*
X2562811D01*
G01X2559320Y101361D02*
X2558832D01*
Y102082D01*
X2559320Y101361D01*
G01X2574910D02*
X2573936Y102082D01*
X2573448Y102804D01*
X2572961Y104248D01*
Y107135D01*
X2573448Y108578D01*
X2573936Y109300D01*
X2574910Y110022D01*
X2575885Y109300D01*
X2576372Y108578D01*
X2576859Y107135D01*
Y104248D01*
X2576372Y102804D01*
X2575885Y102082D01*
X2574910Y101361D01*
G01X2568576D02*
Y110022D01*
X2565166Y103526D01*
X2569551D01*
G01X2552986Y101361D02*
Y110022D01*
X2549575Y103526D01*
X2553961D01*
G01X2646750Y99195D02*
X2547627D01*
G01X2529659Y328455D02*
Y319793D01*
G01X2585178Y310633D02*
X2584204Y309911D01*
X2583229D01*
G01X2582255Y314242D02*
X2583229Y314964D01*
X2584204D01*
X2585178Y314242D01*
X2586153Y312798D01*
G01X2558404Y322680D02*
X2559378Y324124D01*
X2560353Y324846D01*
X2561327D01*
X2562301Y324124D01*
G01X2563276Y321959D02*
X2562301Y320515D01*
X2561327Y319793D01*
X2560353D01*
G01X2586153Y312798D02*
Y312077D01*
X2585178Y310633D01*
G01X2581280Y312077D02*
Y312798D01*
X2582255Y314242D01*
G01X2553045Y328455D02*
Y319793D01*
G01X2537454Y328455D02*
Y319793D01*
G01X2562301Y324124D02*
X2563276Y322680D01*
Y321959D01*
G01X2559378Y320515D02*
X2558404Y321959D01*
Y322680D01*
G01X2583229Y314964D02*
X2582255Y315686D01*
X2581768Y316407D01*
Y317129D01*
X2582255Y317851D01*
X2583229Y318573D01*
X2584204D01*
X2585178Y317851D01*
X2585665Y317129D01*
Y316407D01*
X2585178Y315686D01*
X2584204Y314964D01*
G01X2583229Y309911D02*
X2582255Y310633D01*
X2581280Y312077D01*
G01X2560353Y324846D02*
X2559378Y325567D01*
X2558891Y326289D01*
Y327011D01*
X2559378Y327733D01*
X2560353Y328455D01*
X2561327D01*
X2562301Y327733D01*
X2562789Y327011D01*
Y326289D01*
X2562301Y325567D01*
X2561327Y324846D01*
G01X2560353Y319793D02*
X2559378Y320515D01*
G01X2545249Y319793D02*
X2544762D01*
Y320515D01*
X2545249Y319793D01*
G01X2532078Y351855D02*
X2638902D01*
G01X2528928D02*
X2532078D01*
G01X2578109Y358352D02*
X2579084Y359073D01*
X2580058D01*
X2581033Y358352D01*
G01X2557647Y359073D02*
X2555698Y357630D01*
X2554723Y356186D01*
X2554236Y354021D01*
X2558134D01*
G01X2582007Y356186D02*
X2581033Y354743D01*
X2580058Y354021D01*
X2579084D01*
G01X2554236Y361239D02*
X2554723Y361960D01*
X2555698Y362682D01*
X2556672D01*
X2557647Y361960D01*
X2558134Y361239D01*
Y359795D01*
X2557647Y359073D01*
G01X2541461Y351855D02*
X2548679Y364848D01*
G01X2540739Y358352D02*
X2541461Y360517D01*
X2542904Y361960D01*
X2545070Y362682D01*
X2547235Y361960D01*
X2548679Y360517D01*
X2549400Y358352D01*
X2548679Y356186D01*
X2547235Y354743D01*
X2545070Y354021D01*
X2542904Y354743D01*
X2541461Y356186D01*
X2540739Y358352D01*
G01X2577135Y356186D02*
Y356908D01*
X2578109Y358352D01*
G01X2571776Y362682D02*
Y354021D01*
G01X2581033Y358352D02*
X2582007Y356908D01*
Y356186D01*
G01X2579084Y359073D02*
X2578109Y359795D01*
X2577622Y360517D01*
Y361239D01*
X2578109Y361960D01*
X2579084Y362682D01*
X2580058D01*
X2581033Y361960D01*
X2581520Y361239D01*
Y360517D01*
X2581033Y359795D01*
X2580058Y359073D01*
G01X2579084Y354021D02*
X2578109Y354743D01*
X2577135Y356186D01*
G01X2563980Y354021D02*
X2563493D01*
Y354743D01*
X2563980Y354021D01*
G01X2585178Y426106D02*
X2584204Y425384D01*
X2583229D01*
X2582255Y426106D01*
X2581768Y426827D01*
G01X2582255Y433323D02*
X2583229Y434045D01*
X2584204D01*
X2585178Y433323D01*
X2585665Y432602D01*
Y431880D01*
X2585178Y431158D01*
X2584204Y430436D01*
X2585178Y429715D01*
X2586153Y428271D01*
G01D02*
Y427549D01*
X2585178Y426106D01*
G01Y440344D02*
Y449006D01*
X2581768Y442510D01*
X2586153D01*
G01X2583229Y430436D02*
X2584204D01*
G01X2581768Y543113D02*
X2582255Y544557D01*
X2583716Y545279D01*
X2585178Y544557D01*
X2585665Y543113D01*
X2585178Y541670D01*
X2584691Y540948D01*
X2583716Y540226D01*
X2582742Y540948D01*
X2582255Y541670D01*
X2581768Y543113D01*
Y546001D01*
X2582255Y547444D01*
X2582742Y548166D01*
X2583716Y548888D01*
X2584691Y548166D01*
X2585178Y547444D01*
G01X2583716Y957667D02*
Y949006D01*
G01X2583229Y1348284D02*
X2582255Y1346840D01*
X2581768Y1344675D01*
X2585665D01*
G01X2581768Y1351893D02*
X2582255Y1352615D01*
X2583229Y1353337D01*
X2584204D01*
X2585178Y1352615D01*
X2585665Y1351893D01*
Y1350449D01*
X2585178Y1349728D01*
X2583229Y1348284D01*
G01X2515842Y1713396D02*
G03X2514858Y1712411I0J-984D01*
G01Y1709459D02*
G03X2515842Y1708474I984J-1D01*
G01X2529622Y1718474D02*
G03X2530606Y1719459I0J984D01*
G01X2514858D02*
G03X2515842Y1718474I984J-1D01*
G01X2529622Y1708474D02*
G03X2530606Y1709459I0J984D01*
G01Y1712411D02*
G03X2529622Y1713396I-984J1D01*
G01X2534524Y1714412D02*
X2534666Y1714288D01*
G01X2534527Y1714410D02*
X2534364Y1714502D01*
G01X2534367Y1714501D02*
X2534192Y1714558D01*
G01X2534533Y1708277D02*
Y1713592D01*
G01Y1723592D02*
Y1718277D01*
G01X2532575Y1959833D02*
Y1702037D01*
G01X2531080Y1707293D02*
Y1714577D01*
G01Y1724577D02*
Y1717293D01*
G01X2530606Y1712411D02*
Y1709459D01*
G01Y1722411D02*
Y1719459D01*
G01X2529622Y1708474D02*
Y1706860D01*
G01Y1715010D02*
Y1713396D01*
G01Y1718474D02*
Y1716860D01*
G01X2529079Y1714577D02*
Y1707293D01*
G01Y1724577D02*
Y1717293D01*
G01X2528638Y1708474D02*
Y1706860D01*
G01Y1715010D02*
Y1713396D01*
G01Y1718474D02*
Y1716860D01*
G01X2528271Y1714577D02*
Y1707293D01*
G01Y1724577D02*
Y1717293D01*
G01X2527630Y1714577D02*
Y1707293D01*
G01Y1724577D02*
Y1717293D01*
G01X2527478Y1714577D02*
Y1707293D01*
G01Y1724577D02*
Y1717293D01*
G01X2534195Y1714557D02*
X2534012Y1714577D01*
G01X2514858Y1712411D02*
Y1709459D01*
G01Y1722411D02*
Y1719459D01*
G01X2529622Y1718474D02*
X2515842D01*
G01X2534937Y1718277D02*
X2534533D01*
G01X2534937Y1713592D02*
X2534533D01*
G01X2529622Y1713396D02*
X2515842D01*
G01X2529622Y1708474D02*
X2515842D01*
G01X2534937Y1708277D02*
X2534533D01*
G01X2540449Y1702037D02*
X2532575D01*
G01X2534195Y1717313D02*
X2534012Y1717293D01*
G01X2534195Y1707313D02*
X2534012Y1707293D01*
G01X2534524Y1707458D02*
X2534666Y1707581D01*
G01X2534524Y1717458D02*
X2534666Y1717581D01*
G01X2534364Y1707367D02*
X2534527Y1707460D01*
G01X2534364Y1717367D02*
X2534527Y1717460D01*
G01X2534192Y1707312D02*
X2534367Y1707369D01*
G01X2534192Y1717312D02*
X2534367Y1717369D01*
G01X2534867Y1713967D02*
X2534781Y1714140D01*
G01X2534782Y1714137D02*
X2534666Y1714288D01*
G01X2540449Y1698100D02*
X2535724Y1702825D01*
G01X2534919Y1713784D02*
X2534866Y1713971D01*
G01X2540449Y1966919D02*
Y1694951D01*
G01X2539872Y1706860D02*
Y1698677D01*
G01Y1716860D02*
Y1715010D01*
G01X2537890Y1716860D02*
Y1715010D01*
G01X2537102Y1701447D02*
Y1706860D01*
G01X2534937Y1713592D02*
Y1708277D01*
G01Y1723592D02*
Y1718277D01*
G01X2534919Y1713787D02*
X2534937Y1713592D01*
G01X2534919Y1708083D02*
X2534937Y1708277D01*
G01X2534919Y1718083D02*
X2534937Y1718277D01*
G01X2534866Y1707899D02*
X2534919Y1708086D01*
G01X2534866Y1717899D02*
X2534919Y1718086D01*
G01X2534781Y1707730D02*
X2534867Y1707902D01*
G01X2534781Y1717730D02*
X2534867Y1717902D01*
G01X2534782Y1707733D02*
X2534666Y1707581D01*
G01X2534782Y1717733D02*
X2534666Y1717581D01*
G01X2530606Y1722411D02*
G03X2529622Y1723396I-984J1D01*
G01X2515842D02*
G03X2514858Y1722411I0J-984D01*
G01X2529622Y1725010D02*
Y1723396D01*
G01X2528638Y1725010D02*
Y1723396D01*
G01X2534937Y1723592D02*
X2534533D01*
G01X2529622Y1723396D02*
X2515842D01*
G01X2530606Y1772411D02*
G03X2529622Y1773396I-984J1D01*
G01Y1768474D02*
G03X2530606Y1769459I0J984D01*
G01X2529622Y1788474D02*
G03X2530606Y1789459I0J984D01*
G01Y1792411D02*
G03X2529622Y1793396I-984J1D01*
G01X2530606Y1782411D02*
G03X2529622Y1783396I-984J1D01*
G01Y1778474D02*
G03X2530606Y1779459I0J984D01*
G01X2515842Y1773396D02*
G03X2514858Y1772411I0J-984D01*
G01Y1769459D02*
G03X2515842Y1768474I984J-1D01*
G01Y1793396D02*
G03X2514858Y1792411I0J-984D01*
G01Y1789459D02*
G03X2515842Y1788474I984J-1D01*
G01Y1783396D02*
G03X2514858Y1782411I0J-984D01*
G01Y1779459D02*
G03X2515842Y1778474I984J-1D01*
G01X2530606Y1762411D02*
G03X2529622Y1763396I-984J1D01*
G01Y1758474D02*
G03X2530606Y1759459I0J984D01*
G01X2529622Y1748474D02*
G03X2530606Y1749459I0J984D01*
G01Y1752411D02*
G03X2529622Y1753396I-984J1D01*
G01X2530606Y1742411D02*
G03X2529622Y1743396I-984J1D01*
G01X2530606Y1732411D02*
G03X2529622Y1733396I-984J1D01*
G01Y1728474D02*
G03X2530606Y1729459I0J984D01*
G01X2529622Y1738474D02*
G03X2530606Y1739459I0J984D01*
G01X2515842Y1743396D02*
G03X2514858Y1742411I0J-984D01*
G01X2515842Y1753396D02*
G03X2514858Y1752411I0J-984D01*
G01Y1749459D02*
G03X2515842Y1748474I984J-1D01*
G01Y1763396D02*
G03X2514858Y1762411I0J-984D01*
G01Y1759459D02*
G03X2515842Y1758474I984J-1D01*
G01X2514858Y1739459D02*
G03X2515842Y1738474I984J-1D01*
G01Y1733396D02*
G03X2514858Y1732411I0J-984D01*
G01Y1729459D02*
G03X2515842Y1728474I984J-1D01*
G01X2534524Y1784412D02*
X2534666Y1784288D01*
G01X2534524Y1774412D02*
X2534666Y1774288D01*
G01X2534524Y1764412D02*
X2534666Y1764288D01*
G01X2534524Y1754412D02*
X2534666Y1754288D01*
G01X2534524Y1744412D02*
X2534666Y1744288D01*
G01X2534524Y1734412D02*
X2534666Y1734288D01*
G01X2534524Y1724412D02*
X2534666Y1724288D01*
G01X2534527Y1784410D02*
X2534364Y1784502D01*
G01X2534527Y1774410D02*
X2534364Y1774502D01*
G01X2534527Y1764410D02*
X2534364Y1764502D01*
G01X2534527Y1754410D02*
X2534364Y1754502D01*
G01X2534527Y1744410D02*
X2534364Y1744502D01*
G01X2534527Y1734410D02*
X2534364Y1734502D01*
G01X2534527Y1724410D02*
X2534364Y1724502D01*
G01X2534367Y1784501D02*
X2534192Y1784558D01*
G01X2534367Y1774501D02*
X2534192Y1774558D01*
G01X2534367Y1764501D02*
X2534192Y1764558D01*
G01X2534367Y1754501D02*
X2534192Y1754558D01*
G01X2534367Y1744501D02*
X2534192Y1744558D01*
G01X2534367Y1734501D02*
X2534192Y1734558D01*
G01X2534367Y1724501D02*
X2534192Y1724558D01*
G01X2534195Y1784557D02*
X2534012Y1784577D01*
G01X2534195Y1774557D02*
X2534012Y1774577D01*
G01X2534195Y1764557D02*
X2534012Y1764577D01*
G01X2534533Y1788277D02*
Y1793592D01*
G01Y1768277D02*
Y1773592D01*
G01Y1748277D02*
Y1753592D01*
G01Y1728277D02*
Y1733592D01*
G01Y1743592D02*
Y1738277D01*
G01Y1763592D02*
Y1758277D01*
G01Y1783592D02*
Y1778277D01*
G01X2531080Y1787293D02*
Y1794577D01*
G01Y1767293D02*
Y1774577D01*
G01Y1747293D02*
Y1754577D01*
G01Y1727293D02*
Y1734577D01*
G01Y1744577D02*
Y1737293D01*
G01Y1764577D02*
Y1757293D01*
G01Y1784577D02*
Y1777293D01*
G01X2530606Y1732411D02*
Y1729459D01*
G01Y1742411D02*
Y1739459D01*
G01Y1752411D02*
Y1749459D01*
G01Y1762411D02*
Y1759459D01*
G01Y1772411D02*
Y1769459D01*
G01Y1782411D02*
Y1779459D01*
G01Y1792411D02*
Y1789459D01*
G01X2529622Y1776860D02*
Y1778474D01*
G01Y1736860D02*
Y1738474D01*
G01Y1728474D02*
Y1726860D01*
G01Y1735010D02*
Y1733396D01*
G01Y1748474D02*
Y1746860D01*
G01Y1745010D02*
Y1743396D01*
G01Y1755010D02*
Y1753396D01*
G01Y1758474D02*
Y1756860D01*
G01Y1765010D02*
Y1763396D01*
G01Y1768474D02*
Y1766860D01*
G01Y1775010D02*
Y1773396D01*
G01Y1785010D02*
Y1783396D01*
G01Y1788474D02*
Y1786860D01*
G01Y1795010D02*
Y1793396D01*
G01X2529079Y1734577D02*
Y1727293D01*
G01Y1744577D02*
Y1737293D01*
G01Y1754577D02*
Y1747293D01*
G01Y1764577D02*
Y1757293D01*
G01Y1774577D02*
Y1767293D01*
G01Y1784577D02*
Y1777293D01*
G01Y1794577D02*
Y1787293D01*
G01X2528638Y1728474D02*
Y1726860D01*
G01Y1735010D02*
Y1733396D01*
G01Y1738474D02*
Y1736860D01*
G01Y1745010D02*
Y1743396D01*
G01Y1748474D02*
Y1746860D01*
G01Y1755010D02*
Y1753396D01*
G01Y1758474D02*
Y1756860D01*
G01Y1765010D02*
Y1763396D01*
G01Y1768474D02*
Y1766860D01*
G01Y1775010D02*
Y1773396D01*
G01Y1778474D02*
Y1776860D01*
G01Y1785010D02*
Y1783396D01*
G01Y1788474D02*
Y1786860D01*
G01Y1795010D02*
Y1793396D01*
G01X2528271Y1734577D02*
Y1727293D01*
G01Y1744577D02*
Y1737293D01*
G01Y1754577D02*
Y1747293D01*
G01Y1764577D02*
Y1757293D01*
G01Y1774577D02*
Y1767293D01*
G01Y1784577D02*
Y1777293D01*
G01Y1794577D02*
Y1787293D01*
G01X2527630Y1734577D02*
Y1727293D01*
G01Y1744577D02*
Y1737293D01*
G01Y1754577D02*
Y1747293D01*
G01Y1764577D02*
Y1757293D01*
G01Y1774577D02*
Y1767293D01*
G01Y1784577D02*
Y1777293D01*
G01Y1794577D02*
Y1787293D01*
G01X2527478Y1734577D02*
Y1727293D01*
G01Y1744577D02*
Y1737293D01*
G01Y1754577D02*
Y1747293D01*
G01Y1764577D02*
Y1757293D01*
G01Y1774577D02*
Y1767293D01*
G01Y1784577D02*
Y1777293D01*
G01Y1794577D02*
Y1787293D01*
G01X2534195Y1754557D02*
X2534012Y1754577D01*
G01X2534195Y1744557D02*
X2534012Y1744577D01*
G01X2534195Y1734557D02*
X2534012Y1734577D01*
G01X2534195Y1724557D02*
X2534012Y1724577D01*
G01X2534937Y1793592D02*
X2534533D01*
G01X2529622Y1793396D02*
X2515842D01*
G01X2529622Y1788474D02*
X2515842D01*
G01X2534937Y1788277D02*
X2534533D01*
G01X2534937Y1783592D02*
X2534533D01*
G01X2529622Y1783396D02*
X2515842D01*
G01X2529622Y1778474D02*
X2515842D01*
G01X2534937Y1778277D02*
X2534533D01*
G01X2534937Y1773592D02*
X2534533D01*
G01X2529622Y1773396D02*
X2515842D01*
G01X2529622Y1768474D02*
X2515842D01*
G01X2534937Y1768277D02*
X2534533D01*
G01X2534937Y1763592D02*
X2534533D01*
G01X2529622Y1763396D02*
X2515842D01*
G01X2529622Y1758474D02*
X2515842D01*
G01X2534937Y1758277D02*
X2534533D01*
G01X2534937Y1753592D02*
X2534533D01*
G01X2529622Y1753396D02*
X2515842D01*
G01X2529622Y1748474D02*
X2515842D01*
G01X2534937Y1748277D02*
X2534533D01*
G01X2534937Y1743592D02*
X2534533D01*
G01X2529622Y1743396D02*
X2515842D01*
G01X2529622Y1738474D02*
X2515842D01*
G01X2534937Y1738277D02*
X2534533D01*
G01X2514858Y1732411D02*
Y1729459D01*
G01Y1742411D02*
Y1739459D01*
G01Y1752411D02*
Y1749459D01*
G01Y1762411D02*
Y1759459D01*
G01Y1772411D02*
Y1769459D01*
G01Y1782411D02*
Y1779459D01*
G01Y1792411D02*
Y1789459D01*
G01X2534937Y1733592D02*
X2534533D01*
G01X2529622Y1733396D02*
X2515842D01*
G01X2529622Y1728474D02*
X2515842D01*
G01X2534937Y1728277D02*
X2534533D01*
G01X2534195Y1787313D02*
X2534012Y1787293D01*
G01X2534195Y1777313D02*
X2534012Y1777293D01*
G01X2534195Y1767313D02*
X2534012Y1767293D01*
G01X2534195Y1757313D02*
X2534012Y1757293D01*
G01X2534195Y1747313D02*
X2534012Y1747293D01*
G01X2534195Y1737313D02*
X2534012Y1737293D01*
G01X2534195Y1727313D02*
X2534012Y1727293D01*
G01X2534524Y1727458D02*
X2534666Y1727581D01*
G01X2534524Y1737458D02*
X2534666Y1737581D01*
G01X2534524Y1747458D02*
X2534666Y1747581D01*
G01X2534524Y1757458D02*
X2534666Y1757581D01*
G01X2534524Y1767458D02*
X2534666Y1767581D01*
G01X2534524Y1777458D02*
X2534666Y1777581D01*
G01X2534524Y1787458D02*
X2534666Y1787581D01*
G01X2534364Y1727367D02*
X2534527Y1727460D01*
G01X2534364Y1737367D02*
X2534527Y1737460D01*
G01X2534364Y1747367D02*
X2534527Y1747460D01*
G01X2534364Y1757367D02*
X2534527Y1757460D01*
G01X2534364Y1767367D02*
X2534527Y1767460D01*
G01X2534364Y1777367D02*
X2534527Y1777460D01*
G01X2534364Y1787367D02*
X2534527Y1787460D01*
G01X2534192Y1727312D02*
X2534367Y1727369D01*
G01X2534192Y1737312D02*
X2534367Y1737369D01*
G01X2534192Y1747312D02*
X2534367Y1747369D01*
G01X2534192Y1757312D02*
X2534367Y1757369D01*
G01X2534192Y1767312D02*
X2534367Y1767369D01*
G01X2534192Y1777312D02*
X2534367Y1777369D01*
G01X2534192Y1787312D02*
X2534367Y1787369D01*
G01X2534867Y1723967D02*
X2534781Y1724140D01*
G01X2534782Y1724137D02*
X2534666Y1724288D01*
G01X2534919Y1723784D02*
X2534866Y1723971D01*
G01X2534919Y1723787D02*
X2534937Y1723592D01*
G01X2534867Y1783967D02*
X2534781Y1784140D01*
G01X2534867Y1773967D02*
X2534781Y1774140D01*
G01X2534867Y1763967D02*
X2534781Y1764140D01*
G01X2534867Y1753967D02*
X2534781Y1754140D01*
G01X2534867Y1743967D02*
X2534781Y1744140D01*
G01X2534867Y1733967D02*
X2534781Y1734140D01*
G01X2534782Y1784137D02*
X2534666Y1784288D01*
G01X2534782Y1774137D02*
X2534666Y1774288D01*
G01X2534782Y1764137D02*
X2534666Y1764288D01*
G01X2534782Y1754137D02*
X2534666Y1754288D01*
G01X2534782Y1744137D02*
X2534666Y1744288D01*
G01X2534782Y1734137D02*
X2534666Y1734288D01*
G01X2534919Y1793784D02*
X2534866Y1793971D01*
G01X2534919Y1783784D02*
X2534866Y1783971D01*
G01X2534919Y1773784D02*
X2534866Y1773971D01*
G01X2534919Y1763784D02*
X2534866Y1763971D01*
G01X2534919Y1753784D02*
X2534866Y1753971D01*
G01X2534919Y1743784D02*
X2534866Y1743971D01*
G01X2534919Y1733784D02*
X2534866Y1733971D01*
G01X2539872Y1726860D02*
Y1725010D01*
G01Y1736860D02*
Y1735010D01*
G01Y1746860D02*
Y1745010D01*
G01Y1756860D02*
Y1755010D01*
G01Y1766860D02*
Y1765010D01*
G01Y1776860D02*
Y1775010D01*
G01Y1786860D02*
Y1785010D01*
G01X2537890Y1726860D02*
Y1725010D01*
G01Y1736860D02*
Y1735010D01*
G01Y1756860D02*
Y1755010D01*
G01Y1766860D02*
Y1765010D01*
G01Y1776860D02*
Y1775010D01*
G01X2537102Y1746860D02*
Y1745010D01*
G01Y1786860D02*
Y1785010D01*
G01X2534937Y1768277D02*
Y1773592D01*
G01Y1728277D02*
Y1733592D01*
G01Y1743592D02*
Y1738277D01*
G01Y1753592D02*
Y1748277D01*
G01Y1763592D02*
Y1758277D01*
G01Y1783592D02*
Y1778277D01*
G01Y1793592D02*
Y1788277D01*
G01X2534919Y1793787D02*
X2534937Y1793592D01*
G01X2534919Y1783787D02*
X2534937Y1783592D01*
G01X2534919Y1773787D02*
X2534937Y1773592D01*
G01X2534919Y1763787D02*
X2534937Y1763592D01*
G01X2534919Y1753787D02*
X2534937Y1753592D01*
G01X2534919Y1743787D02*
X2534937Y1743592D01*
G01X2534919Y1733787D02*
X2534937Y1733592D01*
G01X2534919Y1728083D02*
X2534937Y1728277D01*
G01X2534919Y1738083D02*
X2534937Y1738277D01*
G01X2534919Y1748083D02*
X2534937Y1748277D01*
G01X2534919Y1758083D02*
X2534937Y1758277D01*
G01X2534919Y1768083D02*
X2534937Y1768277D01*
G01X2534919Y1778083D02*
X2534937Y1778277D01*
G01X2534919Y1788083D02*
X2534937Y1788277D01*
G01X2534866Y1727899D02*
X2534919Y1728086D01*
G01X2534866Y1737899D02*
X2534919Y1738086D01*
G01X2534866Y1747899D02*
X2534919Y1748086D01*
G01X2534866Y1757899D02*
X2534919Y1758086D01*
G01X2534866Y1767899D02*
X2534919Y1768086D01*
G01X2534866Y1777899D02*
X2534919Y1778086D01*
G01X2534866Y1787899D02*
X2534919Y1788086D01*
G01X2534781Y1727730D02*
X2534867Y1727902D01*
G01X2534781Y1737730D02*
X2534867Y1737902D01*
G01X2534781Y1747730D02*
X2534867Y1747902D01*
G01X2534781Y1757730D02*
X2534867Y1757902D01*
G01X2534781Y1767730D02*
X2534867Y1767902D01*
G01X2534781Y1777730D02*
X2534867Y1777902D01*
G01X2534781Y1787730D02*
X2534867Y1787902D01*
G01X2534782Y1727733D02*
X2534666Y1727581D01*
G01X2534782Y1737733D02*
X2534666Y1737581D01*
G01X2534782Y1747733D02*
X2534666Y1747581D01*
G01X2534782Y1757733D02*
X2534666Y1757581D01*
G01X2534782Y1767733D02*
X2534666Y1767581D01*
G01X2534782Y1777733D02*
X2534666Y1777581D01*
G01X2534782Y1787733D02*
X2534666Y1787581D01*
G01X2534524Y1794412D02*
X2534666Y1794288D01*
G01X2534527Y1794410D02*
X2534364Y1794502D01*
G01X2534367Y1794501D02*
X2534192Y1794558D01*
G01X2534195Y1794557D02*
X2534012Y1794577D01*
G01X2529622Y1798474D02*
Y1796860D01*
G01X2528638Y1798474D02*
Y1796860D01*
G01X2530606Y1862411D02*
G03X2529622Y1863396I-984J1D01*
G01Y1858474D02*
G03X2530606Y1859459I0J984D01*
G01Y1852411D02*
G03X2529622Y1853396I-984J1D01*
G01Y1848474D02*
G03X2530606Y1849459I0J984D01*
G01Y1842411D02*
G03X2529622Y1843396I-984J1D01*
G01Y1838474D02*
G03X2530606Y1839459I0J984D01*
G01X2529622Y1828474D02*
G03X2530606Y1829459I0J984D01*
G01Y1832411D02*
G03X2529622Y1833396I-984J1D01*
G01X2530606Y1822411D02*
G03X2529622Y1823396I-984J1D01*
G01Y1818474D02*
G03X2530606Y1819459I0J984D01*
G01Y1802411D02*
G03X2529622Y1803396I-984J1D01*
G01Y1798474D02*
G03X2530606Y1799459I0J984D01*
G01Y1812411D02*
G03X2529622Y1813396I-984J1D01*
G01Y1808474D02*
G03X2530606Y1809459I0J984D01*
G01X2515842Y1833396D02*
G03X2514858Y1832411I0J-984D01*
G01Y1829459D02*
G03X2515842Y1828474I984J-1D01*
G01Y1863396D02*
G03X2514858Y1862411I0J-984D01*
G01Y1859459D02*
G03X2515842Y1858474I984J-1D01*
G01Y1853396D02*
G03X2514858Y1852411I0J-984D01*
G01Y1849459D02*
G03X2515842Y1848474I984J-1D01*
G01Y1843396D02*
G03X2514858Y1842411I0J-984D01*
G01Y1839459D02*
G03X2515842Y1838474I984J-1D01*
G01Y1823396D02*
G03X2514858Y1822411I0J-984D01*
G01Y1819459D02*
G03X2515842Y1818474I984J-1D01*
G01Y1803396D02*
G03X2514858Y1802411I0J-984D01*
G01Y1799459D02*
G03X2515842Y1798474I984J-1D01*
G01Y1813396D02*
G03X2514858Y1812411I0J-984D01*
G01Y1809459D02*
G03X2515842Y1808474I984J-1D01*
G01X2534524Y1864412D02*
X2534666Y1864288D01*
G01X2534524Y1854412D02*
X2534666Y1854288D01*
G01X2534524Y1844412D02*
X2534666Y1844288D01*
G01X2534524Y1834412D02*
X2534666Y1834288D01*
G01X2534524Y1824412D02*
X2534666Y1824288D01*
G01X2534524Y1814412D02*
X2534666Y1814288D01*
G01X2534524Y1804412D02*
X2534666Y1804288D01*
G01X2534527Y1864410D02*
X2534364Y1864502D01*
G01X2534527Y1854410D02*
X2534364Y1854502D01*
G01X2534527Y1844410D02*
X2534364Y1844502D01*
G01X2534527Y1834410D02*
X2534364Y1834502D01*
G01X2534527Y1824410D02*
X2534364Y1824502D01*
G01X2534527Y1814410D02*
X2534364Y1814502D01*
G01X2534527Y1804410D02*
X2534364Y1804502D01*
G01X2534367Y1864501D02*
X2534192Y1864558D01*
G01X2534367Y1854501D02*
X2534192Y1854558D01*
G01X2534367Y1844501D02*
X2534192Y1844558D01*
G01X2534367Y1834501D02*
X2534192Y1834558D01*
G01X2534367Y1824501D02*
X2534192Y1824558D01*
G01X2534367Y1814501D02*
X2534192Y1814558D01*
G01X2534367Y1804501D02*
X2534192Y1804558D01*
G01X2534195Y1864557D02*
X2534012Y1864577D01*
G01X2534195Y1854557D02*
X2534012Y1854577D01*
G01X2534195Y1844557D02*
X2534012Y1844577D01*
G01X2534195Y1834557D02*
X2534012Y1834577D01*
G01X2534195Y1824557D02*
X2534012Y1824577D01*
G01X2534195Y1814557D02*
X2534012Y1814577D01*
G01X2534195Y1804557D02*
X2534012Y1804577D01*
G01X2534937Y1863592D02*
X2534533D01*
G01X2529622Y1863396D02*
X2515842D01*
G01X2529622Y1858474D02*
X2515842D01*
G01X2534937Y1858277D02*
X2534533D01*
G01X2534937Y1853592D02*
X2534533D01*
G01X2529622Y1853396D02*
X2515842D01*
G01X2529622Y1848474D02*
X2515842D01*
G01X2534937Y1848277D02*
X2534533D01*
G01X2534937Y1843592D02*
X2534533D01*
G01X2529622Y1843396D02*
X2515842D01*
G01X2529622Y1838474D02*
X2515842D01*
G01X2534937Y1838277D02*
X2534533D01*
G01X2534937Y1833592D02*
X2534533D01*
G01X2529622Y1833396D02*
X2515842D01*
G01X2529622Y1828474D02*
X2515842D01*
G01X2534937Y1828277D02*
X2534533D01*
G01X2534937Y1823592D02*
X2534533D01*
G01X2529622Y1823396D02*
X2515842D01*
G01X2529622Y1818474D02*
X2515842D01*
G01X2534937Y1818277D02*
X2534533D01*
G01X2534937Y1813592D02*
X2534533D01*
G01X2529622Y1813396D02*
X2515842D01*
G01X2534533Y1828277D02*
Y1833592D01*
G01Y1808277D02*
Y1813592D01*
G01Y1803592D02*
Y1798277D01*
G01Y1823592D02*
Y1818277D01*
G01Y1843592D02*
Y1838277D01*
G01Y1853592D02*
Y1848277D01*
G01Y1863592D02*
Y1858277D01*
G01X2531080Y1827293D02*
Y1834577D01*
G01Y1807293D02*
Y1814577D01*
G01Y1804577D02*
Y1797293D01*
G01Y1824577D02*
Y1817293D01*
G01Y1844577D02*
Y1837293D01*
G01Y1854577D02*
Y1847293D01*
G01Y1864577D02*
Y1857293D01*
G01X2530606Y1802411D02*
Y1799459D01*
G01Y1812411D02*
Y1809459D01*
G01Y1822411D02*
Y1819459D01*
G01Y1832411D02*
Y1829459D01*
G01Y1842411D02*
Y1839459D01*
G01Y1852411D02*
Y1849459D01*
G01Y1862411D02*
Y1859459D01*
G01X2529622Y1856860D02*
Y1858474D01*
G01Y1836860D02*
Y1838474D01*
G01Y1816860D02*
Y1818474D01*
G01Y1805010D02*
Y1803396D01*
G01Y1808474D02*
Y1806860D01*
G01Y1815010D02*
Y1813396D01*
G01Y1828474D02*
Y1826860D01*
G01Y1825010D02*
Y1823396D01*
G01Y1835010D02*
Y1833396D01*
G01Y1845010D02*
Y1843396D01*
G01Y1848474D02*
Y1846860D01*
G01Y1855010D02*
Y1853396D01*
G01Y1865010D02*
Y1863396D01*
G01X2529079Y1804577D02*
Y1797293D01*
G01Y1814577D02*
Y1807293D01*
G01Y1824577D02*
Y1817293D01*
G01Y1834577D02*
Y1827293D01*
G01Y1844577D02*
Y1837293D01*
G01Y1854577D02*
Y1847293D01*
G01Y1864577D02*
Y1857293D01*
G01X2528638Y1805010D02*
Y1803396D01*
G01Y1808474D02*
Y1806860D01*
G01Y1815010D02*
Y1813396D01*
G01Y1818474D02*
Y1816860D01*
G01Y1825010D02*
Y1823396D01*
G01Y1828474D02*
Y1826860D01*
G01Y1835010D02*
Y1833396D01*
G01Y1838474D02*
Y1836860D01*
G01Y1845010D02*
Y1843396D01*
G01Y1848474D02*
Y1846860D01*
G01Y1855010D02*
Y1853396D01*
G01Y1858474D02*
Y1856860D01*
G01Y1865010D02*
Y1863396D01*
G01X2528271Y1804577D02*
Y1797293D01*
G01Y1814577D02*
Y1807293D01*
G01Y1824577D02*
Y1817293D01*
G01Y1834577D02*
Y1827293D01*
G01Y1844577D02*
Y1837293D01*
G01Y1854577D02*
Y1847293D01*
G01Y1864577D02*
Y1857293D01*
G01X2527630Y1804577D02*
Y1797293D01*
G01Y1814577D02*
Y1807293D01*
G01Y1824577D02*
Y1817293D01*
G01Y1834577D02*
Y1827293D01*
G01Y1844577D02*
Y1837293D01*
G01Y1854577D02*
Y1847293D01*
G01Y1864577D02*
Y1857293D01*
G01X2527478Y1804577D02*
Y1797293D01*
G01Y1814577D02*
Y1807293D01*
G01Y1824577D02*
Y1817293D01*
G01Y1834577D02*
Y1827293D01*
G01Y1844577D02*
Y1837293D01*
G01Y1854577D02*
Y1847293D01*
G01Y1864577D02*
Y1857293D01*
G01X2529622Y1808474D02*
X2515842D01*
G01X2534937Y1808277D02*
X2534533D01*
G01X2534937Y1803592D02*
X2534533D01*
G01X2529622Y1803396D02*
X2515842D01*
G01X2529622Y1798474D02*
X2515842D01*
G01X2534937Y1798277D02*
X2534533D01*
G01X2534195Y1857313D02*
X2534012Y1857293D01*
G01X2534195Y1847313D02*
X2534012Y1847293D01*
G01X2534195Y1837313D02*
X2534012Y1837293D01*
G01X2534195Y1827313D02*
X2534012Y1827293D01*
G01X2534195Y1817313D02*
X2534012Y1817293D01*
G01X2534195Y1807313D02*
X2534012Y1807293D01*
G01X2514858Y1802411D02*
Y1799459D01*
G01Y1812411D02*
Y1809459D01*
G01Y1822411D02*
Y1819459D01*
G01Y1832411D02*
Y1829459D01*
G01Y1842411D02*
Y1839459D01*
G01Y1852411D02*
Y1849459D01*
G01Y1862411D02*
Y1859459D01*
G01X2534195Y1797313D02*
X2534012Y1797293D01*
G01X2534782Y1847733D02*
X2534666Y1847581D01*
X2534527Y1847460D01*
G01X2534524Y1797458D02*
X2534666Y1797581D01*
G01X2534524Y1807458D02*
X2534666Y1807581D01*
G01X2534524Y1817458D02*
X2534666Y1817581D01*
G01X2534524Y1827458D02*
X2534666Y1827581D01*
G01X2534524Y1837458D02*
X2534666Y1837581D01*
G01X2534524Y1847458D02*
X2534666Y1847581D01*
G01X2534524Y1857458D02*
X2534666Y1857581D01*
X2534781Y1857730D01*
X2534866Y1857899D01*
X2534919Y1858086D01*
G01X2534364Y1797367D02*
X2534527Y1797460D01*
G01X2534364Y1807367D02*
X2534527Y1807460D01*
G01X2534364Y1817367D02*
X2534527Y1817460D01*
G01X2534364Y1827367D02*
X2534527Y1827460D01*
G01X2534364Y1837367D02*
X2534527Y1837460D01*
G01X2534364Y1847367D02*
X2534527Y1847460D01*
G01X2534364Y1857367D02*
X2534527Y1857460D01*
G01X2534192Y1797312D02*
X2534367Y1797369D01*
G01X2534192Y1807312D02*
X2534367Y1807369D01*
G01X2534192Y1817312D02*
X2534367Y1817369D01*
G01X2534192Y1827312D02*
X2534367Y1827369D01*
G01X2534192Y1837312D02*
X2534367Y1837369D01*
G01X2534192Y1847312D02*
X2534367Y1847369D01*
G01X2534192Y1857312D02*
X2534367Y1857369D01*
G01X2534867Y1793967D02*
X2534781Y1794140D01*
G01X2534782Y1794137D02*
X2534666Y1794288D01*
G01X2539872Y1796860D02*
Y1795010D01*
G01X2537890Y1796860D02*
Y1795010D01*
G01X2534782Y1864137D02*
X2534666Y1864288D01*
G01X2534782Y1854137D02*
X2534666Y1854288D01*
G01X2534782Y1844137D02*
X2534666Y1844288D01*
G01X2534782Y1834137D02*
X2534666Y1834288D01*
G01X2534782Y1824137D02*
X2534666Y1824288D01*
G01X2534782Y1814137D02*
X2534666Y1814288D01*
G01X2534919Y1863784D02*
X2534866Y1863971D01*
G01X2534919Y1853784D02*
X2534866Y1853971D01*
G01X2534919Y1843784D02*
X2534866Y1843971D01*
G01X2534867Y1863967D02*
X2534781Y1864140D01*
G01X2534867Y1853967D02*
X2534781Y1854140D01*
G01X2534867Y1843967D02*
X2534781Y1844140D01*
G01X2534867Y1833967D02*
X2534781Y1834140D01*
G01X2534867Y1823967D02*
X2534781Y1824140D01*
G01X2534867Y1813967D02*
X2534781Y1814140D01*
G01X2534867Y1803967D02*
X2534781Y1804140D01*
G01X2534782Y1804137D02*
X2534666Y1804288D01*
G01X2534919Y1833784D02*
X2534866Y1833971D01*
G01X2534919Y1823784D02*
X2534866Y1823971D01*
G01X2534919Y1813784D02*
X2534866Y1813971D01*
G01X2534919Y1803784D02*
X2534866Y1803971D01*
G01X2539872Y1806860D02*
Y1805010D01*
G01Y1816860D02*
Y1815010D01*
G01Y1826860D02*
Y1825010D01*
G01Y1836860D02*
Y1835010D01*
G01Y1846860D02*
Y1845010D01*
G01Y1856860D02*
Y1855010D01*
G01Y1866860D02*
Y1865010D01*
G01X2537890Y1806860D02*
Y1805010D01*
G01Y1816860D02*
Y1815010D01*
G01Y1836860D02*
Y1835010D01*
G01Y1846860D02*
Y1845010D01*
G01Y1856860D02*
Y1855010D01*
G01X2537102Y1826860D02*
Y1825010D01*
G01Y1866860D02*
Y1865010D01*
G01X2534937Y1808277D02*
Y1813592D01*
G01Y1803592D02*
Y1798277D01*
G01Y1823592D02*
Y1818277D01*
G01Y1833592D02*
Y1828277D01*
G01Y1843592D02*
Y1838277D01*
G01Y1853592D02*
Y1848277D01*
G01Y1863592D02*
Y1858277D01*
G01X2534919Y1863787D02*
X2534937Y1863592D01*
G01X2534919Y1853787D02*
X2534937Y1853592D01*
G01X2534919Y1843787D02*
X2534937Y1843592D01*
G01X2534919Y1833787D02*
X2534937Y1833592D01*
G01X2534919Y1823787D02*
X2534937Y1823592D01*
G01X2534919Y1813787D02*
X2534937Y1813592D01*
G01X2534919Y1803787D02*
X2534937Y1803592D01*
G01X2534919Y1798083D02*
X2534937Y1798277D01*
G01X2534919Y1818083D02*
X2534937Y1818277D01*
G01X2534919Y1828083D02*
X2534937Y1828277D01*
G01X2534919Y1838083D02*
X2534937Y1838277D01*
G01X2534919Y1848083D02*
X2534937Y1848277D01*
G01X2534919Y1858083D02*
X2534937Y1858277D01*
G01X2534866Y1797899D02*
X2534919Y1798086D01*
G01Y1808086D02*
X2534867Y1807902D01*
G01X2534866Y1807899D02*
X2534919Y1808083D01*
X2534937Y1808277D01*
G01X2534866Y1817899D02*
X2534919Y1818086D01*
G01X2534866Y1827899D02*
X2534919Y1828086D01*
G01X2534866Y1837899D02*
X2534919Y1838086D01*
G01X2534866Y1847899D02*
X2534919Y1848086D01*
G01X2534781Y1797730D02*
X2534867Y1797902D01*
G01X2534781Y1807730D02*
X2534867Y1807902D01*
G01X2534781Y1817730D02*
X2534867Y1817902D01*
G01X2534781Y1827730D02*
X2534867Y1827902D01*
G01X2534781Y1837730D02*
X2534867Y1837902D01*
G01X2534781Y1847730D02*
X2534867Y1847902D01*
G01Y1857902D02*
X2534782Y1857733D01*
X2534666Y1857581D01*
G01X2534782Y1797733D02*
X2534666Y1797581D01*
G01X2534782Y1807733D02*
X2534666Y1807581D01*
G01X2534782Y1817733D02*
X2534666Y1817581D01*
G01X2534782Y1827733D02*
X2534666Y1827581D01*
G01X2534782Y1837733D02*
X2534666Y1837581D01*
G01X2529622Y1868474D02*
G03X2530606Y1869459I0J984D01*
G01X2514858D02*
G03X2515842Y1868474I984J-1D01*
G01X2529622D02*
X2515842D01*
G01X2534937Y1868277D02*
X2534533D01*
G01D02*
Y1873592D01*
G01X2531080Y1867293D02*
Y1874577D01*
G01X2530606Y1872411D02*
Y1869459D01*
G01X2529622Y1868474D02*
Y1866860D01*
G01X2529079Y1874577D02*
Y1867293D01*
G01X2528638Y1868474D02*
Y1866860D01*
G01X2528271Y1874577D02*
Y1867293D01*
G01X2527630Y1874577D02*
Y1867293D01*
G01X2527478Y1874577D02*
Y1867293D01*
G01X2534195Y1867313D02*
X2534012Y1867293D01*
G01X2514858Y1872411D02*
Y1869459D01*
G01X2534524Y1867458D02*
X2534666Y1867581D01*
G01X2534364Y1867367D02*
X2534527Y1867460D01*
G01X2534192Y1867312D02*
X2534367Y1867369D01*
G01X2530606Y1882411D02*
G03X2529622Y1883396I-984J1D01*
G01Y1878474D02*
G03X2530606Y1879459I0J984D01*
G01X2514858D02*
G03X2515842Y1878474I984J-1D01*
G01Y1883396D02*
G03X2514858Y1882411I0J-984D01*
G01X2530606Y1872411D02*
G03X2529622Y1873396I-984J1D01*
G01X2515842D02*
G03X2514858Y1872411I0J-984D01*
G01X2534524Y1884412D02*
X2534666Y1884288D01*
G01X2534524Y1874412D02*
X2534666Y1874288D01*
G01X2534527Y1884410D02*
X2534364Y1884502D01*
G01X2534527Y1874410D02*
X2534364Y1874502D01*
G01X2534367Y1884501D02*
X2534192Y1884558D01*
G01X2534367Y1874501D02*
X2534192Y1874558D01*
G01X2534195Y1884557D02*
X2534012Y1884577D01*
G01X2534195Y1874557D02*
X2534012Y1874577D01*
G01X2534937Y1883592D02*
X2534533D01*
G01X2529622Y1883396D02*
X2515842D01*
G01X2529622Y1878474D02*
X2515842D01*
G01X2534937Y1878277D02*
X2534533D01*
G01X2534937Y1873592D02*
X2534533D01*
G01X2529622Y1873396D02*
X2515842D01*
G01X2534195Y1877313D02*
X2534012Y1877293D01*
G01X2534533Y1883592D02*
Y1878277D01*
G01X2533957Y1895443D02*
Y1893986D01*
G01Y1900443D02*
Y1898986D01*
G01Y1905443D02*
Y1903986D01*
G01Y1910443D02*
Y1908986D01*
G01Y1915443D02*
Y1913986D01*
G01Y1920443D02*
Y1918986D01*
G01Y1925443D02*
Y1923986D01*
G01Y1930443D02*
Y1928986D01*
G01Y1935443D02*
Y1933986D01*
G01Y1940443D02*
Y1938986D01*
G01X2532973Y1895443D02*
Y1893986D01*
G01Y1900443D02*
Y1898986D01*
G01Y1905443D02*
Y1903986D01*
G01Y1910443D02*
Y1908986D01*
G01Y1915443D02*
Y1913986D01*
G01Y1920443D02*
Y1918986D01*
G01Y1925443D02*
Y1923986D01*
G01Y1930443D02*
Y1928986D01*
G01Y1935443D02*
Y1933986D01*
G01Y1940443D02*
Y1938986D01*
G01X2532383Y1895443D02*
Y1893986D01*
G01Y1900443D02*
Y1898986D01*
G01Y1905443D02*
Y1903986D01*
G01Y1910443D02*
Y1908986D01*
G01Y1915443D02*
Y1913986D01*
G01Y1920443D02*
Y1918986D01*
G01Y1925443D02*
Y1923986D01*
G01Y1930443D02*
Y1928986D01*
G01Y1935443D02*
Y1933986D01*
G01Y1940443D02*
Y1938986D01*
G01X2531080Y1884577D02*
Y1877293D01*
G01X2530606Y1882411D02*
Y1879459D01*
G01Y1895443D02*
Y1893986D01*
G01Y1900443D02*
Y1898986D01*
G01Y1905443D02*
Y1903986D01*
G01Y1910443D02*
Y1908986D01*
G01Y1915443D02*
Y1913986D01*
G01Y1920443D02*
Y1918986D01*
G01Y1925443D02*
Y1923986D01*
G01Y1930443D02*
Y1928986D01*
G01Y1935443D02*
Y1933986D01*
G01Y1940443D02*
Y1938986D01*
G01X2530016Y1895443D02*
Y1893986D01*
G01Y1900443D02*
Y1898986D01*
G01Y1905443D02*
Y1903986D01*
G01Y1910443D02*
Y1908986D01*
G01Y1915443D02*
Y1913986D01*
G01Y1920443D02*
Y1918986D01*
G01Y1925443D02*
Y1923986D01*
G01Y1930443D02*
Y1928986D01*
G01Y1935443D02*
Y1933986D01*
G01Y1940443D02*
Y1938986D01*
G01X2529622Y1875010D02*
Y1873396D01*
G01Y1878474D02*
Y1876860D01*
G01Y1885010D02*
Y1883396D01*
G01X2529079Y1884577D02*
Y1877293D01*
G01X2528638Y1875010D02*
Y1873396D01*
G01Y1878474D02*
Y1876860D01*
G01Y1885010D02*
Y1883396D01*
G01X2528271Y1884577D02*
Y1877293D01*
G01X2527630Y1884577D02*
Y1877293D01*
G01X2527478Y1884577D02*
Y1877293D01*
G01X2515798Y1895443D02*
Y1893986D01*
G01Y1900443D02*
Y1898986D01*
G01Y1905443D02*
Y1903986D01*
G01Y1910443D02*
Y1908986D01*
G01Y1915443D02*
Y1913986D01*
G01Y1920443D02*
Y1918986D01*
G01Y1925443D02*
Y1923986D01*
G01Y1930443D02*
Y1928986D01*
G01Y1935443D02*
Y1933986D01*
G01Y1940443D02*
Y1938986D01*
G01X2515236Y1895443D02*
Y1893986D01*
G01Y1900443D02*
Y1898986D01*
G01Y1905443D02*
Y1903986D01*
G01Y1910443D02*
Y1908986D01*
G01Y1915443D02*
Y1913986D01*
G01Y1920443D02*
Y1918986D01*
G01Y1925443D02*
Y1923986D01*
G01Y1930443D02*
Y1928986D01*
G01Y1935443D02*
Y1933986D01*
G01Y1940443D02*
Y1938986D01*
G01X2514858Y1882411D02*
Y1879459D01*
G01X2534524Y1877458D02*
X2534666Y1877581D01*
G01X2534364Y1877367D02*
X2534527Y1877460D01*
G01X2534192Y1877312D02*
X2534367Y1877369D01*
G01X2534937Y1868277D02*
Y1873592D01*
G01X2534919Y1868083D02*
X2534937Y1868277D01*
G01X2534866Y1867899D02*
X2534919Y1868086D01*
G01X2534781Y1867730D02*
X2534867Y1867902D01*
G01X2534782Y1867733D02*
X2534666Y1867581D01*
G01X2534867Y1883967D02*
X2534781Y1884140D01*
G01X2534867Y1873967D02*
X2534781Y1874140D01*
G01X2534782Y1884137D02*
X2534666Y1884288D01*
G01X2534782Y1874137D02*
X2534666Y1874288D01*
G01X2539464Y1888356D02*
X2540449Y1887372D01*
G01X2537693Y1935246D02*
X2537152Y1935443D01*
G01X2537693Y1930246D02*
X2537152Y1930443D01*
G01X2537693Y1925246D02*
X2537152Y1925443D01*
G01X2537693Y1920246D02*
X2537152Y1920443D01*
G01X2537693Y1915246D02*
X2537152Y1915443D01*
G01X2537693Y1910246D02*
X2537152Y1910443D01*
G01X2537693Y1905246D02*
X2537152Y1905443D01*
G01X2537693Y1900246D02*
X2537152Y1900443D01*
G01X2537693Y1895246D02*
X2537152Y1895443D01*
G01X2534919Y1883784D02*
X2534866Y1883971D01*
G01X2534919Y1873784D02*
X2534866Y1873971D01*
G01X2539464Y1888356D02*
X2537102D01*
G01X2539872Y1876860D02*
Y1875010D01*
G01Y1893730D02*
Y1887949D01*
G01Y1898730D02*
Y1895699D01*
G01Y1903730D02*
Y1900699D01*
G01Y1908730D02*
Y1905699D01*
G01Y1913730D02*
Y1910699D01*
G01Y1918730D02*
Y1915699D01*
G01Y1923730D02*
Y1920699D01*
G01Y1928730D02*
Y1925699D01*
G01Y1933730D02*
Y1930699D01*
G01Y1938730D02*
Y1935699D01*
G01X2539464Y1928730D02*
Y1930699D01*
G01Y1895699D02*
Y1893730D01*
G01Y1900699D02*
Y1898730D01*
G01Y1905699D02*
Y1903730D01*
G01Y1910699D02*
Y1908730D01*
G01Y1915699D02*
Y1913730D01*
G01Y1920699D02*
Y1918730D01*
G01Y1925699D02*
Y1923730D01*
G01Y1935699D02*
Y1933730D01*
G01Y1940699D02*
Y1938730D01*
G01X2537890Y1876860D02*
Y1875010D01*
G01X2537693Y1895246D02*
Y1894183D01*
G01Y1900246D02*
Y1899183D01*
G01Y1905246D02*
Y1904183D01*
G01Y1910246D02*
Y1909183D01*
G01Y1915246D02*
Y1914183D01*
G01Y1920246D02*
Y1919183D01*
G01Y1925246D02*
Y1924183D01*
G01Y1930246D02*
Y1929183D01*
G01Y1935246D02*
Y1934183D01*
G01Y1940246D02*
Y1939183D01*
G01X2537102Y1888356D02*
Y1960423D01*
G01X2536315Y1918730D02*
Y1920699D01*
G01Y1908730D02*
Y1910699D01*
G01Y1898730D02*
Y1900699D01*
G01Y1895699D02*
Y1893730D01*
G01Y1905699D02*
Y1903730D01*
G01Y1915699D02*
Y1913730D01*
G01Y1925699D02*
Y1923730D01*
G01Y1930699D02*
Y1928730D01*
G01Y1935699D02*
Y1933730D01*
G01Y1940699D02*
Y1938730D01*
G01X2534937Y1883592D02*
Y1878277D01*
G01Y1895699D02*
Y1893730D01*
G01Y1900699D02*
Y1898730D01*
G01Y1905699D02*
Y1903730D01*
G01Y1910699D02*
Y1908730D01*
G01Y1915699D02*
Y1913730D01*
G01Y1920699D02*
Y1918730D01*
G01Y1925699D02*
Y1923730D01*
G01Y1930699D02*
Y1928730D01*
G01Y1935699D02*
Y1933730D01*
G01Y1940699D02*
Y1938730D01*
G01X2534919Y1883787D02*
X2534937Y1883592D01*
G01X2534919Y1873787D02*
X2534937Y1873592D01*
G01X2534919Y1878083D02*
X2534937Y1878277D01*
G01X2534866Y1877899D02*
X2534919Y1878086D01*
G01X2534781Y1877730D02*
X2534867Y1877902D01*
G01X2534782Y1877733D02*
X2534666Y1877581D01*
G01X2540449Y1885994D02*
X2539464Y1885010D01*
G01X2537693Y1894183D02*
X2537152Y1893986D01*
G01X2537693Y1899183D02*
X2537152Y1898986D01*
G01X2537693Y1904183D02*
X2537152Y1903986D01*
G01X2537693Y1909183D02*
X2537152Y1908986D01*
G01X2537693Y1914183D02*
X2537152Y1913986D01*
G01X2537693Y1919183D02*
X2537152Y1918986D01*
G01X2537693Y1924183D02*
X2537152Y1923986D01*
G01X2537693Y1929183D02*
X2537152Y1928986D01*
G01X2537693Y1934183D02*
X2537152Y1933986D01*
G01X2537693Y1939183D02*
X2537152Y1938986D01*
G01X2540449Y1959833D02*
X2532575D01*
G01X2533957Y1945443D02*
Y1943986D01*
G01Y1950443D02*
Y1948986D01*
G01X2532973Y1945443D02*
Y1943986D01*
G01Y1950443D02*
Y1948986D01*
G01X2532383Y1945443D02*
Y1943986D01*
G01Y1950443D02*
Y1948986D01*
G01X2530606Y1945443D02*
Y1943986D01*
G01Y1950443D02*
Y1948986D01*
G01X2530016Y1945443D02*
Y1943986D01*
G01Y1950443D02*
Y1948986D01*
G01X2515798Y1945443D02*
Y1943986D01*
G01Y1950443D02*
Y1948986D01*
G01X2515236Y1945443D02*
Y1943986D01*
G01Y1950443D02*
Y1948986D01*
G01X2526130Y1998745D02*
X2648545D01*
G01X2522980D02*
X2526130D01*
G01X2537693Y1940246D02*
X2537152Y1940443D01*
G01X2539872Y1943730D02*
Y1940699D01*
G01X2537693Y1950246D02*
X2537152Y1950443D01*
G01X2537693Y1945246D02*
X2537152Y1945443D01*
G01X2565341Y2005963D02*
X2566315D01*
G01X2545023Y2005241D02*
X2547946D01*
G01X2573623Y2000911D02*
X2573136D01*
Y2001632D01*
X2573623Y2000911D01*
G01X2539872Y1948730D02*
Y1945699D01*
G01Y1963193D02*
Y1950699D01*
G01X2539464Y1945699D02*
Y1943730D01*
G01Y1950699D02*
Y1948730D01*
G01X2537693Y1945246D02*
Y1944183D01*
G01Y1950246D02*
Y1949183D01*
G01X2536315Y1945699D02*
Y1943730D01*
G01Y1950699D02*
Y1948730D01*
G01X2534937Y1945699D02*
Y1943730D01*
G01Y1950699D02*
Y1948730D01*
G01X2581419Y2000911D02*
X2581906Y2004519D01*
X2582393Y2006685D01*
X2582880Y2008128D01*
X2583368Y2009572D01*
X2579470D01*
G01X2550382Y2005241D02*
X2551104Y2007407D01*
X2552547Y2008850D01*
X2554713Y2009572D01*
X2556878Y2008850D01*
X2558322Y2007407D01*
X2559043Y2005241D01*
X2558322Y2003076D01*
X2556878Y2001632D01*
X2554713Y2000911D01*
X2552547Y2001632D01*
X2551104Y2003076D01*
X2550382Y2005241D01*
G01X2551104Y1998745D02*
X2558322Y2011737D01*
G01X2568264Y2003076D02*
X2567290Y2001632D01*
X2566315Y2000911D01*
X2565341D01*
X2564367Y2001632D01*
X2563879Y2002354D01*
G01X2536740Y2008128D02*
X2537227Y2008850D01*
X2538202Y2009572D01*
X2539176D01*
X2540151Y2008850D01*
X2540638Y2008128D01*
Y2006685D01*
X2540151Y2005963D01*
G01X2540449Y1963770D02*
X2535724Y1959045D01*
G01X2564367Y2008850D02*
X2565341Y2009572D01*
X2566315D01*
X2567290Y2008850D01*
X2567777Y2008128D01*
Y2007407D01*
X2567290Y2006685D01*
X2566315Y2005963D01*
X2567290Y2005241D01*
X2567777Y2004519D01*
X2568264Y2003798D01*
Y2003076D01*
G01X2540151Y2005963D02*
X2538202Y2004519D01*
X2537227Y2003076D01*
X2536740Y2000911D01*
X2540638D01*
G01X2537693Y1944183D02*
X2537152Y1943986D01*
G01X2537693Y1949183D02*
X2537152Y1948986D01*
G01X2530827Y2208555D02*
X2531549Y2210720D01*
X2532993Y2212163D01*
X2535158Y2212885D01*
X2537323Y2212163D01*
X2538767Y2210720D01*
X2539489Y2208555D01*
X2538767Y2206389D01*
X2537323Y2204945D01*
X2535158Y2204224D01*
X2532993Y2204945D01*
X2531549Y2206389D01*
X2530827Y2208555D01*
G01X2531549Y2202058D02*
X2538767Y2215050D01*
G01X2522166Y2202058D02*
X2621195D01*
G01X2519016D02*
X2522166D01*
G01X2569659Y2204224D02*
X2568685Y2204945D01*
X2568198Y2205667D01*
X2567710Y2207111D01*
Y2209998D01*
X2568198Y2211442D01*
X2568685Y2212163D01*
X2569659Y2212885D01*
X2570634Y2212163D01*
X2571121Y2211442D01*
X2571608Y2209998D01*
Y2207111D01*
X2571121Y2205667D01*
X2570634Y2204945D01*
X2569659Y2204224D01*
G01X2561864D02*
X2560889Y2204945D01*
X2560402Y2205667D01*
X2559915Y2207111D01*
Y2209998D01*
X2560402Y2211442D01*
X2560889Y2212163D01*
X2561864Y2212885D01*
X2562838Y2212163D01*
X2563326Y2211442D01*
X2563813Y2209998D01*
Y2207111D01*
X2563326Y2205667D01*
X2562838Y2204945D01*
X2561864Y2204224D01*
G01X2555417Y2234951D02*
X2552493D01*
X2552006Y2231342D01*
X2552981Y2232063D01*
X2553955D01*
X2554929Y2231342D01*
X2555417Y2230620D01*
X2555904Y2229176D01*
X2555417Y2227733D01*
X2554929Y2227011D01*
X2553955Y2226289D01*
X2552981D01*
X2552006Y2227011D01*
X2551519Y2227733D01*
G01X2561263Y2226289D02*
X2560776D01*
Y2227011D01*
X2561263Y2226289D01*
G01X2582814Y2212885D02*
X2587686D01*
G01X2554069Y2204224D02*
X2553581D01*
Y2204945D01*
X2554069Y2204224D01*
G01X2585178Y2165541D02*
Y2174203D01*
X2581768Y2167707D01*
X2586153D01*
G01X2579290Y2229176D02*
Y2228455D01*
X2578803Y2227733D01*
X2578315Y2227011D01*
X2577341Y2226289D01*
X2576366D01*
X2575392Y2227011D01*
X2574905Y2227733D01*
G01X2570520Y2226289D02*
Y2234951D01*
X2567110Y2228455D01*
X2571494D01*
G01X2547735Y2204224D02*
Y2212885D01*
X2544325Y2206389D01*
X2548709D01*
G01X2539339Y2226289D02*
Y2234951D01*
X2535929Y2228455D01*
X2540313D01*
G01X2547621Y2232063D02*
X2547134Y2230620D01*
X2545673Y2229898D01*
X2544211Y2230620D01*
X2543724Y2232063D01*
X2544211Y2233507D01*
X2544698Y2234229D01*
X2545673Y2234951D01*
X2546647Y2234229D01*
X2547134Y2233507D01*
X2547621Y2232063D01*
Y2229176D01*
X2547134Y2227733D01*
X2546647Y2227011D01*
X2545673Y2226289D01*
X2544698Y2227011D01*
X2544211Y2227733D01*
G01X2577942Y2212885D02*
X2576967Y2211442D01*
X2576480Y2209276D01*
Y2207833D01*
X2576967Y2205667D01*
X2577942Y2204224D01*
G01X2575392Y2234229D02*
X2576366Y2234951D01*
X2577341D01*
X2578315Y2234229D01*
X2578803Y2233507D01*
Y2232785D01*
X2578315Y2232063D01*
X2577341Y2231342D01*
X2578315Y2230620D01*
X2579290Y2229176D01*
G01X2532281Y2262292D02*
X2639105D01*
G01X2529131D02*
X2532281D01*
G01X2576366Y2231342D02*
X2577341D01*
G01X2579287Y2269510D02*
X2578312Y2270231D01*
X2577825Y2270953D01*
Y2271675D01*
X2578312Y2272397D01*
X2579287Y2273119D01*
X2580261D01*
X2581236Y2272397D01*
X2581723Y2271675D01*
Y2270953D01*
X2581236Y2270231D01*
X2580261Y2269510D01*
G01X2579287Y2264457D02*
X2578312Y2265179D01*
X2577825Y2265901D01*
X2577338Y2266622D01*
Y2267344D01*
X2578312Y2268788D01*
G01X2564184Y2264457D02*
X2563696D01*
Y2265179D01*
X2564184Y2264457D01*
G01X2571979Y2273119D02*
Y2264457D01*
G01X2540942Y2268788D02*
X2541664Y2270953D01*
X2543107Y2272397D01*
X2545273Y2273119D01*
X2547438Y2272397D01*
X2548882Y2270953D01*
X2549603Y2268788D01*
X2548882Y2266622D01*
X2547438Y2265179D01*
X2545273Y2264457D01*
X2543107Y2265179D01*
X2541664Y2266622D01*
X2540942Y2268788D01*
G01X2541664Y2262292D02*
X2548882Y2275284D01*
G01X2554439Y2271675D02*
X2554927Y2272397D01*
X2555901Y2273119D01*
X2556875D01*
X2557850Y2272397D01*
X2558337Y2271675D01*
Y2270231D01*
X2557850Y2269510D01*
G01X2581236Y2265179D02*
X2580261Y2264457D01*
X2579287D01*
G01X2578312Y2268788D02*
X2579287Y2269510D01*
X2580261D01*
X2581236Y2268788D01*
X2581723Y2268066D01*
X2582210Y2267344D01*
Y2266622D01*
X2581236Y2265179D01*
G01X2557850Y2269510D02*
X2555901Y2268066D01*
X2554927Y2266622D01*
X2554439Y2264457D01*
X2558337D01*
G01X2592676Y-172119D02*
Y-191056D01*
G01X2650630Y-104550D02*
X2649656Y-105994D01*
X2649169Y-108159D01*
X2653066D01*
G01X2649169Y-100941D02*
X2649656Y-100220D01*
X2650630Y-99498D01*
X2651604D01*
X2652579Y-100220D01*
X2653066Y-100941D01*
Y-102385D01*
X2652579Y-103107D01*
X2650630Y-104550D01*
G01X2606294Y-106716D02*
X2605807Y-107438D01*
X2604833Y-108159D01*
X2603859D01*
X2602884Y-107438D01*
X2601910Y-105994D01*
G01Y-101663D02*
X2602884Y-100220D01*
X2603859Y-99498D01*
X2604833D01*
X2605807Y-100220D01*
X2606294Y-100941D01*
G01X2609705Y-108159D02*
X2612141Y-99498D01*
X2614577Y-108159D01*
G01X2617987Y-99498D02*
Y-108159D01*
X2621885D01*
G01X2601910Y-105994D02*
X2601422Y-103829D01*
X2601910Y-101663D01*
G01X2598499Y-100941D02*
X2598012Y-100220D01*
X2597038Y-99498D01*
X2596063D01*
X2595089Y-100220D01*
X2594602Y-100941D01*
Y-101663D01*
X2595089Y-102385D01*
G01Y-107438D02*
X2594115Y-105994D01*
G01X2595089Y-102385D02*
X2598012Y-104550D01*
X2598499Y-105272D01*
Y-106716D01*
X2598012Y-107438D01*
X2597038Y-108159D01*
X2596063D01*
X2595089Y-107438D01*
G01X2625783Y-103829D02*
X2628219D01*
G01X2610680Y-105272D02*
X2613602D01*
G01X2629680Y-108159D02*
X2625783D01*
Y-99498D01*
X2629680D01*
G01X2621885Y-93002D02*
X2620911Y-94446D01*
X2619936Y-95167D01*
X2617987D01*
Y-86506D01*
G01X2640886Y-95167D02*
X2643322Y-86506D01*
X2645758Y-95167D01*
G01X2656964Y-86506D02*
Y-95167D01*
X2660861D01*
G01X2651117Y-86506D02*
Y-95167D01*
G01X2635527Y-86506D02*
Y-95167D01*
G01X2629428Y20187D02*
Y-48199D01*
G01X2638694Y-47042D02*
X2629428Y-48199D01*
G01X2661710Y-52598D02*
X2638694Y-47042D01*
G01X2620911Y-87228D02*
X2621885Y-88671D01*
X2622372Y-90837D01*
X2621885Y-93002D01*
G01X2633091Y-86506D02*
X2637963D01*
G01X2617987D02*
X2619936D01*
X2620911Y-87228D01*
G01X2625783Y-90837D02*
X2628219D01*
G01X2641861Y-92280D02*
X2644783D01*
G01X2629680Y-95167D02*
X2625783D01*
Y-86506D01*
X2629680D01*
G01X2586259Y-22981D02*
G03X2602019Y-34657I47104J47106D01*
G01X2664073Y41447D02*
X2633365D01*
G01Y24124D02*
X2664073D01*
G01X2629428Y20187D02*
X2633365Y24124D01*
G01Y41447D02*
X2629428Y45384D01*
G01Y155021D02*
Y45384D01*
G01X2664073Y99195D02*
X2646750D01*
G01X2629428D02*
X2646750D01*
G01X2629428Y49321D02*
Y103132D01*
G01Y155021D02*
X2643029Y156186D01*
G01D02*
X2667548Y158829D01*
G01X2597358Y312798D02*
X2597845Y314242D01*
X2599307Y314964D01*
X2600769Y314242D01*
X2601256Y312798D01*
X2600769Y311355D01*
X2600281Y310633D01*
X2599307Y309911D01*
X2598333Y310633D01*
X2597845Y311355D01*
X2597358Y312798D01*
Y315686D01*
X2597845Y317129D01*
X2598333Y317851D01*
X2599307Y318573D01*
X2600281Y317851D01*
X2600769Y317129D01*
G01X2607102Y309911D02*
X2607589Y313520D01*
X2608077Y315686D01*
X2608564Y317129D01*
X2609051Y318573D01*
X2605153D01*
G01X2591512Y309911D02*
X2591024D01*
Y310633D01*
X2591512Y309911D01*
G01X2587853Y362682D02*
X2586879Y361239D01*
X2586392Y359073D01*
Y357630D01*
X2586879Y355464D01*
X2587853Y354021D01*
G01X2601008D02*
Y362682D01*
X2603444D01*
X2604418Y361960D01*
X2604906Y361239D01*
Y359795D01*
X2604418Y359073D01*
X2603444Y358352D01*
X2601008D01*
G01X2593213Y354021D02*
Y362682D01*
X2597110Y354021D01*
Y362682D01*
G01X2620496D02*
Y354021D01*
G01X2616599Y362682D02*
Y354021D01*
G01X2610752Y362682D02*
Y354021D01*
G01X2625855Y362682D02*
X2626830Y361239D01*
X2627317Y359073D01*
Y357630D01*
X2626830Y355464D01*
X2625855Y354021D01*
G01X2608316Y362682D02*
X2613188D01*
G01X2616599Y358352D02*
X2620496D01*
G01X2608564Y441066D02*
X2607589Y440344D01*
X2606615D01*
G01X2590050Y429715D02*
X2591024Y430436D01*
X2591999D01*
X2592973Y429715D01*
X2593461Y428993D01*
X2593948Y428271D01*
Y427549D01*
X2593461Y426827D01*
X2592973Y426106D01*
X2591999Y425384D01*
X2591024D01*
G01X2604666Y442510D02*
Y443232D01*
X2605153Y443953D01*
X2605641Y444675D01*
X2606615Y445397D01*
X2607589D01*
X2608564Y444675D01*
X2609051Y443953D01*
X2609538Y443232D01*
Y442510D01*
X2608564Y441066D01*
G01X2591512Y449006D02*
Y440344D01*
G01X2589076Y427549D02*
Y428271D01*
X2590050Y429715D01*
G01X2606615Y445397D02*
X2605641Y446119D01*
X2605153Y446841D01*
Y447562D01*
X2605641Y448284D01*
X2606615Y449006D01*
X2607589D01*
X2608564Y448284D01*
X2609051Y447562D01*
Y446841D01*
X2608564Y446119D01*
X2607589Y445397D01*
G01X2606615Y440344D02*
X2605641Y441066D01*
X2604666Y442510D01*
G01X2607102Y425384D02*
X2606128Y426106D01*
X2605641Y426827D01*
X2605153Y428271D01*
Y431158D01*
X2605641Y432602D01*
X2606128Y433323D01*
X2607102Y434045D01*
X2608077Y433323D01*
X2608564Y432602D01*
X2609051Y431158D01*
Y428271D01*
X2608564Y426827D01*
X2608077Y426106D01*
X2607102Y425384D01*
G01X2591024Y430436D02*
X2590050Y431158D01*
X2589563Y431880D01*
Y432602D01*
X2590050Y433323D01*
X2591024Y434045D01*
X2591999D01*
X2592973Y433323D01*
X2593461Y432602D01*
Y431880D01*
X2592973Y431158D01*
X2591999Y430436D01*
G01X2591024Y425384D02*
X2590050Y426106D01*
X2589076Y427549D01*
G01X2599307Y440344D02*
X2598820D01*
Y441066D01*
X2599307Y440344D01*
G01Y425384D02*
X2598820D01*
Y426106D01*
X2599307Y425384D01*
G01X2614898Y440344D02*
X2613923Y441066D01*
X2613436Y441788D01*
X2612949Y443232D01*
Y446119D01*
X2613436Y447562D01*
X2613923Y448284D01*
X2614898Y449006D01*
X2615872Y448284D01*
X2616359Y447562D01*
X2616846Y446119D01*
Y443232D01*
X2616359Y441788D01*
X2615872Y441066D01*
X2614898Y440344D01*
G01Y425384D02*
X2613923Y426106D01*
X2613436Y426827D01*
X2612949Y428271D01*
Y431158D01*
X2613436Y432602D01*
X2613923Y433323D01*
X2614898Y434045D01*
X2615872Y433323D01*
X2616359Y432602D01*
X2616846Y431158D01*
Y428271D01*
X2616359Y426827D01*
X2615872Y426106D01*
X2614898Y425384D01*
G01X2591512Y540226D02*
X2591999Y543835D01*
X2592486Y546001D01*
X2592973Y547444D01*
X2593461Y548888D01*
X2589563D01*
G01X2607102D02*
Y540226D01*
G01X2599307D02*
X2598820D01*
Y540948D01*
X2599307Y540226D01*
G01X2614898D02*
X2615385Y543835D01*
X2615872Y546001D01*
X2616359Y547444D01*
X2616846Y548888D01*
X2612949D01*
G01X2591512Y949006D02*
X2591999Y952615D01*
X2592486Y954780D01*
X2592973Y956224D01*
X2593461Y957667D01*
X2589563D01*
G01X2599307D02*
Y949006D01*
G01X2607102D02*
X2606615D01*
Y949728D01*
X2607102Y949006D01*
G01X2622693D02*
X2621718Y949728D01*
X2621231Y950449D01*
X2620744Y951893D01*
Y954780D01*
X2621231Y956224D01*
X2621718Y956945D01*
X2622693Y957667D01*
X2623667Y956945D01*
X2624154Y956224D01*
X2624642Y954780D01*
Y951893D01*
X2624154Y950449D01*
X2623667Y949728D01*
X2622693Y949006D01*
G01X2614898D02*
X2613923Y949728D01*
X2613436Y950449D01*
X2612949Y951893D01*
Y954780D01*
X2613436Y956224D01*
X2613923Y956945D01*
X2614898Y957667D01*
X2615872Y956945D01*
X2616359Y956224D01*
X2616846Y954780D01*
Y951893D01*
X2616359Y950449D01*
X2615872Y949728D01*
X2614898Y949006D01*
G01X2599307Y1353337D02*
Y1344675D01*
G01X2591512D02*
X2591999Y1348284D01*
X2592486Y1350449D01*
X2592973Y1351893D01*
X2593461Y1353337D01*
X2589563D01*
G01X2607102Y1344675D02*
X2606615D01*
Y1345397D01*
X2607102Y1344675D01*
G01X2622693D02*
X2621718Y1345397D01*
X2621231Y1346119D01*
X2620744Y1347562D01*
Y1350449D01*
X2621231Y1351893D01*
X2621718Y1352615D01*
X2622693Y1353337D01*
X2623667Y1352615D01*
X2624154Y1351893D01*
X2624642Y1350449D01*
Y1347562D01*
X2624154Y1346119D01*
X2623667Y1345397D01*
X2622693Y1344675D01*
G01X2616846Y1353337D02*
X2613923D01*
X2613436Y1349728D01*
X2614410Y1350449D01*
X2615385D01*
X2616359Y1349728D01*
X2616846Y1349006D01*
X2617334Y1347562D01*
X2616846Y1346119D01*
X2616359Y1345397D01*
X2615385Y1344675D01*
X2614410D01*
X2613436Y1345397D01*
X2612949Y1346119D01*
G01X2589214Y2000911D02*
X2588240Y2001632D01*
X2587752Y2002354D01*
X2587265Y2003798D01*
Y2006685D01*
X2587752Y2008128D01*
X2588240Y2008850D01*
X2589214Y2009572D01*
X2590188Y2008850D01*
X2590676Y2008128D01*
X2591163Y2006685D01*
Y2003798D01*
X2590676Y2002354D01*
X2590188Y2001632D01*
X2589214Y2000911D01*
G01X2602856D02*
Y2009572D01*
X2606753Y2000911D01*
Y2009572D01*
G01X2597497D02*
X2596522Y2008128D01*
X2596035Y2005963D01*
Y2004519D01*
X2596522Y2002354D01*
X2597497Y2000911D01*
G01X2635499Y2009572D02*
X2636473Y2008128D01*
X2636960Y2005963D01*
Y2004519D01*
X2636473Y2002354D01*
X2635499Y2000911D01*
G01X2610164Y2009572D02*
X2615036D01*
G01X2626242Y2005241D02*
X2630139D01*
G01Y2009572D02*
Y2000911D01*
G01X2626242Y2009572D02*
Y2000911D01*
G01X2618446D02*
Y2009572D01*
X2620882D01*
X2621857Y2008850D01*
X2622344Y2008128D01*
Y2006685D01*
X2621857Y2005963D01*
X2620882Y2005241D01*
X2618446D01*
G01X2612600Y2009572D02*
Y2000911D01*
G01X2599307Y2165541D02*
X2598333Y2166263D01*
X2597845Y2166985D01*
X2597358Y2168428D01*
Y2171315D01*
X2597845Y2172759D01*
X2598333Y2173481D01*
X2599307Y2174203D01*
X2600281Y2173481D01*
X2600769Y2172759D01*
X2601256Y2171315D01*
Y2168428D01*
X2600769Y2166985D01*
X2600281Y2166263D01*
X2599307Y2165541D01*
G01X2591024Y2170594D02*
X2590050Y2171315D01*
X2589563Y2172037D01*
Y2172759D01*
X2590050Y2173481D01*
X2591024Y2174203D01*
X2591999D01*
X2592973Y2173481D01*
X2593461Y2172759D01*
Y2172037D01*
X2592973Y2171315D01*
X2591999Y2170594D01*
G01X2591024Y2165541D02*
X2590050Y2166263D01*
X2589076Y2167707D01*
G01X2598891Y2208555D02*
X2602789D01*
G01X2607102Y2165541D02*
X2606615D01*
Y2166263D01*
X2607102Y2165541D01*
G01X2602789Y2212885D02*
Y2204224D01*
G01X2598891Y2212885D02*
Y2204224D01*
G01X2593948Y2168428D02*
Y2167707D01*
X2593461Y2166985D01*
X2592973Y2166263D01*
X2591999Y2165541D01*
X2591024D01*
G01X2591096Y2204224D02*
Y2212885D01*
X2593532D01*
X2594507Y2212163D01*
X2594994Y2211442D01*
Y2209998D01*
X2594507Y2209276D01*
X2593532Y2208555D01*
X2591096D01*
G01X2589076Y2167707D02*
Y2168428D01*
X2590050Y2169872D01*
G01X2585250Y2212885D02*
Y2204224D01*
G01X2590050Y2169872D02*
X2591024Y2170594D01*
X2591999D01*
X2592973Y2169872D01*
X2593948Y2168428D01*
G01X2608148Y2212885D02*
X2609123Y2211442D01*
X2609610Y2209276D01*
Y2207833D01*
X2609123Y2205667D01*
X2608148Y2204224D01*
G01X2622693Y2165541D02*
X2621718Y2166263D01*
X2621231Y2166985D01*
X2620744Y2168428D01*
Y2171315D01*
X2621231Y2172759D01*
X2621718Y2173481D01*
X2622693Y2174203D01*
X2623667Y2173481D01*
X2624154Y2172759D01*
X2624642Y2171315D01*
Y2168428D01*
X2624154Y2166985D01*
X2623667Y2166263D01*
X2622693Y2165541D01*
G01X2614898D02*
X2613923Y2166263D01*
X2613436Y2166985D01*
X2612949Y2168428D01*
Y2171315D01*
X2613436Y2172759D01*
X2613923Y2173481D01*
X2614898Y2174203D01*
X2615872Y2173481D01*
X2616359Y2172759D01*
X2616846Y2171315D01*
Y2168428D01*
X2616359Y2166985D01*
X2615872Y2166263D01*
X2614898Y2165541D01*
G01X2601211Y2264457D02*
Y2273119D01*
X2603647D01*
X2604621Y2272397D01*
X2605109Y2271675D01*
Y2270231D01*
X2604621Y2269510D01*
X2603647Y2268788D01*
X2601211D01*
G01X2593416Y2264457D02*
Y2273119D01*
X2597313Y2264457D01*
Y2273119D01*
G01X2588056D02*
X2587082Y2271675D01*
X2586595Y2269510D01*
Y2268066D01*
X2587082Y2265901D01*
X2588056Y2264457D01*
G01X2626058Y2273119D02*
X2627033Y2271675D01*
X2627520Y2269510D01*
Y2268066D01*
X2627033Y2265901D01*
X2626058Y2264457D01*
G01X2608519Y2273119D02*
X2613391D01*
G01X2616802Y2268788D02*
X2620699D01*
G01Y2273119D02*
Y2264457D01*
G01X2616802Y2273119D02*
Y2264457D01*
G01X2610955Y2273119D02*
Y2264457D01*
G01X2592676Y2437400D02*
Y2418463D01*
G01X2682298Y-108159D02*
X2681324Y-107438D01*
X2680837Y-106716D01*
X2680350Y-105272D01*
Y-102385D01*
X2680837Y-100941D01*
X2681324Y-100220D01*
X2682298Y-99498D01*
X2683273Y-100220D01*
X2683760Y-100941D01*
X2684247Y-102385D01*
Y-105272D01*
X2683760Y-106716D01*
X2683273Y-107438D01*
X2682298Y-108159D01*
G01X2674503D02*
X2673529Y-107438D01*
X2673042Y-106716D01*
X2672554Y-105272D01*
Y-102385D01*
X2673042Y-100941D01*
X2673529Y-100220D01*
X2674503Y-99498D01*
X2675478Y-100220D01*
X2675965Y-100941D01*
X2676452Y-102385D01*
Y-105272D01*
X2675965Y-106716D01*
X2675478Y-107438D01*
X2674503Y-108159D01*
G01X2666708D02*
X2665733Y-107438D01*
X2665246Y-106716D01*
X2664759Y-105272D01*
Y-102385D01*
X2665246Y-100941D01*
X2665733Y-100220D01*
X2666708Y-99498D01*
X2667682Y-100220D01*
X2668169Y-100941D01*
X2668657Y-102385D01*
Y-105272D01*
X2668169Y-106716D01*
X2667682Y-107438D01*
X2666708Y-108159D01*
G01X2658913D02*
X2658426D01*
Y-107438D01*
X2658913Y-108159D01*
G01X2705664Y-49302D02*
X2691927Y-55420D01*
G01X2718406Y-43124D02*
X2705664Y-49302D01*
G01X2730041Y-36808D02*
X2718406Y-43124D01*
G01X2740828Y-29522D02*
X2730041Y-36808D01*
G01X2679863Y-95167D02*
X2682298Y-86506D01*
X2684735Y-95167D01*
G01X2664629Y-54843D02*
X2663175Y-53711D01*
G01D02*
X2661710Y-52598D01*
G01X2666105Y-55895D02*
X2664629Y-54843D01*
G01X2678266Y-58770D02*
X2666105Y-55895D01*
G01X2691927Y-55420D02*
X2678266Y-58770D01*
G01X2680837Y-92280D02*
X2683760D01*
G01X2664073Y24124D02*
G03Y41447I0J8662D01*
G01Y36722D02*
Y103132D01*
G01X2725409Y151589D02*
X2735737Y145259D01*
G01X2714455Y156186D02*
X2725409Y151589D01*
G01X2691535Y159907D02*
X2714455Y156186D01*
G01X2667548Y158829D02*
X2691535Y159907D01*
G01X2718675Y1848754D02*
X2717953Y1849241D01*
X2717232Y1850215D01*
Y1851190D01*
X2717953Y1852164D01*
X2718675Y1852651D01*
X2720119D01*
X2720840Y1852164D01*
G01X2718675Y1864344D02*
X2717953Y1864831D01*
X2717232Y1865806D01*
Y1866780D01*
X2717953Y1867754D01*
X2718675Y1868242D01*
X2720119D01*
X2720840Y1867754D01*
G01D02*
X2722284Y1865806D01*
X2723727Y1864831D01*
X2725893Y1864344D01*
Y1868242D01*
G01X2720840Y1852164D02*
X2722284Y1850215D01*
X2723727Y1849241D01*
X2725893Y1848754D01*
Y1852651D01*
G01Y1858498D02*
Y1858011D01*
X2725171D01*
X2725893Y1858498D01*
G01X2728058Y1846805D02*
Y1903572D01*
G01Y1899242D02*
Y1846805D01*
G01X2725893Y1874088D02*
X2725171Y1873114D01*
X2724449Y1872627D01*
X2723006Y1872139D01*
X2720119D01*
X2718675Y1872627D01*
X2717953Y1873114D01*
X2717232Y1874088D01*
X2717953Y1875063D01*
X2718675Y1875550D01*
X2720119Y1876037D01*
X2723006D01*
X2724449Y1875550D01*
X2725171Y1875063D01*
X2725893Y1874088D01*
G01X2728058Y1927588D02*
Y1903572D01*
G01Y1907903D02*
Y1927588D01*
G01X2748752Y1899242D02*
X2724121D01*
G01X2748752Y1907903D02*
X2724121D01*
G01X2751122Y-20374D02*
X2740828Y-29522D01*
G01X2760133Y-9646D02*
X2751122Y-20374D01*
G01X2767201Y2345D02*
X2760133Y-9646D01*
G01X2771530Y13981D02*
X2767201Y2345D01*
G01X2774280Y26148D02*
X2771530Y13981D01*
G01X2775992Y38607D02*
X2774280Y26148D01*
G01X2777233Y54491D02*
X2775992Y38607D01*
G01X2758580Y122274D02*
X2768610Y104791D01*
G01X2774893Y85859D02*
X2777070Y70296D01*
G01X2768610Y104791D02*
X2774893Y85859D01*
G01X2777070Y70296D02*
X2777233Y54491D01*
G01X2745224Y137506D02*
X2758580Y122274D01*
G01X2735737Y145259D02*
X2745224Y137506D01*
G01X2750720Y252619D02*
G03X2754657Y248682I3937J0D01*
G01X2750720D02*
Y249817D01*
G01Y983887D02*
Y252619D01*
G01Y248682D02*
X2751854D01*
G01X2871980D02*
X2754657D01*
G01X2795208Y530179D02*
G03I-984J0D01*
G01X2790088D02*
G03X2778281I-5903J0D01*
G01X2790090D02*
G03X2778279I-5906J0D01*
G01X2792059D02*
G03X2776311I-7874J0D01*
G01X2797964D02*
G03X2770405I-13779J0D01*
G01X2799933D02*
G03X2768437I-15748J0D01*
G01X2799933D02*
G03X2768437I-15748J0D01*
G01X2799933D02*
G03X2768437I-15748J0D01*
G01X2790088Y526045D02*
G03X2791213Y523289I3937J-1D01*
G01X2777156D02*
G03X2791213I7029J-6890D01*
G01X2768437Y516399D02*
G03X2799933I15748J0D01*
G01X2768437D02*
G03X2799933I15748J0D01*
G01X2768437D02*
G03X2799933I15748J0D01*
G01X2775129Y530179D02*
G03I-984J0D01*
G01X2777156Y523289D02*
G03X2778281Y526045I-2812J2755D01*
G01X2799933Y516399D02*
Y530179D01*
G01Y516399D02*
Y530179D01*
G01Y516399D02*
Y530179D01*
G01X2797964Y527816D02*
Y530179D01*
G01X2792059Y527816D02*
Y530179D01*
G01X2790090D02*
Y527816D01*
G01X2790088Y526045D02*
Y530179D01*
G01X2778281D02*
Y526045D01*
G01X2778279Y527816D02*
Y530179D01*
G01X2776311D02*
Y527816D01*
G01X2770405Y530179D02*
Y527816D01*
G01X2768437Y516399D02*
Y530179D01*
G01Y516399D02*
Y530179D01*
G01Y516399D02*
Y530179D01*
G01X2790090Y527816D02*
X2797964D01*
G01X2770405D02*
X2778279D01*
G01X2793863Y535198D02*
G03I-984J0D01*
G01X2790189Y538873D02*
G03I-985J0D01*
G01X2780149D02*
G03I-984J0D01*
G01X2776474Y535198D02*
G03I-984J0D01*
G01X2766862Y820108D02*
G03I-4331J0D01*
G01X2768043Y985856D02*
G03Y994517I0J4331D01*
G01X2750720Y983887D02*
X2752689Y985856D01*
G01D02*
X2768043D01*
G01Y994517D02*
X2752689D01*
G01X2750720Y1479950D02*
Y996486D01*
G01X2752689Y994517D02*
X2750720Y996486D01*
G01X2766862Y1198060D02*
G03I-4331J0D01*
G01X2791173Y1278210D02*
G03I-6988J0D01*
G01X2799933D02*
G03I-15748J0D01*
G01X2766862Y1316171D02*
G03I-4331J0D01*
G01X2750720Y1479950D02*
X2752689Y1481919D01*
G01X2768043D02*
G03Y1490580I0J4331D01*
G01D02*
X2752689D01*
G01Y1481919D02*
X2768043D01*
G01X2752689Y1490580D02*
X2750720Y1492549D01*
G01Y1897273D02*
Y1492549D01*
G01X2766862Y1694123D02*
G03I-4331J0D01*
G01Y1733493D02*
G03I-4331J0D01*
G01X2731035Y1931215D02*
X2761547D01*
G01X2750720D02*
X2731035D01*
G01X2768043Y1899242D02*
G03Y1907903I0J4331D01*
G01D02*
X2752689D01*
G01Y1899242D02*
X2768043D01*
G01X2752689Y1907903D02*
X2750720Y1909871D01*
G01Y2236871D02*
Y1909871D01*
G01Y1897273D02*
X2752689Y1899242D01*
G01X2772374Y1907509D02*
Y1935152D01*
G01X2802722Y1942042D02*
X2799798D01*
X2799311Y1938432D01*
X2800286Y1939154D01*
X2801260D01*
X2802235Y1938432D01*
X2802722Y1937711D01*
X2803209Y1936267D01*
X2802722Y1934824D01*
X2802235Y1934102D01*
X2801260Y1933380D01*
X2800286D01*
X2799311Y1934102D01*
X2798824Y1934824D01*
G01X2828056Y1931215D02*
X2761547D01*
G01X2772374D02*
X2828056D01*
G01X2766862Y2111446D02*
G03I-4331J0D01*
G01X2765343Y2164626D02*
G03X2779404I7031J-6888D01*
G01X2756626Y2157738D02*
G03X2788122I15748J0D01*
G01X2756626D02*
G03X2788122I15748J0D01*
G01X2756626D02*
G03X2788122I15748J0D01*
G01X2782052Y2176537D02*
G03I-984J0D01*
G01X2778378Y2180211D02*
G03I-985J0D01*
G01X2780523Y2199194D02*
G03I-4291J0D01*
G01X2783397Y2171517D02*
G03I-984J0D01*
G01X2778279Y2167381D02*
G03X2779404Y2164626I3937J0D01*
G01X2778279Y2171517D02*
G03X2766468I-5906J0D01*
G01X2778279D02*
G03X2766468I-5906J0D01*
G01X2778673D02*
G03I-6299J0D01*
G01X2780248D02*
G03X2764500I-7874J0D01*
G01X2786153D02*
G03X2758594I-13779J0D01*
G01X2788122D02*
G03X2756626I-15748J0D01*
G01X2788122D02*
G03X2756626I-15748J0D01*
G01X2788122D02*
G03X2756626I-15748J0D01*
G01X2768338Y2180211D02*
G03I-984J0D01*
G01X2764663Y2176537D02*
G03I-984J0D01*
G01X2763318Y2171517D02*
G03I-984J0D01*
G01X2765343Y2164626D02*
G03X2766468Y2167381I-2812J2755D01*
G01X2778279Y2169155D02*
X2786153D01*
G01X2758594D02*
X2766468D01*
G01X2788122Y2157738D02*
Y2171517D01*
G01Y2157738D02*
Y2171517D01*
G01Y2157738D02*
Y2171517D01*
G01X2786153Y2169155D02*
Y2171517D01*
G01X2780248Y2169155D02*
Y2171517D01*
G01X2778279Y2167381D02*
Y2171517D01*
G01D02*
Y2169155D01*
G01X2766468D02*
Y2171517D01*
G01D02*
Y2167381D01*
G01X2764500Y2171517D02*
Y2169155D01*
G01X2758594Y2171517D02*
Y2169155D01*
G01X2756626Y2157738D02*
Y2171517D01*
G01Y2157738D02*
Y2171517D01*
G01Y2157738D02*
Y2171517D01*
G01X2754657Y2240808D02*
G03X2750720Y2236871I0J-3937D01*
G01X2754657Y2240808D02*
X3784185D01*
G01X2812345Y-172119D02*
Y-191056D01*
G01X2868830Y252619D02*
G03X2900326I15748J0D01*
G01X2875523Y266399D02*
G03I-984J0D01*
G01X2825720Y264155D02*
G03Y267305I0J1575D01*
G01X2821389D02*
G03Y264155I0J-1575D01*
G01X2878030Y260571D02*
X2871980Y248682D01*
G01X2870799Y266399D02*
Y264037D01*
G01X2868830Y248682D02*
Y266399D01*
G01Y252619D02*
Y266399D01*
G01X2825720Y264155D02*
X2821389D01*
G01X2870799Y264037D02*
X2878673D01*
G01X2900326Y248682D02*
X2868830D01*
G01X2898358Y266399D02*
G03X2870799I-13780J0D01*
G01X2900326D02*
G03X2868830I-15748J0D01*
G01X2900326D02*
G03X2868830I-15748J0D01*
G01X2876868Y271419D02*
G03I-984J0D01*
G01X2836311Y277541D02*
G03I-3504J0D01*
G01X2821389Y267305D02*
X2825720D01*
G01Y437383D02*
G03Y440533I0J1575D01*
G01X2836311Y427147D02*
G03I-3504J0D01*
G01X2821389Y440533D02*
G03Y437383I0J-1575D01*
G01Y440533D02*
X2825720D01*
G01Y437383D02*
X2821389D01*
G01X2825720Y669667D02*
G03Y672816I0J1574D01*
G01X2821389D02*
G03Y669667I0J-1574D01*
G01Y672816D02*
X2825720D01*
G01Y669667D02*
X2821389D01*
G01X2836311Y683053D02*
G03I-3504J0D01*
G01X2825720Y842895D02*
G03Y846045I0J1575D01*
G01X2821389D02*
G03Y842895I0J-1575D01*
G01X2836311Y832659D02*
G03I-3504J0D01*
G01X2821389Y846045D02*
X2825720D01*
G01Y842895D02*
X2821389D01*
G01X2825720Y1075179D02*
G03Y1078328I0J1574D01*
G01X2821389D02*
G03Y1075179I0J-1575D01*
G01X2836311Y1088564D02*
G03I-3504J0D01*
G01X2821389Y1078328D02*
X2825720D01*
G01Y1075179D02*
X2821389D01*
G01X2825720Y1248407D02*
G03Y1251556I0J1575D01*
G01X2821389D02*
G03Y1248407I0J-1574D01*
G01X2836311Y1238171D02*
G03I-3504J0D01*
G01X2821389Y1251556D02*
X2825720D01*
G01Y1248407D02*
X2821389D01*
G01X2836311Y1494076D02*
G03I-3504J0D01*
G01X2825720Y1480690D02*
G03Y1483840I0J1575D01*
G01X2821389D02*
G03Y1480690I0J-1575D01*
G01Y1483840D02*
X2825720D01*
G01Y1480690D02*
X2821389D01*
G01X2836311Y1643682D02*
G03I-3504J0D01*
G01X2825720Y1653919D02*
G03Y1657068I0J1575D01*
G01X2821389D02*
G03Y1653919I0J-1574D01*
G01Y1657068D02*
X2825720D01*
G01Y1653919D02*
X2821389D01*
G01X2825720Y1886202D02*
G03Y1889352I0J1575D01*
G01X2821389D02*
G03Y1886202I0J-1575D01*
G01X2836311Y1899588D02*
G03I-3504J0D01*
G01X2821389Y1889352D02*
X2825720D01*
G01Y1886202D02*
X2821389D01*
G01X2818312Y1942042D02*
X2815389D01*
X2814902Y1938432D01*
X2815876Y1939154D01*
X2816851D01*
X2817825Y1938432D01*
X2818312Y1937711D01*
X2818799Y1936267D01*
X2818312Y1934824D01*
X2817825Y1934102D01*
X2816851Y1933380D01*
X2815876D01*
X2814902Y1934102D01*
X2814414Y1934824D01*
G01X2808568Y1933380D02*
X2808081D01*
Y1934102D01*
X2808568Y1933380D01*
G01X2824159D02*
X2823184Y1934102D01*
X2822697Y1934824D01*
X2822210Y1936267D01*
Y1939154D01*
X2822697Y1940598D01*
X2823184Y1941320D01*
X2824159Y1942042D01*
X2825133Y1941320D01*
X2825620Y1940598D01*
X2826107Y1939154D01*
Y1936267D01*
X2825620Y1934824D01*
X2825133Y1934102D01*
X2824159Y1933380D01*
G01X2825720Y2059430D02*
G03Y2062580I0J1575D01*
G01X2821389D02*
G03Y2059430I0J-1575D01*
G01X2836311Y2049194D02*
G03I-3504J0D01*
G01X2821389Y2062580D02*
X2825720D01*
G01Y2059430D02*
X2821389D01*
G01X2812345Y2437400D02*
Y2418463D01*
G01X2878030Y260571D02*
G03X2878673Y263249I-5262J2680D01*
G01Y264037D02*
Y266399D01*
G01D02*
Y263249D01*
G01X2876704Y266399D02*
Y264037D01*
G01X2890484Y263249D02*
G03X2891126Y260571I5905J0D01*
G01X2895602Y266399D02*
G03I-984J0D01*
G01X2900326Y252619D02*
Y266399D01*
G01D02*
Y248682D01*
G01X2898358Y264037D02*
Y266399D01*
G01X2892452Y264037D02*
Y266399D01*
G01X2890484Y263249D02*
Y266399D01*
G01D02*
Y264037D01*
G01X2897177Y248682D02*
X2891126Y260571D01*
G01X2890484Y264037D02*
X2898358D01*
G01X3784185Y248682D02*
X2897177D01*
G01X2890484Y266399D02*
G03X2878673I-5906J0D01*
G01X2890484D02*
G03X2878673I-5906J0D01*
G01X2892452D02*
G03X2876704I-7874J0D01*
G01X2880543Y275093D02*
G03I-984J0D01*
G01X2894257Y271419D02*
G03I-984J0D01*
G01X2890582Y275093D02*
G03I-984J0D01*
G01X2916232Y440297D02*
G03I-3504J0D01*
G01X2924145Y426911D02*
G03Y430060I0J1574D01*
G01X2919814D02*
G03Y426911I1J-1575D01*
G01Y430060D02*
X2924145D01*
G01Y426911D02*
X2919814D01*
G01X2924145Y600139D02*
G03Y603289I0J1575D01*
G01X2919814D02*
G03Y600139I0J-1575D01*
G01X2916232Y589903D02*
G03I-3504J0D01*
G01X2919814Y603289D02*
X2924145D01*
G01Y600139D02*
X2919814D01*
G01X2924145Y832423D02*
G03Y835572I0J1575D01*
G01X2919814D02*
G03Y832423I1J-1574D01*
G01X2916232Y845808D02*
G03I-3504J0D01*
G01X2919814Y835572D02*
X2924145D01*
G01Y832423D02*
X2919814D01*
G01X2916232Y995415D02*
G03I-3504J0D01*
G01X2924145Y1005651D02*
G03Y1008801I0J1575D01*
G01X2919814D02*
G03Y1005651I0J-1575D01*
G01Y1008801D02*
X2924145D01*
G01Y1005651D02*
X2919814D01*
G01X2916232Y1251320D02*
G03I-3504J0D01*
G01X2924145Y1237934D02*
G03Y1241084I0J1575D01*
G01X2919814D02*
G03Y1237934I0J-1575D01*
G01Y1241084D02*
X2924145D01*
G01Y1237934D02*
X2919814D01*
G01X2916232Y1400927D02*
G03I-3504J0D01*
G01X2924145Y1411163D02*
G03Y1414312I0J1575D01*
G01X2919814D02*
G03Y1411163I1J-1575D01*
G01Y1414312D02*
X2924145D01*
G01Y1411163D02*
X2919814D01*
G01X2924145Y1643446D02*
G03Y1646596I0J1575D01*
G01X2919814D02*
G03Y1643446I0J-1575D01*
G01Y1646596D02*
X2924145D01*
G01Y1643446D02*
X2919814D01*
G01X2916232Y1656832D02*
G03I-3504J0D01*
G01X2924145Y1816675D02*
G03Y1819824I0J1574D01*
G01X2919814D02*
G03Y1816675I1J-1575D01*
G01X2916232Y1806438D02*
G03I-3504J0D01*
G01X2919814Y1819824D02*
X2924145D01*
G01Y1816675D02*
X2919814D01*
G01X2924145Y2048958D02*
G03Y2052108I0J1575D01*
G01X2919814D02*
G03Y2048958I0J-1575D01*
G01X2916232Y2062344D02*
G03I-3504J0D01*
G01X2919814Y2052108D02*
X2924145D01*
G01Y2048958D02*
X2919814D01*
G01X2916232Y2211950D02*
G03I-3504J0D01*
G01X2924145Y2222186D02*
G03Y2225336I0J1575D01*
G01X2919814D02*
G03Y2222186I0J-1575D01*
G01Y2225336D02*
X2924145D01*
G01Y2222186D02*
X2919814D01*
G01X2901118Y2353126D02*
X3938520D01*
G01X2901118Y2344622D02*
X3938520D01*
G01X2905055Y2353126D02*
Y2344622D01*
G01X2901118D02*
Y2353126D01*
G01X3032216Y528210D02*
G03X3020405I-5906J0D01*
G01X3032216D02*
G03X3020405I-5906J0D01*
G01X3034185D02*
G03X3018437I-7874J0D01*
G01X3040090D02*
G03X3012531I-13780J0D01*
G01X3042059D02*
G03X3010563I-15748J0D01*
G01X3042059D02*
G03X3010563I-15748J0D01*
G01X3019280Y521319D02*
G03X3033341I7031J-6888D01*
G01X3010563Y514430D02*
G03X3042059I15748J1D01*
G01X3010563D02*
G03X3042059I15748J1D01*
G01X3017255Y528210D02*
G03I-984J0D01*
G01X3018600Y533230D02*
G03I-984J0D01*
G01X3019280Y521319D02*
G03X3020405Y524074I-2812J2755D01*
G01Y525848D02*
Y528210D01*
G01D02*
Y524074D01*
G01X3018437Y528210D02*
Y525848D01*
G01X3012531Y528210D02*
Y525848D01*
G01X3010563Y514430D02*
Y528210D01*
G01Y514430D02*
Y528210D01*
G01X3012531Y525848D02*
X3020405D01*
G01X3022275Y536904D02*
G03I-984J0D01*
G01X3019282Y926823D02*
G03X3033339I7028J-6890D01*
G01X3010563Y919933D02*
G03X3042059I15748J0D01*
G01X3010563D02*
G03X3042059I15748J0D01*
G01X3010563D02*
G03X3042059I15748J0D01*
G01X3010563D02*
Y933712D01*
G01Y919933D02*
Y933712D01*
G01Y919933D02*
Y933712D01*
G01X3032214D02*
G03X3020407I-5904J0D01*
G01X3032216D02*
G03X3020405I-5906J0D01*
G01X3034185D02*
G03X3018437I-7874J0D01*
G01X3040090D02*
G03X3012531I-13780J0D01*
G01X3042059D02*
G03X3010563I-15748J0D01*
G01X3042059D02*
G03X3010563I-15748J0D01*
G01X3042059D02*
G03X3010563I-15748J0D01*
G01X3017255D02*
G03I-984J0D01*
G01X3022275Y942406D02*
G03I-984J0D01*
G01X3018600Y938732D02*
G03I-984J0D01*
G01X3019282Y926823D02*
G03X3020407Y929578I-2812J2755D01*
G01Y933712D02*
Y929578D01*
G01X3020405Y931350D02*
Y933712D01*
G01X3018437D02*
Y931350D01*
G01X3012531Y933712D02*
Y931350D01*
G01D02*
X3020405D01*
G01X3019282Y1330366D02*
G03X3033339I7028J-6890D01*
G01X3010563Y1323476D02*
G03X3042059I15748J0D01*
G01X3010563D02*
G03X3042059I15748J0D01*
G01X3010563D02*
G03X3042059I15748J0D01*
G01X3019282Y1330366D02*
G03X3020407Y1333122I-2812J2755D01*
G01Y1337255D02*
Y1333122D01*
G01X3010563Y1323476D02*
Y1337255D01*
G01Y1323476D02*
Y1337255D01*
G01Y1323476D02*
Y1337255D01*
G01X3032214D02*
G03X3020407I-5904J0D01*
G01X3032216D02*
G03X3020405I-5906J0D01*
G01X3034185D02*
G03X3018437I-7874J0D01*
G01X3040090D02*
G03X3012531I-13780J0D01*
G01X3042059D02*
G03X3010563I-15748J0D01*
G01X3042059D02*
G03X3010563I-15748J0D01*
G01X3042059D02*
G03X3010563I-15748J0D01*
G01X3017255D02*
G03I-984J0D01*
G01X3022275Y1345950D02*
G03I-984J0D01*
G01X3018600Y1342275D02*
G03I-984J0D01*
G01X3012531Y1334893D02*
X3020405D01*
G01D02*
Y1337255D01*
G01X3018437D02*
Y1334893D01*
G01X3012531Y1337255D02*
Y1334893D01*
G01X3027393Y1738840D02*
G03I-6988J0D01*
G01X3036153D02*
G03I-15748J0D01*
G01X3019282Y2145326D02*
G03X3033339I7028J-6890D01*
G01X3010563Y2138437D02*
G03X3042059I15748J0D01*
G01X3010563D02*
G03X3042059I15748J0D01*
G01X3010563D02*
G03X3042059I15748J0D01*
G01X3032214Y2152216D02*
G03X3020407I-5904J0D01*
G01X3032216D02*
G03X3020405I-5906J0D01*
G01X3034185D02*
G03X3018437I-7874J0D01*
G01X3040090D02*
G03X3012531I-13780J0D01*
G01X3042059D02*
G03X3010563I-15748J0D01*
G01X3042059D02*
G03X3010563I-15748J0D01*
G01X3042059D02*
G03X3010563I-15748J0D01*
G01X3017255D02*
G03I-984J0D01*
G01X3018600Y2157236D02*
G03I-984J0D01*
G01X3019282Y2145326D02*
G03X3020407Y2148082I-2812J2756D01*
G01X3012531Y2149854D02*
X3020405D01*
G01X3020407Y2152216D02*
Y2148082D01*
G01X3020405Y2149854D02*
Y2152216D01*
G01X3018437D02*
Y2149854D01*
G01X3012531Y2152216D02*
Y2149854D01*
G01X3010563Y2138437D02*
Y2152216D01*
G01Y2138437D02*
Y2152216D01*
G01Y2138437D02*
Y2152216D01*
G01X3022275Y2160910D02*
G03I-984J0D01*
G01X3032014Y-172119D02*
Y-191056D01*
G01X3035989Y533230D02*
G03I-984J0D01*
G01X3037334Y528210D02*
G03I-984J0D01*
G01X3032216Y524074D02*
G03X3033341Y521319I3937J0D01*
G01X3042059Y514430D02*
Y528210D01*
G01Y514430D02*
Y528210D01*
G01X3040090Y525848D02*
Y528210D01*
G01X3034185Y525848D02*
Y528210D01*
G01X3032216Y524074D02*
Y528210D01*
G01D02*
Y525848D01*
G01D02*
X3040090D01*
G01X3032314Y536904D02*
G03I-984J0D01*
G01X3042059Y919933D02*
Y933712D01*
G01Y919933D02*
Y933712D01*
G01Y919933D02*
Y933712D01*
G01X3035989Y938732D02*
G03I-984J0D01*
G01X3032314Y942406D02*
G03I-984J0D01*
G01X3037334Y933712D02*
G03I-984J0D01*
G01X3032214Y929578D02*
G03X3033339Y926823I3937J0D01*
G01X3040090Y931350D02*
Y933712D01*
G01X3034185Y931350D02*
Y933712D01*
G01X3032216D02*
Y931350D01*
G01X3032214Y929578D02*
Y933712D01*
G01X3032216Y931350D02*
X3040090D01*
G01X3032214Y1333122D02*
G03X3033339Y1330366I3937J-1D01*
G01X3042059Y1323476D02*
Y1337255D01*
G01Y1323476D02*
Y1337255D01*
G01Y1323476D02*
Y1337255D01*
G01X3032214Y1333122D02*
Y1337255D01*
G01X3035989Y1342275D02*
G03I-984J0D01*
G01X3032314Y1345950D02*
G03I-984J0D01*
G01X3037334Y1337255D02*
G03I-984J0D01*
G01X3032216Y1334893D02*
X3040090D01*
G01D02*
Y1337255D01*
G01X3034185Y1334893D02*
Y1337255D01*
G01X3032216D02*
Y1334893D01*
G01X3035989Y2157236D02*
G03I-984J0D01*
G01X3037334Y2152216D02*
G03I-984J0D01*
G01X3032214Y2148082D02*
G03X3033339Y2145326I3937J0D01*
G01X3032216Y2149854D02*
X3040090D01*
G01X3042059Y2138437D02*
Y2152216D01*
G01Y2138437D02*
Y2152216D01*
G01Y2138437D02*
Y2152216D01*
G01X3040090Y2149854D02*
Y2152216D01*
G01X3034185Y2149854D02*
Y2152216D01*
G01X3032216D02*
Y2149854D01*
G01X3032214Y2148082D02*
Y2152216D01*
G01X3032314Y2160910D02*
G03I-984J0D01*
G01X3032014Y2437400D02*
Y2418463D01*
G01X3172454Y-159506D02*
Y96400D01*
G01Y-159506D02*
X4117336D01*
G01Y-99242D02*
X3172454D01*
G01Y-54116D02*
X3703681D01*
G01X3172454Y36136D02*
X4117336D01*
G01X3172454Y-8990D02*
X4117336D01*
G01X3172454Y96400D02*
X4117336D01*
G01X3251683Y-172119D02*
Y-191056D01*
G01X3257291Y205584D02*
X3256317Y204140D01*
X3255343Y203418D01*
X3254368Y204140D01*
X3253394Y205584D01*
Y207027D01*
X3254368Y208471D01*
X3255343Y209193D01*
X3256317Y208471D01*
X3257291Y207027D01*
Y205584D01*
G01X3272882D02*
X3271908Y204140D01*
X3270933Y203418D01*
X3269959Y204140D01*
X3268984Y205584D01*
Y207027D01*
X3269959Y208471D01*
X3270933Y209193D01*
X3271908Y208471D01*
X3272882Y207027D01*
G01Y212080D02*
Y203418D01*
G01X3263138D02*
Y212080D01*
G01X3249496Y210636D02*
X3249009Y211358D01*
X3248034Y212080D01*
X3247060D01*
X3246086Y211358D01*
X3245598Y210636D01*
Y209914D01*
X3246086Y209193D01*
G01X3249009Y207027D02*
X3249496Y206305D01*
Y204862D01*
X3249009Y204140D01*
X3248034Y203418D01*
X3247060D01*
X3246086Y204140D01*
G01D02*
X3245111Y205584D01*
G01X3246086Y209193D02*
X3249009Y207027D01*
G01X3280190Y204862D02*
X3279703Y204140D01*
X3278728Y203418D01*
X3277754Y204140D01*
X3276780Y205584D01*
Y207027D01*
X3277754Y208471D01*
X3278728Y209193D01*
X3279703Y208471D01*
X3280190Y207027D01*
X3276780D01*
G01X3285062Y207749D02*
X3286036Y209193D01*
X3287011D01*
X3287498Y208471D01*
G01X3309910Y209193D02*
Y203418D01*
G01Y212080D02*
Y211358D01*
G01X3285062Y203418D02*
Y209193D01*
G01X3304063Y210636D02*
X3303576Y211358D01*
X3302601Y212080D01*
X3301627D01*
X3300653Y211358D01*
X3300165Y210636D01*
Y209914D01*
X3300653Y209193D01*
G01X3303576Y207027D02*
X3304063Y206305D01*
Y204862D01*
X3303576Y204140D01*
X3302601Y203418D01*
X3301627D01*
X3300653Y204140D01*
G01D02*
X3299678Y205584D01*
G01X3300653Y209193D02*
X3303576Y207027D01*
G01X3251683Y2437400D02*
Y2418463D01*
G01X3361430Y-99242D02*
Y96280D01*
G01X3326962Y204862D02*
X3326475Y204140D01*
X3325500Y203418D01*
X3324526Y204140D01*
X3323551Y205584D01*
Y207027D01*
X3324526Y208471D01*
X3325500Y209193D01*
X3326475Y208471D01*
X3326962Y207027D01*
X3323551D01*
G01X3319654Y205584D02*
X3318679Y204140D01*
X3317705Y203418D01*
X3316730Y204140D01*
X3315756Y205584D01*
Y207027D01*
X3316730Y208471D01*
X3317705Y209193D01*
X3318679Y208471D01*
X3319654Y207027D01*
G01Y212080D02*
Y203418D01*
G01X3471352Y-172119D02*
Y-191056D01*
G01Y2437400D02*
Y2418463D01*
G01X3644420Y255290D02*
X3688232Y218927D01*
G01X3640483Y268367D02*
Y248682D01*
G01X3644420D02*
Y268367D01*
G01D02*
X3640483D01*
G01X3652492Y426911D02*
G03Y430060I0J1574D01*
G01X3648161D02*
G03Y426911I0J-1575D01*
G01X3644578Y440297D02*
G03I-3504J0D01*
G01X3648161Y430060D02*
X3652492D01*
G01Y426911D02*
X3648161D01*
G01X3652492Y600139D02*
G03Y603289I0J1575D01*
G01X3648161D02*
G03Y600139I0J-1575D01*
G01X3644578Y589903D02*
G03I-3504J0D01*
G01X3648161Y603289D02*
X3652492D01*
G01Y600139D02*
X3648161D01*
G01X3652492Y832423D02*
G03Y835572I0J1575D01*
G01X3648161D02*
G03Y832423I0J-1574D01*
G01X3644578Y845808D02*
G03I-3504J0D01*
G01X3648161Y835572D02*
X3652492D01*
G01Y832423D02*
X3648161D01*
G01X3644578Y995415D02*
G03I-3504J0D01*
G01X3652492Y1005651D02*
G03Y1008801I0J1575D01*
G01X3648161D02*
G03Y1005651I0J-1575D01*
G01Y1008801D02*
X3652492D01*
G01Y1005651D02*
X3648161D01*
G01X3644578Y1251320D02*
G03I-3504J0D01*
G01X3652492Y1237934D02*
G03Y1241084I0J1575D01*
G01X3648161D02*
G03Y1237934I0J-1575D01*
G01Y1241084D02*
X3652492D01*
G01Y1237934D02*
X3648161D01*
G01X3644578Y1400927D02*
G03I-3504J0D01*
G01X3652492Y1411163D02*
G03Y1414312I0J1575D01*
G01X3648161D02*
G03Y1411163I0J-1575D01*
G01Y1414312D02*
X3652492D01*
G01Y1411163D02*
X3648161D01*
G01X3652492Y1643446D02*
G03Y1646596I0J1575D01*
G01X3648161D02*
G03Y1643446I0J-1575D01*
G01Y1646596D02*
X3652492D01*
G01Y1643446D02*
X3648161D01*
G01X3644578Y1656832D02*
G03I-3504J0D01*
G01X3652492Y1816675D02*
G03Y1819824I0J1574D01*
G01X3648161D02*
G03Y1816675I0J-1575D01*
G01X3644578Y1806438D02*
G03I-3504J0D01*
G01X3648161Y1819824D02*
X3652492D01*
G01Y1816675D02*
X3648161D01*
G01X3652492Y2048958D02*
G03Y2052108I0J1575D01*
G01X3648161D02*
G03Y2048958I0J-1575D01*
G01X3644578Y2062344D02*
G03I-3504J0D01*
G01X3648161Y2052108D02*
X3652492D01*
G01Y2048958D02*
X3648161D01*
G01X3670371Y2092291D02*
X3669396Y2093013D01*
X3668909Y2093734D01*
Y2094456D01*
X3669396Y2095178D01*
X3670371Y2095900D01*
X3671345D01*
X3672320Y2095178D01*
X3672807Y2094456D01*
Y2093734D01*
X3672320Y2093013D01*
X3671345Y2092291D01*
G01X3670371Y2087238D02*
X3669396Y2087960D01*
G01X3661114Y2091569D02*
X3665011D01*
G01X3672320D02*
X3673294Y2090125D01*
Y2089403D01*
G01X3669396Y2087960D02*
X3668422Y2089403D01*
Y2090125D01*
G01X3661601Y2093734D02*
X3664524Y2089403D01*
G01X3663063Y2094456D02*
Y2088682D01*
G01X3655267Y2095900D02*
Y2087238D01*
G01X3647472Y2095900D02*
Y2087238D01*
G01X3673294Y2089403D02*
X3672320Y2087960D01*
X3671345Y2087238D01*
X3670371D01*
G01X3668422Y2090125D02*
X3669396Y2091569D01*
X3670371Y2092291D01*
X3671345D01*
X3672320Y2091569D01*
G01X3661601Y2089403D02*
X3664524Y2093734D01*
G01X3748752Y2085073D02*
X3643574D01*
G01X3644578Y2211950D02*
G03I-3504J0D01*
G01X3652492Y2222186D02*
G03Y2225336I0J1575D01*
G01X3648161D02*
G03Y2222186I0J-1575D01*
G01Y2225336D02*
X3652492D01*
G01Y2222186D02*
X3648161D01*
G01X3640483Y2221123D02*
Y2240808D01*
G01X3644420D02*
Y2221123D01*
G01D02*
X3640483D01*
G01X3644420Y2237814D02*
X3666502Y2265908D01*
G01D02*
X3678313D01*
G01X3691021Y-172119D02*
Y-191056D01*
G01X3700013Y-8797D02*
Y-98927D01*
G01X3703681Y-54116D02*
X4117336D01*
G01X3709787Y220371D02*
X3711736Y215319D01*
X3711249Y213153D01*
X3710274Y211710D01*
X3709300D01*
G01X3701505Y214597D02*
Y223258D01*
X3703941Y216040D01*
X3706377Y223258D01*
Y214597D01*
G01X3719531D02*
Y223258D01*
G01X3729276Y220371D02*
Y214597D01*
G01X3733660D02*
Y220371D01*
G01X3748764Y214597D02*
Y223258D01*
X3751200D01*
X3752174Y222536D01*
X3752661Y221815D01*
Y220371D01*
X3752174Y219649D01*
X3751200Y218927D01*
X3748764D01*
G01X3711736Y215319D02*
X3713685Y220371D01*
G01X3729276Y216762D02*
X3728301Y215319D01*
X3727327Y214597D01*
X3726352Y215319D01*
X3725378Y216762D01*
Y218206D01*
X3726352Y219649D01*
X3727327Y220371D01*
X3728301Y219649D01*
X3729276Y218206D01*
G01X3733660Y218927D02*
X3734635Y220371D01*
X3735609D01*
X3736096Y219649D01*
G01X3688232Y218927D02*
X3700043D01*
G01X3736940Y253909D02*
X3766327Y239333D01*
G01X3733003Y248682D02*
Y268367D01*
G01X3736940D02*
Y248682D01*
G01X3733003Y268367D02*
X3736940D01*
G01X3733003Y398279D02*
G03X3764500I15749J0D01*
G01X3733003D02*
G03X3764500I15749J0D01*
G01X3733003D02*
G03X3764500I15749J0D01*
G01X3741723Y405169D02*
G03X3755780I7028J-6890D01*
G01X3739696Y412059D02*
G03I-984J0D01*
G01X3741723Y405169D02*
G03X3742848Y407925I-2812J2755D01*
G01Y412059D02*
Y407925D01*
G01X3742846Y409696D02*
Y412059D01*
G01X3740878D02*
Y409696D01*
G01X3734972Y412059D02*
Y409696D01*
G01X3733003Y398279D02*
Y412059D01*
G01Y398279D02*
Y412059D01*
G01Y398279D02*
Y412059D01*
G01X3734972Y409696D02*
X3742846D01*
G01X3754655Y412059D02*
G03X3742848I-5904J0D01*
G01X3754657D02*
G03X3742846I-5906J0D01*
G01X3756626D02*
G03X3740878I-7874J0D01*
G01X3762531D02*
G03X3734972I-13779J0D01*
G01X3764500D02*
G03X3733003I-15749J0D01*
G01X3764500D02*
G03X3733003I-15749J0D01*
G01X3764500D02*
G03X3733003I-15749J0D01*
G01X3744716Y420753D02*
G03I-984J0D01*
G01X3741041Y417078D02*
G03I-984J0D01*
G01X3741723Y928791D02*
G03X3755780I7028J-6890D01*
G01X3733003Y921901D02*
G03X3764500I15749J0D01*
G01X3733003D02*
G03X3764500I15749J0D01*
G01X3733003D02*
G03X3764500I15749J0D01*
G01X3754655Y935681D02*
G03X3742848I-5904J0D01*
G01X3754657D02*
G03X3742846I-5906J0D01*
G01X3756626D02*
G03X3740878I-7874J0D01*
G01X3762531D02*
G03X3734972I-13779J0D01*
G01X3764500D02*
G03X3733003I-15749J0D01*
G01X3764500D02*
G03X3733003I-15749J0D01*
G01X3764500D02*
G03X3733003I-15749J0D01*
G01X3739696D02*
G03I-984J0D01*
G01X3744716Y944375D02*
G03I-984J0D01*
G01X3741041Y940700D02*
G03I-984J0D01*
G01X3741723Y928791D02*
G03X3742848Y931547I-2812J2755D01*
G01Y935681D02*
Y931547D01*
G01X3742846Y933318D02*
Y935681D01*
G01X3740878D02*
Y933318D01*
G01X3734972Y935681D02*
Y933318D01*
G01X3733003Y921901D02*
Y935681D01*
G01Y921901D02*
Y935681D01*
G01Y921901D02*
Y935681D01*
G01X3734972Y933318D02*
X3742846D01*
G01X3754655Y1331350D02*
G03X3742848I-5904J0D01*
G01X3754657D02*
G03X3742846I-5906J0D01*
G01X3756626D02*
G03X3740878I-7874J0D01*
G01X3762531D02*
G03X3734972I-13779J0D01*
G01X3764500D02*
G03X3733003I-15749J0D01*
G01X3764500D02*
G03X3733003I-15749J0D01*
G01X3764500D02*
G03X3733003I-15749J0D01*
G01X3741723Y1324460D02*
G03X3755780I7028J-6890D01*
G01X3733003Y1317570D02*
G03X3764500I15749J0D01*
G01X3733003D02*
G03X3764500I15749J0D01*
G01X3733003D02*
G03X3764500I15749J0D01*
G01X3739696Y1331350D02*
G03I-984J0D01*
G01X3741723Y1324460D02*
G03X3742848Y1327216I-2812J2756D01*
G01Y1331350D02*
Y1327216D01*
G01X3742846Y1328988D02*
Y1331350D01*
G01X3740878D02*
Y1328988D01*
G01X3734972Y1331350D02*
Y1328988D01*
G01X3733003Y1317570D02*
Y1331350D01*
G01Y1317570D02*
Y1331350D01*
G01Y1317570D02*
Y1331350D01*
G01X3734972Y1328988D02*
X3742846D01*
G01X3744716Y1340044D02*
G03I-984J0D01*
G01X3741041Y1336370D02*
G03I-984J0D01*
G01X3744401Y1864765D02*
G03Y1860553I0J-2106D01*
G01Y1864765D02*
X3771980D01*
G01Y1860553D02*
X3744401D01*
G01X3733003Y2134500D02*
Y2081136D01*
G01X3678653Y2087238D02*
X3678166D01*
Y2087960D01*
X3678653Y2087238D01*
G01X3741723Y2145326D02*
G03X3755780I7028J-6890D01*
G01X3733003Y2138437D02*
G03X3764500I15749J0D01*
G01X3733003D02*
G03X3764500I15749J0D01*
G01X3733003D02*
G03X3764500I15749J0D01*
G01X3694244Y2087238D02*
X3693269Y2087960D01*
X3692782Y2088682D01*
X3692295Y2090125D01*
Y2093013D01*
X3692782Y2094456D01*
X3693269Y2095178D01*
X3694244Y2095900D01*
X3695218Y2095178D01*
X3695705Y2094456D01*
X3696193Y2093013D01*
Y2090125D01*
X3695705Y2088682D01*
X3695218Y2087960D01*
X3694244Y2087238D01*
G01X3686448D02*
X3685474Y2087960D01*
X3684987Y2088682D01*
X3684499Y2090125D01*
Y2093013D01*
X3684987Y2094456D01*
X3685474Y2095178D01*
X3686448Y2095900D01*
X3687423Y2095178D01*
X3687910Y2094456D01*
X3688397Y2093013D01*
Y2090125D01*
X3687910Y2088682D01*
X3687423Y2087960D01*
X3686448Y2087238D01*
G01X3689055Y2118751D02*
Y2145326D01*
G01Y2138437D02*
Y2118751D01*
G01X3733003Y2085073D02*
X3748752D01*
G01X3764500D02*
X3748752D01*
G01X3754655Y2152216D02*
G03X3742848I-5904J0D01*
G01X3754657D02*
G03X3742846I-5906J0D01*
G01X3756626D02*
G03X3740878I-7874J0D01*
G01X3762531D02*
G03X3734972I-13779J0D01*
G01X3764500D02*
G03X3733003I-15749J0D01*
G01X3764500D02*
G03X3733003I-15749J0D01*
G01X3764500D02*
G03X3733003I-15749J0D01*
G01X3739696D02*
G03I-984J0D01*
G01X3741041Y2157236D02*
G03I-984J0D01*
G01X3741723Y2145326D02*
G03X3742848Y2148082I-2812J2756D01*
G01X3734972Y2149854D02*
X3742846D01*
G01X3742848Y2152216D02*
Y2148082D01*
G01X3742846Y2149854D02*
Y2152216D01*
G01X3740878D02*
Y2149854D01*
G01X3734972Y2152216D02*
Y2149854D01*
G01X3733003Y2138437D02*
Y2152216D01*
G01Y2138437D02*
Y2152216D01*
G01Y2138437D02*
Y2152216D01*
G01X3689055Y2225062D02*
Y2145326D01*
G01Y2152216D02*
Y2225062D01*
G01X3744814Y2152216D02*
X3685118D01*
G01X3744814Y2138437D02*
X3685118D01*
G01X3684725Y2188521D02*
X3680394Y2191445D01*
G01X3679672Y2189983D02*
X3685446D01*
G01X3678229Y2182188D02*
X3686890D01*
G01X3678229Y2174393D02*
X3686890D01*
G01X3678950Y2196317D02*
X3678229Y2197291D01*
Y2198266D01*
X3678950Y2199240D01*
X3679672Y2199727D01*
X3680394D01*
X3681116Y2199240D01*
X3681837Y2198266D01*
X3682559Y2199240D01*
G01X3681837Y2197291D02*
Y2198266D01*
G01X3680394Y2188521D02*
X3684725Y2191445D01*
G01X3678229Y2215318D02*
Y2212395D01*
X3681837Y2211907D01*
X3681116Y2212882D01*
Y2213856D01*
X3681837Y2214831D01*
X3682559Y2215318D01*
X3684003Y2215805D01*
X3685446Y2215318D01*
X3686168Y2214831D01*
X3686890Y2213856D01*
Y2212882D01*
X3686168Y2211907D01*
X3685446Y2211420D01*
G01X3686890Y2221164D02*
X3686168Y2220190D01*
X3685446Y2219703D01*
X3684003Y2219215D01*
X3681116D01*
X3679672Y2219703D01*
X3678950Y2220190D01*
X3678229Y2221164D01*
X3678950Y2222139D01*
X3679672Y2222626D01*
X3681116Y2223113D01*
X3684003D01*
X3685446Y2222626D01*
X3686168Y2222139D01*
X3686890Y2221164D01*
G01X3744716Y2160910D02*
G03I-984J0D01*
G01X3684725Y2200214D02*
X3686168Y2199240D01*
X3686890Y2198266D01*
Y2197291D01*
X3686168Y2196317D01*
X3685446Y2195830D01*
G01X3686890Y2205574D02*
Y2205086D01*
X3686168D01*
X3686890Y2205574D01*
G01X3682559Y2188034D02*
Y2191932D01*
G01Y2199240D02*
X3684003Y2200214D01*
X3684725D01*
G01X3733003Y2221123D02*
X3736940D01*
G01X3733003Y2240808D02*
Y2221123D01*
G01X3736940D02*
Y2240808D01*
G01X3679775Y2261577D02*
Y2270238D01*
X3682211Y2263021D01*
X3684647Y2270238D01*
Y2261577D01*
G01X3747121Y2256051D02*
X3758932D01*
G01X3707546Y2263743D02*
X3706571Y2262299D01*
X3705597Y2261577D01*
X3704622Y2262299D01*
X3703648Y2263743D01*
Y2265186D01*
X3704622Y2266630D01*
X3705597Y2267351D01*
X3706571Y2266630D01*
X3707546Y2265186D01*
G01X3711931Y2265908D02*
X3712905Y2267351D01*
X3713879D01*
X3714366Y2266630D01*
G01X3738727Y2263743D02*
X3737752Y2262299D01*
X3736778Y2261577D01*
X3735804Y2262299D01*
X3734829Y2263743D01*
Y2265186D01*
X3735804Y2266630D01*
X3736778Y2267351D01*
X3737752Y2266630D01*
X3738727Y2265186D01*
Y2263743D01*
G01X3746035Y2263021D02*
X3745061Y2261577D01*
X3744086D01*
G01X3707546Y2267351D02*
Y2261577D01*
G01X3711931D02*
Y2267351D01*
G01X3727034Y2261577D02*
Y2270238D01*
X3729470D01*
X3730444Y2269517D01*
X3730931Y2268795D01*
Y2267351D01*
X3730444Y2266630D01*
X3729470Y2265908D01*
X3727034D01*
G01X3745548Y2266630D02*
X3745061Y2267351D01*
X3744086D01*
X3743599Y2266630D01*
Y2265908D01*
X3744573Y2265186D01*
X3745548Y2264464D01*
X3746035Y2263743D01*
Y2263021D01*
G01X3744086Y2261577D02*
X3743112Y2263021D01*
G01X3736940Y2231778D02*
X3747121Y2256051D01*
G01X3690006Y2262299D02*
X3691955Y2267351D01*
G01X3697802Y2261577D02*
Y2270238D01*
G01X3688057Y2267351D02*
X3690006Y2262299D01*
X3689519Y2260134D01*
X3688545Y2258690D01*
X3687570D01*
G01X3691021Y2437400D02*
Y2418463D01*
G01X3784185Y248682D02*
G03X3788122Y252619I0J3937D01*
G01Y1673564D02*
Y252619D01*
G01X3780432Y219649D02*
X3783355D01*
G01X3774098Y223258D02*
Y222536D01*
G01Y220371D02*
Y214597D01*
G01X3781894D02*
Y223258D01*
G01X3765816Y214597D02*
X3764841Y216040D01*
G01X3767278Y219649D02*
X3766790Y220371D01*
X3765816D01*
X3765329Y219649D01*
Y218927D01*
X3767278Y217484D01*
X3767765Y216762D01*
Y216040D01*
G01X3760457Y216762D02*
X3759482Y215319D01*
X3758508Y214597D01*
X3757533Y215319D01*
X3756559Y216762D01*
Y218206D01*
X3757533Y219649D01*
X3758508Y220371D01*
X3759482Y219649D01*
X3760457Y218206D01*
Y216762D01*
G01X3767765Y216040D02*
X3766790Y214597D01*
X3765816D01*
G01X3787882Y240777D02*
X3789831Y235725D01*
X3789344Y233559D01*
X3788369Y232116D01*
X3787395D01*
G01X3779600Y235003D02*
Y243664D01*
X3782035Y236446D01*
X3784472Y243664D01*
Y235003D01*
G01X3789689Y223258D02*
Y222536D01*
G01Y220371D02*
Y214597D01*
G01X3797626Y235003D02*
Y243664D01*
G01X3803818Y214597D02*
Y220371D01*
G01X3807370Y240777D02*
Y235003D01*
G01X3811755D02*
Y240777D01*
G01X3818921Y223258D02*
Y214597D01*
X3822819D01*
G01X3789831Y235725D02*
X3791780Y240777D01*
G01X3807370Y237168D02*
X3806396Y235725D01*
X3805421Y235003D01*
X3804447Y235725D01*
X3803472Y237168D01*
Y238612D01*
X3804447Y240055D01*
X3805421Y240777D01*
X3806396Y240055D01*
X3807370Y238612D01*
G01X3803818Y218927D02*
X3804792Y220371D01*
X3805767D01*
X3806741Y218927D01*
Y214597D01*
G01X3811755Y239333D02*
X3812729Y240777D01*
X3813704D01*
X3814191Y240055D01*
G01X3799433Y216762D02*
X3798459Y215319D01*
X3797484Y214597D01*
X3796510Y215319D01*
X3795535Y216762D01*
Y218206D01*
X3796510Y219649D01*
X3797484Y220371D01*
X3798459Y219649D01*
X3799433Y218206D01*
Y216762D01*
G01X3766327Y239333D02*
X3778138D01*
G01X3765996Y292698D02*
G03I-4292J0D01*
G01X3754655Y407925D02*
G03X3755780Y405169I3937J-1D01*
G01X3754657Y412059D02*
Y409696D01*
G01X3754655Y407925D02*
Y412059D01*
G01X3754657Y409696D02*
X3762531D01*
G01X3759775Y412059D02*
G03I-984J0D01*
G01X3764500Y398279D02*
Y412059D01*
G01Y398279D02*
Y412059D01*
G01Y398279D02*
Y412059D01*
G01X3762531Y409696D02*
Y412059D01*
G01X3756626Y409696D02*
Y412059D01*
G01X3754755Y420753D02*
G03I-984J0D01*
G01X3758430Y417078D02*
G03I-984J0D01*
G01X3754755Y944375D02*
G03I-984J0D01*
G01X3754655Y931547D02*
G03X3755780Y928791I3937J-1D01*
G01X3754657Y935681D02*
Y933318D01*
G01X3754655Y931547D02*
Y935681D01*
G01X3754657Y933318D02*
X3762531D01*
G01X3758430Y940700D02*
G03I-984J0D01*
G01X3759775Y935681D02*
G03I-984J0D01*
G01X3764500Y921901D02*
Y935681D01*
G01Y921901D02*
Y935681D01*
G01Y921901D02*
Y935681D01*
G01X3762531Y933318D02*
Y935681D01*
G01X3756626Y933318D02*
Y935681D01*
G01X3754655Y1327216D02*
G03X3755780Y1324460I3937J0D01*
G01X3754657Y1331350D02*
Y1328988D01*
G01X3754655Y1327216D02*
Y1331350D01*
G01X3754657Y1328988D02*
X3762531D01*
G01X3754755Y1340044D02*
G03I-984J0D01*
G01X3759775Y1331350D02*
G03I-984J0D01*
G01X3764500Y1317570D02*
Y1331350D01*
G01Y1317570D02*
Y1331350D01*
G01Y1317570D02*
Y1331350D01*
G01X3762531Y1328988D02*
Y1331350D01*
G01X3756626Y1328988D02*
Y1331350D01*
G01X3758430Y1336370D02*
G03I-984J0D01*
G01X3773948Y1682974D02*
G03X3779421Y1677501I5473J0D01*
G01X3781232Y1664706D02*
G03I-7284J0D01*
G01X3788122Y1673564D02*
X3784185Y1677501D01*
G01X3773948Y1682974D02*
Y1858584D01*
G01X3784185Y1677501D02*
X3779421D01*
G01X3773948Y1858584D02*
X3771980Y1860553D01*
G01X3773948Y1866734D02*
X3771980Y1864765D01*
G01X3773948Y1866734D02*
Y1924627D01*
G01X3779421Y1930100D02*
G03X3773948Y1924627I0J-5473D01*
G01X3781232Y1942895D02*
G03I-7284J0D01*
G01X3779421Y1930100D02*
X3784185D01*
G01X3788122Y2236871D02*
Y1934037D01*
G01D02*
X3784185Y1930100D01*
G01X3764500Y2134500D02*
Y2081136D01*
G01X3754655Y2148082D02*
G03X3755780Y2145326I3937J0D01*
G01X3754657Y2149854D02*
X3762531D01*
G01X3754657Y2152216D02*
Y2149854D01*
G01X3754655Y2148082D02*
Y2152216D01*
G01X3754527Y2153446D02*
X3879917Y2180150D01*
G01X3759775Y2152216D02*
G03I-984J0D01*
G01X3758430Y2157236D02*
G03I-984J0D01*
G01X3764500Y2138437D02*
Y2152216D01*
G01Y2138437D02*
Y2152216D01*
G01Y2138437D02*
Y2152216D01*
G01X3762531Y2149854D02*
Y2152216D01*
G01X3756626Y2149854D02*
Y2152216D01*
G01X3754755Y2160910D02*
G03I-984J0D01*
G01X3765523Y2199194D02*
G03I-4291J0D01*
G01X3820480Y2178561D02*
X3822284Y2170090D01*
G01X3788122Y2236871D02*
G03X3784185Y2240808I-3937J0D01*
G01X3752368Y2270238D02*
Y2269517D01*
G01Y2267351D02*
Y2261577D01*
G01X3782088Y2265908D02*
X3783063Y2267351D01*
X3784037D01*
X3785011Y2265908D01*
Y2261577D01*
G01X3823987Y2263021D02*
X3823500Y2262299D01*
X3822526Y2261577D01*
X3821552Y2262299D01*
X3820577Y2263743D01*
Y2265186D01*
X3821552Y2266630D01*
X3822526Y2267351D01*
X3823500Y2266630D01*
X3823987Y2265186D01*
X3820577D01*
G01X3788165Y2253885D02*
X3787190Y2252442D01*
X3786216Y2251720D01*
X3785241Y2252442D01*
X3784267Y2253885D01*
Y2255329D01*
X3785241Y2256772D01*
X3786216Y2257494D01*
X3787190Y2256772D01*
X3788165Y2255329D01*
G01X3792550Y2256051D02*
X3793524Y2257494D01*
X3794498D01*
X3794985Y2256772D01*
G01X3819346Y2253885D02*
X3818371Y2252442D01*
X3817397Y2251720D01*
X3816422Y2252442D01*
X3815448Y2253885D01*
Y2255329D01*
X3816422Y2256772D01*
X3817397Y2257494D01*
X3818371Y2256772D01*
X3819346Y2255329D01*
Y2253885D01*
G01X3813269Y2265908D02*
X3814244Y2267351D01*
X3815218D01*
X3816192Y2265908D01*
Y2261577D01*
G01X3778420Y2251720D02*
Y2260381D01*
G01X3782088Y2261577D02*
Y2267351D01*
G01X3788165Y2257494D02*
Y2251720D01*
G01X3792550D02*
Y2257494D01*
G01X3797191Y2270238D02*
Y2261577D01*
X3801089D01*
G01X3806935Y2270238D02*
Y2269517D01*
G01Y2267351D02*
Y2261577D01*
G01X3807653Y2251720D02*
Y2260381D01*
X3810089D01*
X3811063Y2259659D01*
X3811550Y2258938D01*
Y2257494D01*
X3811063Y2256772D01*
X3810089Y2256051D01*
X3807653D01*
G01X3813269Y2261577D02*
Y2267351D01*
G01X3777703Y2263743D02*
X3776729Y2262299D01*
X3775754Y2261577D01*
X3774780Y2262299D01*
X3773805Y2263743D01*
Y2265186D01*
X3774780Y2266630D01*
X3775754Y2267351D01*
X3776729Y2266630D01*
X3777703Y2265186D01*
Y2263743D01*
G01X3770625Y2252442D02*
X3772574Y2257494D01*
G01X3760164Y2261577D02*
Y2270238D01*
G01X3760394Y2251720D02*
Y2260381D01*
X3762830Y2253164D01*
X3765266Y2260381D01*
Y2251720D01*
G01X3767959Y2270238D02*
Y2269517D01*
G01Y2267351D02*
Y2261577D01*
G01X3768676Y2257494D02*
X3770625Y2252442D01*
X3770138Y2250277D01*
X3769164Y2248833D01*
X3768189D01*
G01X3758702Y2266630D02*
X3761626D01*
G01X3888989Y-8797D02*
Y-98927D01*
G01X3826859Y235003D02*
Y243664D01*
X3829294D01*
X3830269Y242942D01*
X3830756Y242221D01*
Y240777D01*
X3830269Y240055D01*
X3829294Y239333D01*
X3826859D01*
G01X3858527Y240055D02*
X3861450D01*
G01X3852193Y240777D02*
Y235003D01*
G01X3859988D02*
Y243664D01*
G01X3867784Y240777D02*
Y235003D01*
G01X3881913D02*
Y240777D01*
G01Y239333D02*
X3882887Y240777D01*
X3883861D01*
X3884836Y239333D01*
Y235003D01*
G01X3877528Y237168D02*
X3876554Y235725D01*
X3875579Y235003D01*
X3874605Y235725D01*
X3873630Y237168D01*
Y238612D01*
X3874605Y240055D01*
X3875579Y240777D01*
X3876554Y240055D01*
X3877528Y238612D01*
Y237168D01*
G01X3844885Y235003D02*
X3843911D01*
G01D02*
X3842936Y236446D01*
G01X3845372Y240055D02*
X3844885Y240777D01*
X3843911D01*
X3843423Y240055D01*
Y239333D01*
X3844398Y238612D01*
X3845372Y237890D01*
X3845859Y237168D01*
Y236446D01*
X3844885Y235003D01*
G01X3828665Y223258D02*
Y222536D01*
G01Y220371D02*
Y214597D01*
G01X3834999D02*
Y220371D01*
G01X3838552Y237168D02*
X3837577Y235725D01*
X3836603Y235003D01*
X3835628Y235725D01*
X3834654Y237168D01*
Y238612D01*
X3835628Y240055D01*
X3836603Y240777D01*
X3837577Y240055D01*
X3838552Y238612D01*
Y237168D01*
G01X3834999Y218927D02*
X3835974Y220371D01*
X3836948D01*
X3837922Y218927D01*
Y214597D01*
G01X3845718Y216040D02*
X3845230Y215319D01*
X3844256Y214597D01*
X3843281Y215319D01*
X3842307Y216762D01*
Y218206D01*
X3843281Y219649D01*
X3844256Y220371D01*
X3845230Y219649D01*
X3845718Y218206D01*
X3842307D01*
G01X3852193Y243664D02*
Y242942D01*
G01X3867784Y243664D02*
Y242942D01*
G01X3828104Y2180185D02*
X3829908Y2171714D01*
G01X3834750Y2179386D02*
X3838511Y2175760D01*
G01X3875654Y2181456D02*
X3874551Y2181959D01*
X3873924Y2182563D01*
X3873146Y2183874D01*
X3872545Y2186698D01*
X3872721Y2188211D01*
X3873047Y2189019D01*
X3873850Y2189927D01*
X3874953Y2189424D01*
X3875580Y2188820D01*
X3876357Y2187509D01*
X3876959Y2184686D01*
X3876783Y2183172D01*
X3876457Y2182365D01*
X3875654Y2181456D01*
G01X3844731Y2179298D02*
X3847063Y2175367D01*
G01X3850977Y2185056D02*
X3852781Y2176585D01*
G01X3868132Y2188710D02*
X3865272Y2188101D01*
X3865548Y2184469D01*
X3866350Y2185378D01*
X3867303Y2185581D01*
X3868407Y2185078D01*
X3869034Y2184474D01*
X3869811Y2183163D01*
X3869635Y2181650D01*
X3869309Y2180843D01*
X3868506Y2179934D01*
X3867553Y2179731D01*
X3866450Y2180234D01*
X3865823Y2180838D01*
G01X3834724Y2177167D02*
X3838536Y2177979D01*
G01X3860405Y2178209D02*
X3859929Y2178107D01*
X3859779Y2178813D01*
X3860405Y2178209D01*
G01X3843251Y2174555D02*
X3841447Y2183027D01*
X3843829Y2183534D01*
X3844933Y2183031D01*
X3845560Y2182427D01*
X3845860Y2181015D01*
X3845534Y2180207D01*
X3844731Y2179298D01*
X3842349Y2178791D01*
G01X3836029Y2180397D02*
X3837232Y2174749D01*
G01X3835652Y2175151D02*
X3837609Y2179995D01*
G01X3826654Y2253164D02*
X3825679Y2251720D01*
X3824705D01*
X3824218Y2252442D01*
X3823730Y2253164D01*
G01X3826166Y2256772D02*
X3825679Y2257494D01*
X3824705D01*
X3824218Y2256772D01*
Y2256051D01*
X3825192Y2255329D01*
X3826166Y2254607D01*
X3826654Y2253885D01*
Y2253164D01*
G01X3858322Y2253885D02*
X3857348Y2252442D01*
X3856373Y2251720D01*
X3855399Y2252442D01*
X3854424Y2253885D01*
Y2255329D01*
X3855399Y2256772D01*
X3856373Y2257494D01*
X3857348Y2256772D01*
X3858322Y2255329D01*
Y2253885D01*
G01X3862707Y2256051D02*
X3863681Y2257494D01*
X3864656D01*
X3865630Y2256051D01*
Y2251720D01*
G01X3893888Y2256051D02*
X3894862Y2257494D01*
X3895837D01*
X3896811Y2256051D01*
Y2251720D01*
G01X3848578Y2260381D02*
Y2259659D01*
G01Y2257494D02*
Y2251720D01*
G01X3862707D02*
Y2257494D01*
G01X3877810Y2260381D02*
Y2251720D01*
X3881708D01*
G01X3887554Y2260381D02*
Y2259659D01*
G01Y2257494D02*
Y2251720D01*
G01X3893888D02*
Y2257494D01*
G01X3832987Y2260381D02*
Y2259659D01*
G01Y2257494D02*
Y2251720D01*
G01X3840783D02*
Y2260381D01*
G01X3839321Y2256772D02*
X3842244D01*
G01X3910690Y-172119D02*
Y-191056D01*
G01X3897016Y243664D02*
Y235003D01*
X3900914D01*
G01X3923812Y236446D02*
X3923325Y235725D01*
X3922351Y235003D01*
X3921376Y235725D01*
X3920402Y237168D01*
Y238612D01*
X3921376Y240055D01*
X3922351Y240777D01*
X3923325Y240055D01*
X3923812Y238612D01*
X3920402D01*
G01X3906760Y240777D02*
Y235003D01*
G01X3913094D02*
Y240777D01*
G01Y239333D02*
X3914068Y240777D01*
X3915042D01*
X3916017Y239333D01*
Y235003D01*
G01X3906760Y243664D02*
Y242942D01*
G01X3904607Y2253164D02*
X3904119Y2252442D01*
X3903145Y2251720D01*
X3902170Y2252442D01*
X3901196Y2253885D01*
Y2255329D01*
X3902170Y2256772D01*
X3903145Y2257494D01*
X3904119Y2256772D01*
X3904607Y2255329D01*
X3901196D01*
G01X3938520Y2353126D02*
Y2344622D01*
G01X3934583D02*
Y2353126D01*
G01X3910690Y2437400D02*
Y2418463D01*
G01X4149296Y2437400D02*
Y-191056D01*
G01X4130359Y2418463D02*
Y-172119D01*
G01X4117336Y-159506D02*
Y96280D01*
G01X4130359Y43763D02*
X4149296D01*
G01X4130359Y259644D02*
X4149296D01*
G01X4130360Y404330D02*
Y259644D01*
G01X4130359Y475526D02*
X4149296D01*
G01X4130359Y691409D02*
X4149296D01*
G01X4130359Y907291D02*
X4149296D01*
G01X4130359Y1123172D02*
X4149296D01*
G01X4130359Y1339055D02*
X4149296D01*
G01X4130359Y1554935D02*
X4149296D01*
G01X4130359Y1770818D02*
X4149296D01*
G01X4130359Y1986700D02*
X4149296D01*
G01X4130170Y2202582D02*
X4149107D01*
G01X4130359Y2418463D02*
Y2323976D01*
M02*
